G04 ================== begin FILE IDENTIFICATION RECORD ==================*
G04 Layout Name:  E:/<user>/9332_F0TG_MB_C/brd/0417/9332_F0TG_MB_C_V02_0417_0820.brd*
G04 Film Name:    sst*
G04 File Format:  Gerber RS274X*
G04 File Origin:  Cadence Allegro 17.2-S081*
G04 Origin Date:  Wed Apr 19 14:50:16 2023*
G04 *
G04 Layer:  DRAWING FORMAT/TITLE_BLOCK_A*
G04 Layer:  BOARD GEOMETRY/DESIGN_OUTLINE*
G04 Layer:  BOARD GEOMETRY/CUTOUT*
G04 Layer:  DRAWING FORMAT/TITLE_BLOCK*
G04 Layer:  MANUFACTURING/TP_TEXT_TOP*
G04 Layer:  REF DES/SILKSCREEN_TOP*
G04 Layer:  PACKAGE GEOMETRY/SILKSCREEN_TOP*
G04 Layer:  MANUFACTURING/PHOTOPLOT_OUTLINE*
G04 Layer:  DRAWING FORMAT/TITLE_DATA_SST*
G04 Layer:  BOARD GEOMETRY/SILKSCREEN_TOP*
G04 *
G04 Offset:    (0.00 0.00)*
G04 Mirror:    No*
G04 Mode:      Positive*
G04 Rotation:  0*
G04 FullContactRelief:  No*
G04 UndefLineWidth:     6.00*
G04 ================== end FILE IDENTIFICATION RECORD ====================*
%FSLAX25Y25*MOIN*%
%IR0*IPPOS*OFA0.00000B0.00000*MIA0B0*SFA1.00000B1.00000*%
%ADD10C,.01*%
%ADD11C,.04*%
%ADD12C,.006*%
%ADD13C,.065*%
%ADD14C,.06501*%
%ADD15C,.06502*%
G75*
%LPD*%
G75*
G36*
G01X17781Y212224D02*
X13781Y210224D01*
Y214224D01*
X17781Y212224D01*
G37*
G36*
G01X11680Y298207D02*
X7680Y296207D01*
Y300207D01*
X11680Y298207D01*
G37*
G36*
G01X16574Y395753D02*
Y392753D01*
X19574Y394253D01*
X16574Y395753D01*
G37*
G36*
G01X17387Y540724D02*
X23037D01*
Y543024D01*
X17387D01*
Y540724D01*
G37*
G36*
G01X43390Y282049D02*
Y283783D01*
X45125Y282916D01*
X43390Y282049D01*
G37*
G36*
G01X41411Y296754D02*
X37803Y294111D01*
X37132Y298054D01*
X41411Y296754D01*
G37*
G36*
G01X43533Y312772D02*
Y314506D01*
X45268Y313639D01*
X43533Y312772D01*
G37*
G36*
G01X42962Y533784D02*
X45262D01*
Y536084D01*
X42962D01*
Y533784D01*
G37*
G36*
G01X50552Y1541802D02*
X54265Y1540569D01*
X53025Y1544275D01*
X50552Y1541802D01*
G37*
G36*
G01X52680Y1603905D02*
X53828Y1601609D01*
X51532D01*
X52680Y1603905D01*
G37*
G36*
G01X67151Y402177D02*
X63534Y400971D01*
X64739Y404589D01*
X67151Y402177D01*
G37*
G36*
G01X82258Y167604D02*
X79112Y165134D01*
X83155Y163223D01*
X82258Y167604D01*
G37*
G36*
G01X93190Y750994D02*
X90412Y754498D01*
X94882Y754618D01*
X93190Y750994D01*
G37*
G36*
G01X88583Y1544990D02*
X85775Y1542142D01*
X90029Y1540758D01*
X88583Y1544990D01*
G37*
G36*
G01X100725Y212241D02*
X96725Y210241D01*
Y214241D01*
X100725Y212241D01*
G37*
G36*
G01X101920Y299922D02*
X99729Y295540D01*
X97538Y299922D01*
X101920D01*
G37*
G36*
G01Y320356D02*
X99729Y315974D01*
X97538Y320356D01*
X101920D01*
G37*
G36*
G01X97665Y1345094D02*
X96465Y1344494D01*
Y1345694D01*
X97665Y1345094D01*
G37*
G36*
G01X101739Y1374621D02*
X99087Y1375505D01*
X100855Y1377272D01*
X101739Y1374621D01*
G37*
G36*
G01X96941Y1706645D02*
X97643Y1709003D01*
X99363Y1707143D01*
X96941Y1706645D01*
G37*
G36*
G01X121624Y751229D02*
X119223Y755002D01*
X123682Y754659D01*
X121624Y751229D01*
G37*
G36*
G01X127548Y1719507D02*
Y1717047D01*
X125368Y1718339D01*
X127548Y1719507D01*
G37*
G36*
G01X139770Y442994D02*
X138120Y438894D01*
X141270D01*
X139770Y442994D01*
G37*
G36*
G01X131075Y521909D02*
X132243Y519729D01*
X129783D01*
X131075Y521909D01*
G37*
G36*
G01X130265Y1345094D02*
X128500Y1344212D01*
Y1345976D01*
X130265Y1345094D01*
G37*
G36*
G01X134233Y1374654D02*
X131581Y1375538D01*
X133349Y1377306D01*
X134233Y1374654D01*
G37*
G36*
G01X130661Y1450619D02*
X126661D01*
X128661Y1446619D01*
X130661Y1450619D01*
G37*
G36*
G01X151314Y750961D02*
X148982Y754777D01*
X153434Y754353D01*
X151314Y750961D01*
G37*
G36*
G01X143665Y1663944D02*
X141553Y1665000D01*
X143665Y1666056D01*
Y1663944D01*
G37*
G36*
G01X148683Y1725852D02*
X150493Y1728244D01*
X151980Y1725237D01*
X148683Y1725852D01*
G37*
G36*
G01X166550Y442454D02*
X164900Y438354D01*
X168050D01*
X166550Y442454D01*
G37*
G36*
G01X159253Y670952D02*
X157932Y673265D01*
X160575Y672934D01*
X159253Y670952D01*
G37*
G36*
G01X162765Y1345094D02*
X161000Y1344212D01*
Y1345976D01*
X162765Y1345094D01*
G37*
G36*
G01X167266Y1374690D02*
X164614Y1375573D01*
X166382Y1377341D01*
X167266Y1374690D01*
G37*
G36*
G01X181395Y751320D02*
X178601Y754812D01*
X183071Y754952D01*
X181395Y751320D01*
G37*
G36*
G01X176480Y1723718D02*
X178601Y1725839D01*
X179662Y1722657D01*
X176480Y1723718D01*
G37*
G36*
G01X192861Y106500D02*
X188861D01*
X190861Y110500D01*
X192861Y106500D01*
G37*
G36*
G01X201372Y162325D02*
X199606Y161387D01*
X201427Y160090D01*
X201372Y162325D01*
G37*
G36*
G01X195365Y1345094D02*
X193665Y1344244D01*
Y1345944D01*
X195365Y1345094D01*
G37*
G36*
G01X200056Y1374706D02*
X197404Y1375590D01*
X199172Y1377358D01*
X200056Y1374706D01*
G37*
G36*
G01X190872Y1722586D02*
X192575Y1725056D01*
X194193Y1722118D01*
X190872Y1722586D01*
G37*
G36*
G01X205061Y106500D02*
X201061D01*
X203061Y110500D01*
X205061Y106500D01*
G37*
G36*
G01X211014Y751054D02*
X208441Y754712D01*
X212911Y754575D01*
X211014Y751054D01*
G37*
G36*
G01X227965Y1345094D02*
X226265Y1344244D01*
Y1345944D01*
X227965Y1345094D01*
G37*
G36*
G01X232761Y1374683D02*
X230109Y1375567D01*
X231877Y1377335D01*
X232761Y1374683D01*
G37*
G36*
G01X219912Y1736565D02*
X224618Y1734212D01*
X219912Y1731859D01*
Y1736565D01*
G37*
G36*
G01X239959Y160162D02*
X237195Y158780D01*
Y161544D01*
X239959Y160162D01*
G37*
G36*
G01X235832Y216131D02*
Y214131D01*
X237832Y215131D01*
X235832Y216131D01*
G37*
G36*
G01X244459Y754152D02*
X240459Y756152D01*
X244459Y758152D01*
Y754152D01*
G37*
G36*
G01X258719Y8829D02*
X260719Y4829D01*
X256719D01*
X258719Y8829D01*
G37*
G36*
G01X253613Y144216D02*
X256377Y145598D01*
Y142834D01*
X253613Y144216D01*
G37*
G36*
G01X257552Y273904D02*
X257052Y274454D01*
X261187Y278752D01*
X260698Y284182D01*
X256852Y288154D01*
X257102Y288854D01*
X257802Y288954D01*
X260523Y286126D01*
X260415Y287322D01*
X261655Y288322D01*
X262655Y288372D01*
X263605Y288822D01*
X265755D01*
X266305Y288572D01*
X267455Y287722D01*
X267655D01*
X268055Y288122D01*
X268855Y288022D01*
X269205Y287622D01*
Y287086D01*
X271002Y288954D01*
X271702Y288854D01*
X271952Y288154D01*
X269205Y285317D01*
Y284272D01*
X268955Y283972D01*
X268355D01*
X267759Y278605D01*
X267853Y278507D01*
X267905Y278472D01*
G02X268528Y277805I-1089J-1641D01*
G01X271752Y274454D01*
X271252Y273904D01*
X270602Y273954D01*
X268608Y276013D01*
G02X265155Y275772I-1792J818D01*
G01X261455D01*
X261328Y277182D01*
X258202Y273954D01*
X257552Y273904D01*
G37*
G36*
G01X262265Y1298948D02*
X258265Y1296948D01*
Y1300948D01*
X262265Y1298948D01*
G37*
G36*
G01X277025Y164263D02*
X274197Y161434D01*
X278440Y160020D01*
X277025Y164263D01*
G37*
G36*
G01X266320Y224332D02*
Y226792D01*
X268500Y225500D01*
X266320Y224332D01*
G37*
G36*
G01X267968Y591893D02*
X269968Y587893D01*
X265968D01*
X267968Y591893D01*
G37*
G36*
G01X269069Y655480D02*
X272206Y654434D01*
X270115Y652344D01*
X269069Y655480D01*
G37*
G36*
G01X274812Y682380D02*
X278812Y684380D01*
Y680380D01*
X274812Y682380D01*
G37*
G36*
G01X266377Y1328395D02*
X263725Y1329279D01*
X265493Y1331047D01*
X266377Y1328395D01*
G37*
G36*
G01X263457Y1542491D02*
Y1545491D01*
X270197D01*
Y1538431D01*
X267197D01*
Y1542491D01*
X263457D01*
G37*
G36*
G01X280314Y118089D02*
X276630Y117392D01*
X278283Y120756D01*
X280314Y118089D01*
G37*
G36*
G01X293823Y1734212D02*
X289823Y1732212D01*
Y1736212D01*
X293823Y1734212D01*
G37*
G36*
G01D02*
X289823Y1732212D01*
Y1736212D01*
X293823Y1734212D01*
G37*
G36*
G01X302455Y82460D02*
Y88570D01*
X308486D01*
Y85570D01*
X305455D01*
Y82460D01*
X302455D01*
G37*
G36*
G01X308490Y88567D02*
Y85567D01*
X305459D01*
Y82457D01*
X302459D01*
Y88567D01*
X308490D01*
G37*
G36*
G01X298029Y239625D02*
X296867Y241253D01*
X295820Y239277D01*
X298029Y239625D01*
G37*
G36*
G01X302072Y689657D02*
X304723Y688773D01*
X302956Y687006D01*
X302072Y689657D01*
G37*
G36*
G01X295161Y1298863D02*
X293461Y1298013D01*
Y1299713D01*
X295161Y1298863D01*
G37*
G36*
G01X299197Y1328009D02*
X296546Y1328893D01*
X298313Y1330661D01*
X299197Y1328009D01*
G37*
G36*
G01X319053Y553897D02*
X322053Y552397D01*
X319053Y550897D01*
Y553897D01*
G37*
G36*
G01X313345Y658315D02*
G02X340117I13386J0D01*
G01X313345D01*
G37*
G36*
G01X306631Y722797D02*
X308045Y727040D01*
X310874Y724212D01*
X306631Y722797D01*
G37*
G36*
G01X333689Y184470D02*
X336129D01*
X334909Y182030D01*
X333689Y184470D01*
G37*
G36*
G01X320320Y276832D02*
Y279292D01*
X322500Y278000D01*
X320320Y276832D01*
G37*
G36*
G01X334242Y709450D02*
X337263Y708443D01*
X335249Y706429D01*
X334242Y709450D01*
G37*
G36*
G01X328065Y1298863D02*
X326365Y1298013D01*
Y1299713D01*
X328065Y1298863D01*
G37*
G36*
G01X332223Y1328211D02*
X329572Y1329095D01*
X331339Y1330863D01*
X332223Y1328211D01*
G37*
G36*
G01X341734Y135429D02*
X340710Y133710D01*
X343800Y133035D01*
X341734Y135429D01*
G37*
G36*
G01X338891Y739414D02*
X340991Y740464D01*
Y738364D01*
X338891Y739414D01*
G37*
G36*
G01X370016Y228675D02*
Y222565D01*
X363985D01*
Y225565D01*
X367016D01*
Y228675D01*
X370016D01*
G37*
G36*
G01X363982Y222561D02*
Y225561D01*
X367013D01*
Y228671D01*
X370013D01*
Y222561D01*
X363982D01*
G37*
G36*
G01X350345Y658315D02*
G02X377117I13386J0D01*
G01X350345D01*
G37*
G36*
G01X360561Y1298920D02*
X358861Y1298070D01*
Y1299770D01*
X360561Y1298920D01*
G37*
G36*
G01X365005Y1328537D02*
X362354Y1329421D01*
X364122Y1331189D01*
X365005Y1328537D01*
G37*
G36*
G01X366123Y141637D02*
Y143637D01*
X368123Y142637D01*
X366123Y141637D01*
G37*
G36*
G01X370394Y293128D02*
X371808Y297370D01*
X374637Y294542D01*
X370394Y293128D01*
G37*
G36*
G01X366820Y310332D02*
Y312792D01*
X369000Y311500D01*
X366820Y310332D01*
G37*
G36*
G01X367677Y709660D02*
X370329Y708776D01*
X368561Y707008D01*
X367677Y709660D01*
G37*
G36*
G01X371951Y739326D02*
X374051Y740376D01*
Y738276D01*
X371951Y739326D01*
G37*
G36*
G01X377540Y1589432D02*
X374878Y1589358D01*
X375883Y1591517D01*
X377540Y1589432D01*
G37*
G36*
G01X377611Y1635222D02*
Y1631222D01*
X381611Y1633222D01*
X377611Y1635222D01*
G37*
G36*
G01X389925Y146294D02*
X391925Y150294D01*
X393925Y146294D01*
X389925D01*
G37*
G36*
G01X387876Y497626D02*
X391610D01*
X389743Y493891D01*
X387876Y497626D01*
G37*
G36*
G01X393701Y1322864D02*
X391898Y1323465D01*
X393100Y1324667D01*
X393701Y1322864D01*
G37*
G36*
G01X391519Y1542491D02*
Y1545491D01*
X398259D01*
Y1538431D01*
X395259D01*
Y1542491D01*
X391519D01*
G37*
G36*
G01X404746Y495996D02*
X403578Y498176D01*
X406038D01*
X404746Y495996D01*
G37*
G36*
G01X400963Y709672D02*
X403614Y708788D01*
X401847Y707021D01*
X400963Y709672D01*
G37*
G36*
G01X409958Y719958D02*
X406895Y718426D01*
Y721490D01*
X409958Y719958D01*
G37*
G36*
G01X404991Y739214D02*
X408991Y741214D01*
Y737214D01*
X404991Y739214D01*
G37*
G36*
G01X397477Y1347793D02*
X394825Y1348677D01*
X396593Y1350445D01*
X397477Y1347793D01*
G37*
G36*
G01X421056Y242953D02*
Y238953D01*
X425056Y240953D01*
X421056Y242953D01*
G37*
G36*
G01X418783Y495675D02*
X417615Y497855D01*
X420075D01*
X418783Y495675D01*
G37*
G36*
G01X416999Y1599460D02*
X412999D01*
X414999Y1595460D01*
X416999Y1599460D01*
G37*
G36*
G01X410692Y1673650D02*
X412426D01*
X411559Y1671915D01*
X410692Y1673650D01*
G37*
G36*
G01X427307Y66129D02*
X426399Y70024D01*
X430748Y68986D01*
X427307Y66129D01*
G37*
G36*
G01X429649Y86643D02*
Y82443D01*
X425349Y84743D01*
X429649Y86643D01*
G37*
G36*
G01X428177Y103794D02*
Y106094D01*
X425877D01*
Y103794D01*
X428177D01*
G37*
G36*
G01X431649Y271905D02*
X427649D01*
X429649Y267905D01*
X431649Y271905D01*
G37*
G36*
G01X432563Y495740D02*
X431395Y497920D01*
X433855D01*
X432563Y495740D01*
G37*
G36*
G01X438545Y607645D02*
G02Y580873I0J-13386D01*
G01Y607645D01*
G37*
G36*
G01X434157Y692010D02*
X436808Y691126D01*
X435041Y689358D01*
X434157Y692010D01*
G37*
G36*
G01X442374Y1597789D02*
X438374D01*
X440374Y1593789D01*
X442374Y1597789D01*
G37*
G36*
G01X427018Y1623486D02*
X427422Y1628732D01*
X431457Y1626311D01*
X427018Y1623486D01*
G37*
G36*
G01X466406Y667469D02*
X469058Y666585D01*
X467290Y664817D01*
X466406Y667469D01*
G37*
G36*
G01X458919Y1577565D02*
X460110Y1579947D01*
X461539Y1578042D01*
X458919Y1577565D01*
G37*
G36*
G01X459536Y1632441D02*
X462300Y1633823D01*
Y1631059D01*
X459536Y1632441D01*
G37*
G36*
G01X483970Y210253D02*
X484970Y208253D01*
X482970D01*
X483970Y210253D01*
G37*
G36*
G01X472318Y305290D02*
X469136Y306351D01*
X471258Y308472D01*
X472318Y305290D01*
G37*
G36*
G01X472490Y696814D02*
X474190Y697664D01*
Y695964D01*
X472490Y696814D01*
G37*
G36*
G01X479253Y1653681D02*
X480262Y1656602D01*
X482195Y1654627D01*
X479253Y1653681D01*
G37*
G36*
G01X476888Y1694842D02*
X477908Y1692421D01*
X474975Y1692611D01*
X476888Y1694842D01*
G37*
G36*
G01X475436Y1731661D02*
X476662Y1730435D01*
X474822Y1729821D01*
X475436Y1731661D01*
G37*
G36*
G01X493049Y106450D02*
X494549Y103450D01*
X491549D01*
X493049Y106450D01*
G37*
G36*
G01X488566Y1734212D02*
X484566Y1732212D01*
Y1736212D01*
X488566Y1734212D01*
G37*
G36*
G01X501863Y250439D02*
X499480Y247227D01*
X503884Y246450D01*
X501863Y250439D01*
G37*
G36*
G01X513555Y451917D02*
X510952Y448880D01*
X515291Y447795D01*
X513555Y451917D01*
G37*
G36*
G01X498911Y640738D02*
X501563Y639854D01*
X499795Y638086D01*
X498911Y640738D01*
G37*
G36*
G01X504862Y670314D02*
X506562Y671164D01*
Y669464D01*
X504862Y670314D01*
G37*
G36*
G01X519200Y212432D02*
X521200Y213432D01*
Y211432D01*
X519200Y212432D01*
G37*
G36*
G01X527630Y1542491D02*
Y1545491D01*
X534370D01*
Y1538431D01*
X531370D01*
Y1542491D01*
X527630D01*
G37*
G36*
G01X532027Y606612D02*
X534679Y605728D01*
X532911Y603960D01*
X532027Y606612D01*
G37*
G36*
G01X537462Y636214D02*
X540000Y637483D01*
Y634945D01*
X537462Y636214D01*
G37*
G36*
G01X549566Y134980D02*
Y130980D01*
X545566Y132980D01*
X549566Y134980D01*
G37*
G36*
G01X558906Y314091D02*
X555724Y315152D01*
X557845Y317273D01*
X558906Y314091D01*
G37*
G36*
G01X557996Y1734212D02*
X553996Y1732212D01*
Y1736212D01*
X557996Y1734212D01*
G37*
G36*
G01D02*
X553996Y1732212D01*
Y1736212D01*
X557996Y1734212D01*
G37*
G36*
G01X568802Y160264D02*
X570527Y161989D01*
X571390Y159401D01*
X568802Y160264D01*
G37*
G36*
G01X559145Y380486D02*
X562145Y378986D01*
X559145Y377486D01*
Y380486D01*
G37*
G36*
G01Y391286D02*
X562145Y389786D01*
X559145Y388286D01*
Y391286D01*
G37*
G36*
G01Y405217D02*
X562145Y403717D01*
X559145Y402217D01*
Y405217D01*
G37*
G36*
G01X563612Y415846D02*
X561348Y414714D01*
Y416978D01*
X563612Y415846D01*
G37*
G36*
G01X585393Y880671D02*
Y867789D01*
X571448D01*
Y870789D01*
X582393D01*
Y880671D01*
X585393D01*
G37*
G36*
G01X576672Y230955D02*
X575672Y232955D01*
X577672D01*
X576672Y230955D01*
G37*
G36*
G01X577242Y421321D02*
X580006Y422703D01*
Y419939D01*
X577242Y421321D01*
G37*
G36*
G01X577624Y456244D02*
Y460244D01*
X573624Y458244D01*
X577624Y456244D01*
G37*
G36*
G01X595435Y180578D02*
X593935Y177578D01*
X592435Y180578D01*
X595435D01*
G37*
G36*
G01X596170Y228660D02*
X598074Y232178D01*
X600640Y228516D01*
X596170Y228660D01*
G37*
G36*
G01X595145Y391286D02*
X598145Y389786D01*
X595145Y388286D01*
Y391286D01*
G37*
G36*
G01Y380486D02*
X598145Y378986D01*
X595145Y377486D01*
Y380486D01*
G37*
G36*
G01X596723Y405936D02*
Y409936D01*
X600723Y407936D01*
X596723Y405936D01*
G37*
G36*
G01X591171Y439949D02*
X588991Y438781D01*
Y441241D01*
X591171Y439949D01*
G37*
G36*
G01X606516Y285372D02*
X611316D01*
X609016Y280172D01*
X606516Y285372D01*
G37*
G36*
G01X613055Y413397D02*
X614298Y414964D01*
X612109Y415423D01*
X613055Y413397D01*
G37*
G36*
G01X634181Y304413D02*
X631250Y305390D01*
X633204Y307344D01*
X634181Y304413D01*
G37*
G36*
G01X623941Y461254D02*
X627941Y463254D01*
Y459254D01*
X623941Y461254D01*
G37*
G36*
G01X632514Y513971D02*
X633611Y516508D01*
X635599Y514142D01*
X632514Y513971D01*
G37*
G36*
G01X634914Y125171D02*
X635914Y123171D01*
X633914D01*
X634914Y125171D01*
G37*
G36*
G01X637485Y412169D02*
X635531Y410215D01*
X634554Y413146D01*
X637485Y412169D01*
G37*
G36*
G01X650292Y1382518D02*
X647726Y1382584D01*
X649319Y1384597D01*
X650292Y1382518D01*
G37*
G36*
G01X639885Y1686765D02*
X637425D01*
X638717Y1688945D01*
X639885Y1686765D01*
G37*
G36*
G01X656168Y364820D02*
X653708D01*
X655000Y367000D01*
X656168Y364820D01*
G37*
G36*
G01X655692Y1542491D02*
Y1545491D01*
X662432D01*
Y1538431D01*
X659432D01*
Y1542491D01*
X655692D01*
G37*
G36*
G01X660918Y1682909D02*
X657901Y1685535D01*
X656784Y1681205D01*
X660918Y1682909D01*
G37*
G36*
G01X655284Y1723631D02*
X652418Y1724787D01*
X654489Y1726617D01*
X655284Y1723631D01*
G37*
G36*
G01X654765Y1735825D02*
X651711Y1736297D01*
X653311Y1738551D01*
X654765Y1735825D01*
G37*
G36*
G01X670175Y750927D02*
X667559Y754555D01*
X672031Y754471D01*
X670175Y750927D01*
G37*
G36*
G01X680452Y1686558D02*
X676452D01*
X678452Y1682558D01*
X680452Y1686558D01*
G37*
G36*
G01X693000Y423043D02*
Y415562D01*
X700481D01*
Y412562D01*
X690000D01*
Y423043D01*
X693000D01*
G37*
G36*
G01D02*
Y415562D01*
X700481D01*
Y412562D01*
X690000D01*
Y423043D01*
X693000D01*
G37*
G36*
G01X684721Y1644509D02*
Y1647273D01*
X687485Y1645891D01*
X684721Y1644509D01*
G37*
G36*
G01X701901Y25416D02*
X705901D01*
X703901Y29416D01*
X701901Y25416D01*
G37*
G36*
G01X705013Y223653D02*
Y219653D01*
X701013Y221653D01*
X705013Y223653D01*
G37*
G36*
G01D02*
Y219653D01*
X701013Y221653D01*
X705013Y223653D01*
G37*
G36*
G01X701013Y221653D02*
X705013Y223653D01*
Y219653D01*
X701013Y221653D01*
G37*
G36*
G01X704440Y611197D02*
X706880D01*
X705660Y608757D01*
X704440Y611197D01*
G37*
G36*
G01X699876Y750927D02*
X697260Y754555D01*
X701732Y754471D01*
X699876Y750927D01*
G37*
G36*
G01X709400Y1392568D02*
X706748Y1393452D01*
X708516Y1395220D01*
X709400Y1392568D01*
G37*
G36*
G01X705773Y1637089D02*
X703489Y1640372D01*
X707914Y1641015D01*
X705773Y1637089D01*
G37*
G36*
G01X711730Y123451D02*
X708349Y121832D01*
X709083Y125508D01*
X711730Y123451D01*
G37*
G36*
G01X715985Y641554D02*
X717176Y643936D01*
X718367Y641554D01*
X715985D01*
G37*
G36*
G01X737036Y101942D02*
Y108052D01*
X743067D01*
Y105052D01*
X740036D01*
Y101942D01*
X737036D01*
G37*
G36*
G01X743066Y108052D02*
Y105052D01*
X740035D01*
Y101942D01*
X737035D01*
Y108052D01*
X743066D01*
G37*
G36*
G01X729531Y751189D02*
X726893Y754800D01*
X731364Y754744D01*
X729531Y751189D01*
G37*
G36*
G01X751358Y207353D02*
X748674Y206693D01*
X749356Y209707D01*
X751358Y207353D01*
G37*
G36*
G01X742038Y1392686D02*
X739386Y1393570D01*
X741154Y1395338D01*
X742038Y1392686D01*
G37*
G36*
G01X741259Y1431813D02*
G02X768031I13386J0D01*
G01X741259D01*
G37*
G36*
G01X740837Y1593133D02*
X741649Y1597530D01*
X744843Y1595123D01*
X740837Y1593133D01*
G37*
G36*
G01X751666Y1636420D02*
X750175Y1637754D01*
X752254Y1638578D01*
X751666Y1636420D01*
G37*
G36*
G01X747084Y1720581D02*
Y1724963D01*
X751466Y1722772D01*
X747084Y1720581D01*
G37*
G36*
G01X759232Y751189D02*
X756594Y754800D01*
X761065Y754744D01*
X759232Y751189D01*
G37*
G36*
G01X772782Y167352D02*
X775546Y168734D01*
Y165970D01*
X772782Y167352D01*
G37*
G36*
G01X776279Y281384D02*
X777109Y285778D01*
X780293Y283357D01*
X776279Y281384D01*
G37*
G36*
G01X782048Y384024D02*
Y386484D01*
X784228Y385192D01*
X782048Y384024D01*
G37*
G36*
G01X788933Y751189D02*
X786295Y754800D01*
X790766Y754744D01*
X788933Y751189D01*
G37*
G36*
G01X783342Y1488821D02*
X787342Y1490821D01*
Y1486821D01*
X783342Y1488821D01*
G37*
G36*
G01X795941Y1573968D02*
X800183Y1572554D01*
X797355Y1569726D01*
X795941Y1573968D01*
G37*
G36*
G01X798364Y1334469D02*
X801165Y1335870D01*
Y1333068D01*
X798364Y1334469D01*
G37*
G36*
G01X817423Y125605D02*
X814594Y128433D01*
X818837Y129847D01*
X817423Y125605D01*
G37*
G36*
G01D02*
X814594Y128433D01*
X818837Y129847D01*
X817423Y125605D01*
G37*
G36*
G01X817422D02*
X814593Y128433D01*
X818836Y129847D01*
X817422Y125605D01*
G37*
G36*
G01X813751Y490643D02*
Y493083D01*
X816191Y491863D01*
X813751Y490643D01*
G37*
G36*
G01X818679Y513872D02*
X815915D01*
X817297Y516636D01*
X818679Y513872D01*
G37*
G36*
G01X820526Y750863D02*
X817888Y754474D01*
X822359Y754418D01*
X820526Y750863D01*
G37*
G36*
G01X837697Y98527D02*
X832497Y101027D01*
Y96627D01*
X837697Y98527D01*
G37*
G36*
G01X837575Y219548D02*
X839324Y221600D01*
X840502Y218825D01*
X837575Y219548D01*
G37*
G36*
G01X839636Y395900D02*
X840457Y398218D01*
X842081Y396273D01*
X839636Y395900D01*
G37*
G36*
G01X837941Y1573968D02*
X842183Y1572554D01*
X839355Y1569726D01*
X837941Y1573968D01*
G37*
G36*
G01X847876Y84948D02*
X846708Y87128D01*
X849168D01*
X847876Y84948D01*
G37*
G36*
G01X843760Y462400D02*
X845760D01*
X844760Y464400D01*
X843760Y462400D01*
G37*
G36*
G01X856483Y1514672D02*
X852483D01*
X854483Y1518672D01*
X856483Y1514672D01*
G37*
G36*
G01X860784Y163675D02*
X858344D01*
X859564Y166115D01*
X860784Y163675D01*
G37*
G36*
G01X863346Y280001D02*
Y286111D01*
X869377D01*
Y283111D01*
X866346D01*
Y280001D01*
X863346D01*
G37*
G36*
G01D02*
Y286111D01*
X869377D01*
Y283111D01*
X866346D01*
Y280001D01*
X863346D01*
G37*
G36*
G01X869376Y286111D02*
Y283111D01*
X866345D01*
Y280001D01*
X863345D01*
Y286111D01*
X869376D01*
G37*
G36*
G01X875740Y401450D02*
Y403450D01*
X873740Y402450D01*
X875740Y401450D01*
G37*
G36*
G01X879941Y1573968D02*
X884183Y1572554D01*
X881355Y1569726D01*
X879941Y1573968D01*
G37*
G36*
G01X899530Y1157362D02*
Y1153362D01*
X903530Y1155362D01*
X899530Y1157362D01*
G37*
G36*
G01X903550Y162695D02*
X908540Y164359D01*
X906877Y159368D01*
X903550Y162695D01*
G37*
G36*
G01X921941Y1573968D02*
X926183Y1572554D01*
X923355Y1569726D01*
X921941Y1573968D01*
G37*
G36*
G01X944868Y268442D02*
Y266002D01*
X942428Y267222D01*
X944868Y268442D01*
G37*
G36*
G01X939766Y578179D02*
X936938Y575350D01*
X935523Y579593D01*
X939766Y578179D01*
G37*
G36*
G01X938348Y599195D02*
Y595195D01*
X934348Y597195D01*
X938348Y599195D01*
G37*
G36*
G01X939590Y608890D02*
X937247Y605649D01*
X935177Y609613D01*
X939590Y608890D01*
G37*
G36*
G01X937728Y624411D02*
X934404Y626073D01*
X937728Y627735D01*
Y624411D01*
G37*
G36*
G01X934620Y1503895D02*
X934955Y1507027D01*
X938856Y1504950D01*
X934620Y1503895D01*
G37*
G36*
G01X940780Y1734190D02*
X936780D01*
X938780Y1730190D01*
X940780Y1734190D01*
G37*
G36*
G01X946555Y1157362D02*
Y1153362D01*
X950555Y1155362D01*
X946555Y1157362D01*
G37*
G36*
G01X959865Y1464365D02*
X963865Y1466365D01*
Y1462365D01*
X959865Y1464365D01*
G37*
G36*
G01X961117Y1503245D02*
X961246Y1506393D01*
X965275Y1504576D01*
X961117Y1503245D01*
G37*
G36*
G01X984401Y1503304D02*
X984387Y1506454D01*
X988494Y1504823D01*
X984401Y1503304D01*
G37*
G36*
G01X1002499Y169510D02*
X999499D01*
Y172541D01*
X996389D01*
Y175541D01*
X1002499D01*
Y169510D01*
G37*
G36*
G01X993913Y263755D02*
X991149Y262373D01*
Y265137D01*
X993913Y263755D01*
G37*
G36*
G01Y274239D02*
X991149Y272857D01*
Y275621D01*
X993913Y274239D01*
G37*
G36*
G01X993391Y298277D02*
X994597Y299523D01*
X995240Y297693D01*
X993391Y298277D01*
G37*
G36*
G01X1004662Y404823D02*
X1002662Y408823D01*
X1006662D01*
X1004662Y404823D01*
G37*
G36*
G01X992786Y431028D02*
X991786Y433028D01*
X993786D01*
X992786Y431028D01*
G37*
G36*
G01X1008065Y188360D02*
X1007410Y192050D01*
X1010755Y190359D01*
X1008065Y188360D01*
G37*
G36*
G01X1007764Y1503036D02*
Y1506186D01*
X1011864Y1504536D01*
X1007764Y1503036D01*
G37*
G36*
G01X1025159Y483394D02*
X1021159Y481394D01*
Y485394D01*
X1025159Y483394D01*
G37*
G36*
G01X1030687Y512615D02*
X1032687Y508615D01*
X1028687D01*
X1030687Y512615D01*
G37*
G36*
G01X1030689Y540970D02*
X1031689Y538970D01*
X1029689D01*
X1030689Y540970D01*
G37*
G36*
G01X1031219Y1503266D02*
X1031369Y1506412D01*
X1035386Y1504569D01*
X1031219Y1503266D01*
G37*
G36*
G01X1062763Y1431367D02*
X1067145Y1429176D01*
X1062763Y1426985D01*
Y1431367D01*
G37*
G36*
G01X1054679Y1503228D02*
X1054751Y1506377D01*
X1058812Y1504634D01*
X1054679Y1503228D01*
G37*
G36*
G01X1065869Y375927D02*
X1069869Y377927D01*
Y373927D01*
X1065869Y375927D01*
G37*
G36*
G01X1066249Y411624D02*
X1070249Y413624D01*
Y409624D01*
X1066249Y411624D01*
G37*
G36*
G01X1068511Y753491D02*
X1066722Y755638D01*
X1069513Y755781D01*
X1068511Y753491D01*
G37*
G36*
G01X1069191Y1348913D02*
X1067388Y1349514D01*
X1068590Y1350716D01*
X1069191Y1348913D01*
G37*
G36*
G01X1070698Y1375663D02*
X1072593Y1377558D01*
X1073540Y1374716D01*
X1070698Y1375663D01*
G37*
G36*
G01X1078023Y1503293D02*
X1078054Y1506443D01*
X1082138Y1504753D01*
X1078023Y1503293D01*
G37*
G36*
G01X1070870Y1658767D02*
Y1663149D01*
X1075252Y1660958D01*
X1070870Y1658767D01*
G37*
G36*
G01X1098343Y752295D02*
X1096554Y754442D01*
X1099345Y754585D01*
X1098343Y752295D01*
G37*
G36*
G01X1102003Y1345075D02*
X1100303Y1344225D01*
Y1345925D01*
X1102003Y1345075D01*
G37*
G36*
G01X1103288Y1375597D02*
X1105200Y1377509D01*
X1106156Y1374641D01*
X1103288Y1375597D01*
G37*
G36*
G01X1108589Y1653831D02*
X1103883Y1651478D01*
Y1656184D01*
X1108589Y1653831D01*
G37*
G36*
G01X1102314Y1713521D02*
X1100474Y1712907D01*
X1101088Y1714747D01*
X1102314Y1713521D01*
G37*
G36*
G01X1101892Y1726394D02*
X1103847Y1728349D01*
X1104824Y1725417D01*
X1101892Y1726394D01*
G37*
G36*
G01X1122282Y374453D02*
X1126754D01*
X1124965Y370876D01*
X1122282Y374453D01*
G37*
G36*
G01X1117534Y485052D02*
X1115534Y489052D01*
X1119534D01*
X1117534Y485052D01*
G37*
G36*
G01X1128043Y752295D02*
X1126254Y754442D01*
X1129045Y754585D01*
X1128043Y752295D01*
G37*
G36*
G01X1134703Y1345075D02*
X1133003Y1344225D01*
Y1345925D01*
X1134703Y1345075D01*
G37*
G36*
G01X1136137Y1375547D02*
X1137964Y1377374D01*
X1138877Y1374634D01*
X1136137Y1375547D01*
G37*
G36*
G01X1140436Y1551149D02*
X1139774Y1548570D01*
X1137975Y1550131D01*
X1140436Y1551149D01*
G37*
G36*
G01X1138698Y1599722D02*
X1135095Y1601460D01*
X1135158Y1596988D01*
X1138698Y1599722D01*
G37*
G36*
G01X1129480Y1686633D02*
X1131940D01*
X1130648Y1684453D01*
X1129480Y1686633D01*
G37*
G36*
G01X1140819Y66186D02*
Y70186D01*
X1144819Y68186D01*
X1140819Y66186D01*
G37*
G36*
G01X1153149Y1417400D02*
G02X1179921I13386J0D01*
G01X1153149D01*
G37*
G36*
G01X1157744Y752295D02*
X1155955Y754442D01*
X1158746Y754585D01*
X1157744Y752295D01*
G37*
G36*
G01X1167603Y1345075D02*
X1165903Y1344225D01*
Y1345925D01*
X1167603Y1345075D01*
G37*
G36*
G01X1169003Y1375639D02*
X1170836Y1377472D01*
X1171751Y1374724D01*
X1169003Y1375639D01*
G37*
G36*
G01X1179525Y85177D02*
X1180586Y88359D01*
X1182707Y86237D01*
X1179525Y85177D01*
G37*
G36*
G01X1173858Y201602D02*
X1175858Y197602D01*
X1171858D01*
X1173858Y201602D01*
G37*
G36*
G01X1187250Y1689765D02*
X1183250D01*
X1185250Y1685765D01*
X1187250Y1689765D01*
G37*
G36*
G01X1190751Y82798D02*
X1193515Y84180D01*
Y81416D01*
X1190751Y82798D01*
G37*
G36*
G01X1190135Y104434D02*
Y102434D01*
X1193135Y103434D01*
X1190135Y104434D01*
G37*
G36*
G01X1201253Y450261D02*
X1197010Y451675D01*
X1199838Y454504D01*
X1201253Y450261D01*
G37*
G36*
G01X1195305Y578178D02*
X1192923Y579369D01*
X1195305Y580560D01*
Y578178D01*
G37*
G36*
G01X1187510Y752262D02*
X1185721Y754409D01*
X1188512Y754552D01*
X1187510Y752262D01*
G37*
G36*
G01X1200403Y1345075D02*
X1198703Y1344225D01*
Y1345925D01*
X1200403Y1345075D01*
G37*
G36*
G01X1201801Y1375582D02*
X1203651Y1377432D01*
X1204575Y1374658D01*
X1201801Y1375582D01*
G37*
G36*
G01X1199751Y1687723D02*
X1200728Y1690654D01*
X1202683Y1688700D01*
X1199751Y1687723D01*
G37*
G36*
G01X1203871Y1705019D02*
X1206802Y1704042D01*
X1204848Y1702088D01*
X1203871Y1705019D01*
G37*
G36*
G01X1203918Y1719019D02*
X1206849Y1718042D01*
X1204895Y1716088D01*
X1203918Y1719019D01*
G37*
G36*
G01X1218433Y186189D02*
X1222433D01*
X1220433Y182189D01*
X1218433Y186189D01*
G37*
G36*
G01X1217106Y477089D02*
X1215106Y481089D01*
X1219106D01*
X1217106Y477089D01*
G37*
G36*
G01X1220357Y754593D02*
X1216304Y756482D01*
X1220247Y758591D01*
X1220357Y754593D01*
G37*
G36*
G01X1231612Y1439024D02*
X1227612D01*
X1229612Y1435024D01*
X1231612Y1439024D01*
G37*
G36*
G01X1215034Y1687693D02*
X1216011Y1690625D01*
X1217966Y1688670D01*
X1215034Y1687693D01*
G37*
G36*
G01X1232266Y1734212D02*
X1228266Y1732212D01*
Y1736212D01*
X1232266Y1734212D01*
G37*
G36*
G01X1233232Y98210D02*
X1231052Y97042D01*
Y99502D01*
X1233232Y98210D01*
G37*
G36*
G01X1238394Y1298929D02*
X1234394Y1296929D01*
Y1300929D01*
X1238394Y1298929D01*
G37*
G36*
G01X1242382Y1328407D02*
X1239730Y1329291D01*
X1241498Y1331059D01*
X1242382Y1328407D01*
G37*
G36*
G01X1263841Y57384D02*
X1257841Y60384D01*
X1263841Y63384D01*
Y57384D01*
G37*
G36*
G01X1257674Y151263D02*
X1261674D01*
X1259674Y147263D01*
X1257674Y151263D01*
G37*
G36*
G01D02*
X1261674D01*
X1259674Y147263D01*
X1257674Y151263D01*
G37*
G36*
G01D02*
X1261674D01*
X1259674Y147263D01*
X1257674Y151263D01*
G37*
G36*
G01D02*
X1261674D01*
X1259674Y147263D01*
X1257674Y151263D01*
G37*
G36*
G01X1250065Y251594D02*
X1246065Y249594D01*
Y253594D01*
X1250065Y251594D01*
G37*
G36*
G01X1270402Y416595D02*
X1267739Y413610D01*
X1272056Y412440D01*
X1270402Y416595D01*
G37*
G36*
G01X1271290Y1298844D02*
X1269590Y1297994D01*
Y1299694D01*
X1271290Y1298844D01*
G37*
G36*
G01X1275303Y1327797D02*
X1272803Y1326547D01*
Y1329047D01*
X1275303Y1327797D01*
G37*
G36*
G01X1271330Y1575491D02*
Y1578491D01*
X1278070D01*
Y1571431D01*
X1275070D01*
Y1575491D01*
X1271330D01*
G37*
G36*
G01X1277760Y1380636D02*
G02X1304532I13386J0D01*
G01X1277760D01*
G37*
G36*
G01X1299409Y82866D02*
X1296645Y81484D01*
Y84248D01*
X1299409Y82866D01*
G37*
G36*
G01X1304194Y1298844D02*
X1302494Y1297994D01*
Y1299694D01*
X1304194Y1298844D01*
G37*
G36*
G01X1302696Y1734212D02*
X1298696Y1732212D01*
Y1736212D01*
X1302696Y1734212D01*
G37*
G36*
G01D02*
X1298696Y1732212D01*
Y1736212D01*
X1302696Y1734212D01*
G37*
G36*
G01X1308818Y95394D02*
X1305207Y94430D01*
X1306602Y97898D01*
X1308818Y95394D01*
G37*
G36*
G01X1313323Y561302D02*
X1310707Y559994D01*
Y562610D01*
X1313323Y561302D01*
G37*
G36*
G01X1308220Y1328354D02*
X1305568Y1329238D01*
X1307336Y1331006D01*
X1308220Y1328354D01*
G37*
G36*
G01X1307130Y1380636D02*
G02X1333902I13386J0D01*
G01X1307130D01*
G37*
G36*
G01X1344958Y87248D02*
X1343576Y90012D01*
X1346340D01*
X1344958Y87248D01*
G37*
G36*
G01X1336690Y1298901D02*
X1334990Y1298051D01*
Y1299751D01*
X1336690Y1298901D01*
G37*
G36*
G01X1341132Y1328696D02*
X1338480Y1329579D01*
X1340248Y1331347D01*
X1341132Y1328696D01*
G37*
G36*
G01X1356922Y86988D02*
X1355540Y89752D01*
X1358304D01*
X1356922Y86988D01*
G37*
G36*
G01X1362927Y236594D02*
X1366927Y238594D01*
Y234594D01*
X1362927Y236594D01*
G37*
G36*
G01X1368369Y119882D02*
X1367201Y122062D01*
X1369661D01*
X1368369Y119882D01*
G37*
G36*
G01X1369524Y1315958D02*
X1368110Y1311715D01*
X1365281Y1314544D01*
X1369524Y1315958D01*
G37*
G36*
G01X1373625Y1347966D02*
X1370973Y1348850D01*
X1372741Y1350618D01*
X1373625Y1347966D01*
G37*
G36*
G01X1393260Y184113D02*
X1389260D01*
X1391260Y180113D01*
X1393260Y184113D01*
G37*
G36*
G01X1379420Y624733D02*
X1382441Y623726D01*
X1380427Y621712D01*
X1379420Y624733D01*
G37*
G36*
G01X1384463Y650205D02*
X1388463Y652205D01*
Y648205D01*
X1384463Y650205D01*
G37*
G36*
G01X1383800Y1680602D02*
X1385182Y1677838D01*
X1382418D01*
X1383800Y1680602D01*
G37*
G36*
G01X1393338Y1729198D02*
X1395459Y1727077D01*
X1392277Y1726016D01*
X1393338Y1729198D01*
G37*
G36*
G01X1399392Y1575491D02*
Y1578491D01*
X1406132D01*
Y1571431D01*
X1403132D01*
Y1575491D01*
X1399392D01*
G37*
G36*
G01X1397816Y1632503D02*
X1396839Y1629572D01*
X1394885Y1631526D01*
X1397816Y1632503D01*
G37*
G36*
G01X1416486Y90432D02*
X1422486Y87432D01*
X1416486Y84432D01*
Y90432D01*
G37*
G36*
G01X1420611Y614616D02*
G02Y587844I0J-13386D01*
G01Y614616D01*
G37*
G36*
G01X1412386Y657589D02*
X1415237Y656639D01*
X1413337Y654738D01*
X1412386Y657589D01*
G37*
G36*
G01X1417580Y683116D02*
X1421580Y685116D01*
Y681116D01*
X1417580Y683116D01*
G37*
G36*
G01X1415622Y1619105D02*
X1411622D01*
X1413622Y1623105D01*
X1415622Y1619105D01*
G37*
G36*
G01X1439780Y1597851D02*
Y1595087D01*
X1437016Y1596469D01*
X1439780Y1597851D01*
G37*
G36*
G01X1427895Y1627929D02*
X1425131D01*
X1426513Y1630693D01*
X1427895Y1627929D01*
G37*
G36*
G01X1435485Y1646584D02*
X1437150Y1648558D01*
X1438292Y1645906D01*
X1435485Y1646584D01*
G37*
G36*
G01X1442507Y59724D02*
X1440572Y58603D01*
X1440449Y60599D01*
X1442507Y59724D01*
G37*
G36*
G01X1444884Y690217D02*
X1447600Y689312D01*
X1445789Y687501D01*
X1444884Y690217D01*
G37*
G36*
G01X1449732Y723726D02*
X1451147Y727969D01*
X1453975Y725141D01*
X1449732Y723726D01*
G37*
G36*
G01X1456839Y162536D02*
X1454839Y166536D01*
X1458839D01*
X1456839Y162536D01*
G37*
G36*
G01X1474291Y645066D02*
G02X1501063I13386J0D01*
G01X1474291D01*
G37*
G36*
G01X1478072Y709718D02*
X1480562Y708888D01*
X1478902Y707227D01*
X1478072Y709718D01*
G37*
G36*
G01X1482161Y739414D02*
X1484500Y740584D01*
Y738244D01*
X1482161Y739414D01*
G37*
G36*
G01X1475912Y1684132D02*
X1474721Y1686514D01*
X1477103D01*
X1475912Y1684132D01*
G37*
G36*
G01X1496440Y1734212D02*
X1492440Y1732212D01*
Y1736212D01*
X1496440Y1734212D01*
G37*
G36*
G01X1509220Y126022D02*
Y128022D01*
X1506220Y127022D01*
X1509220Y126022D01*
G37*
G36*
G01X1511051Y645286D02*
G02X1537823I13386J0D01*
G01X1511051D01*
G37*
G36*
G01X1511286Y709854D02*
X1513927Y708973D01*
X1512167Y707213D01*
X1511286Y709854D01*
G37*
G36*
G01X1515243Y739414D02*
X1517250Y740417D01*
Y738411D01*
X1515243Y739414D01*
G37*
G36*
G01X1534578Y548384D02*
X1537578Y546884D01*
X1534578Y545384D01*
Y548384D01*
G37*
G36*
G01X1535504Y1575491D02*
Y1578491D01*
X1542244D01*
Y1571431D01*
X1539244D01*
Y1575491D01*
X1535504D01*
G37*
G36*
G01X1551213Y309151D02*
X1547220Y308917D01*
X1549451Y305041D01*
X1551213Y309151D01*
G37*
G36*
G01X1552568Y591453D02*
X1550377Y587071D01*
X1548186Y591453D01*
X1552568D01*
G37*
G36*
G01X1543738Y709475D02*
X1546435Y708575D01*
X1544638Y706778D01*
X1543738Y709475D01*
G37*
G36*
G01X1548043Y739414D02*
X1551000Y740892D01*
Y737936D01*
X1548043Y739414D01*
G37*
G36*
G01X1561535Y880670D02*
Y867788D01*
X1547590D01*
Y870788D01*
X1558535D01*
Y880670D01*
X1561535D01*
G37*
G36*
G01X1569502Y209250D02*
X1573502Y211250D01*
Y207250D01*
X1569502Y209250D01*
G37*
G36*
G01X1568243Y595801D02*
X1570994Y592342D01*
X1566688Y593061D01*
X1568243Y595801D01*
G37*
G36*
G01X1566370Y1734212D02*
X1562370Y1732212D01*
Y1736212D01*
X1566370Y1734212D01*
G37*
G36*
G01D02*
X1562370Y1732212D01*
Y1736212D01*
X1566370Y1734212D01*
G37*
G36*
G01X1576849Y687792D02*
X1579923Y686767D01*
X1577874Y684717D01*
X1576849Y687792D01*
G37*
G36*
G01X1582514Y717474D02*
X1585000Y718717D01*
Y716231D01*
X1582514Y717474D01*
G37*
G36*
G01X1592771Y308101D02*
X1595210Y308145D01*
X1594035Y305683D01*
X1592771Y308101D01*
G37*
G36*
G01X1593845Y530219D02*
X1596609Y531601D01*
Y528837D01*
X1593845Y530219D01*
G37*
G36*
G01X1613801Y566864D02*
X1610972Y564036D01*
X1615215Y562621D01*
X1613801Y566864D01*
G37*
G36*
G01X1609869Y654207D02*
X1612889Y653201D01*
X1610875Y651187D01*
X1609869Y654207D01*
G37*
G36*
G01X1615644Y683705D02*
X1617500Y684633D01*
Y682777D01*
X1615644Y683705D01*
G37*
G36*
G01X1630410Y229912D02*
X1626410Y227912D01*
Y231912D01*
X1630410Y229912D01*
G37*
G36*
G01X1648414Y417124D02*
X1643947Y417337D01*
X1645904Y420826D01*
X1648414Y417124D01*
G37*
G36*
G01X1642389Y634852D02*
X1645197Y633916D01*
X1643324Y632044D01*
X1642389Y634852D01*
G37*
G36*
G01X1646499Y752195D02*
X1644851Y754453D01*
X1647646Y754416D01*
X1646499Y752195D01*
G37*
G36*
G01X1658865Y164845D02*
Y168845D01*
X1662865Y166845D01*
X1658865Y164845D01*
G37*
G36*
G01X1663546Y231735D02*
X1661178Y232450D01*
X1662918Y234190D01*
X1663546Y231735D01*
G37*
G36*
G01X1648443Y664705D02*
X1650500Y665734D01*
Y663676D01*
X1648443Y664705D01*
G37*
G36*
G01X1657209Y1391964D02*
X1654558Y1392848D01*
X1656325Y1394616D01*
X1657209Y1391964D01*
G37*
G36*
G01X1660411Y1434958D02*
X1658599Y1435865D01*
X1660412Y1436772D01*
X1660411Y1434958D01*
G37*
G36*
G01X1660984Y1719067D02*
X1658220Y1717685D01*
Y1720449D01*
X1660984Y1719067D01*
G37*
G36*
G01X1660724Y1732027D02*
X1657960Y1730645D01*
Y1733409D01*
X1660724Y1732027D01*
G37*
G36*
G01X1676406Y752002D02*
X1674568Y754518D01*
X1677684Y754477D01*
X1676406Y752002D01*
G37*
G36*
G01X1663566Y1575491D02*
Y1578491D01*
X1670306D01*
Y1571431D01*
X1667306D01*
Y1575491D01*
X1663566D01*
G37*
G36*
G01X1668101Y1703913D02*
X1664101D01*
X1666101Y1699913D01*
X1668101Y1703913D01*
G37*
G36*
G01X1687899Y203533D02*
G02X1714671I13386J0D01*
G01X1687899D01*
G37*
G36*
G01X1687147Y1392915D02*
X1688887Y1394656D01*
X1689759Y1392044D01*
X1687147Y1392915D01*
G37*
G36*
G01X1687454Y1429440D02*
G02X1714226I13386J0D01*
G01X1687454D01*
G37*
G36*
G01X1684551Y1678913D02*
X1682566Y1674905D01*
X1680154Y1678097D01*
X1684551Y1678913D01*
G37*
G36*
G01X1707208Y418612D02*
X1704208D01*
Y421643D01*
X1701098D01*
Y424643D01*
X1707208D01*
Y418612D01*
G37*
G36*
G01X1705901Y752195D02*
X1704253Y754453D01*
X1707048Y754416D01*
X1705901Y752195D01*
G37*
G36*
G01X1695339Y1719218D02*
X1692483Y1720397D01*
X1694569Y1722210D01*
X1695339Y1719218D01*
G37*
G36*
G01X1718274Y203533D02*
G02X1745046I13386J0D01*
G01X1718274D01*
G37*
G36*
G01X1733831Y9212D02*
X1735831Y5211D01*
X1731831Y5212D01*
X1733831Y9212D01*
G37*
G36*
G01X1733447Y660094D02*
X1731065Y661285D01*
X1733447Y662476D01*
Y660094D01*
G37*
G36*
G01X1735602Y752195D02*
X1733954Y754453D01*
X1736749Y754416D01*
X1735602Y752195D01*
G37*
G36*
G01X1734844Y1713383D02*
X1732080Y1712001D01*
Y1714765D01*
X1734844Y1713383D01*
G37*
G36*
G01X1735104Y1731033D02*
X1732340Y1729651D01*
Y1732415D01*
X1735104Y1731033D01*
G37*
G36*
G01X1752676Y285229D02*
X1748576Y286879D01*
X1752676Y288379D01*
Y285229D01*
G37*
G36*
G01X1743820Y368254D02*
Y366448D01*
X1742014Y367351D01*
X1743820Y368254D01*
G37*
G36*
G01X1740471Y1577957D02*
X1737642Y1575128D01*
X1741885Y1573714D01*
X1740471Y1577957D01*
G37*
G36*
G01X1755440Y120619D02*
X1752203Y118729D01*
X1752635Y122453D01*
X1755440Y120619D01*
G37*
G36*
G01X1757056Y289855D02*
G02X1783828I13386J0D01*
G01X1757056D01*
G37*
G36*
G01X1765435Y752071D02*
X1763666Y754495D01*
X1766666Y754456D01*
X1765435Y752071D01*
G37*
G36*
G01X1756416Y1680456D02*
X1755268Y1682752D01*
X1757564D01*
X1756416Y1680456D01*
G37*
G36*
G01X1767546Y83627D02*
Y89737D01*
X1773577D01*
Y86737D01*
X1770546D01*
Y83627D01*
X1767546D01*
G37*
G36*
G01X1773611Y89691D02*
Y86691D01*
X1770580D01*
Y83581D01*
X1767580D01*
Y89691D01*
X1773611D01*
G37*
G36*
G01X1775996Y1578203D02*
X1773220Y1575324D01*
X1777488Y1573988D01*
X1775996Y1578203D01*
G37*
G36*
G01X1786616Y289855D02*
G02X1813388I13386J0D01*
G01X1786616D01*
G37*
G36*
G01X1794269Y409748D02*
Y411482D01*
X1796004Y410615D01*
X1794269Y409748D01*
G37*
G36*
G01X1794258Y423026D02*
Y424760D01*
X1795993Y423893D01*
X1794258Y423026D01*
G37*
G36*
G01X1798189Y753846D02*
X1794214Y755896D01*
X1798239Y757846D01*
X1798189Y753846D01*
G37*
G36*
G01X1798448Y154807D02*
X1799827Y156186D01*
X1800517Y154117D01*
X1798448Y154807D01*
G37*
G36*
G01X1800441Y166517D02*
X1797510Y167494D01*
X1799464Y169448D01*
X1800441Y166517D01*
G37*
G36*
G01X1807985Y192083D02*
X1809240Y192710D01*
Y191456D01*
X1807985Y192083D01*
G37*
G36*
G01X1798547Y369171D02*
Y373171D01*
X1802547Y371171D01*
X1798547Y369171D01*
G37*
G36*
G01X1803231Y396743D02*
X1807231D01*
X1805231Y392743D01*
X1803231Y396743D01*
G37*
G36*
G01X1837240Y157151D02*
X1840171Y156174D01*
X1838217Y154220D01*
X1837240Y157151D01*
G37*
G36*
G01X1895799Y1791399D02*
X1898799Y1797399D01*
X1901799Y1791399D01*
X1895799D01*
G37*
G36*
G01X1911799Y1217197D02*
X1908799Y1211197D01*
X1905799Y1217197D01*
X1911799D01*
G37*
G36*
G01X1934395Y-20964D02*
X1931395Y-26964D01*
X1928395Y-20964D01*
X1934395D01*
G37*
G36*
G01X1918395Y553238D02*
X1921395Y559238D01*
X1924395Y553238D01*
X1918395D01*
G37*
G36*
G01X1942395Y1171618D02*
X1945395Y1165618D01*
X1939395D01*
X1942395Y1171618D01*
G37*
G36*
G01X1937886Y1791371D02*
X1940886Y1797371D01*
X1943886Y1791371D01*
X1937886D01*
G37*
G36*
G01X1952395Y585416D02*
X1949395Y591416D01*
X1955395D01*
X1952395Y585416D01*
G37*
G36*
G01X1953886Y1217169D02*
X1950886Y1211169D01*
X1947886Y1217169D01*
X1953886D01*
G37*
G36*
G01X1976362Y-20822D02*
X1973362Y-26822D01*
X1970362Y-20822D01*
X1976362D01*
G37*
G36*
G01X1960362Y553380D02*
X1963362Y559380D01*
X1966362Y553380D01*
X1960362D01*
G37*
G36*
G01X1984482Y1171590D02*
X1987482Y1165590D01*
X1981482D01*
X1984482Y1171590D01*
G37*
G36*
G01X1979856Y1791551D02*
X1982856Y1797551D01*
X1985856Y1791551D01*
X1979856D01*
G37*
G36*
G01X2002452Y553390D02*
X2005452Y559390D01*
X2008452Y553390D01*
X2002452D01*
G37*
G36*
G01X1994482Y585388D02*
X1991482Y591388D01*
X1997482D01*
X1994482Y585388D01*
G37*
G36*
G01X1995856Y1217349D02*
X1992856Y1211349D01*
X1989856Y1217349D01*
X1995856D01*
G37*
G36*
G01X2018452Y-20812D02*
X2015452Y-26812D01*
X2012452Y-20812D01*
X2018452D01*
G37*
G36*
G01X2036452Y585568D02*
X2033452Y591568D01*
X2039452D01*
X2036452Y585568D01*
G37*
G36*
G01X2026452Y1171770D02*
X2029452Y1165770D01*
X2023452D01*
X2026452Y1171770D01*
G37*
G36*
G01X2044419Y553532D02*
X2047419Y559532D01*
X2050419Y553532D01*
X2044419D01*
G37*
G36*
G01X2060419Y-20670D02*
X2057419Y-26670D01*
X2054419Y-20670D01*
X2060419D01*
G37*
G36*
G01X2078539Y585540D02*
X2075539Y591540D01*
X2081539D01*
X2078539Y585540D01*
G37*
G36*
G01X2068539Y1171742D02*
X2071539Y1165742D01*
X2065539D01*
X2068539Y1171742D01*
G37*
%LPC*%
G75*
G36*
G01X264402Y282094D02*
X262036Y284553D01*
X261955Y285822D01*
X266855D01*
X266776Y284562D01*
X264402Y282094D01*
G37*
G36*
G01X263564Y281223D02*
X262331Y279941D01*
X262156Y282676D01*
X263564Y281223D01*
G37*
G36*
G01X266487Y279927D02*
X265240Y281223D01*
X266659Y282688D01*
X266487Y279927D01*
G37*
G36*
G01X266155Y278522D02*
G03X264855Y277172I849J-2119D01*
G01X262505Y277222D01*
X262434Y278325D01*
X264402Y280357D01*
X266172Y278529D01*
X266155Y278522D01*
G37*
G54D13*
X326731Y663236D03*
X363731D03*
X754645Y1436735D03*
X1166535Y1422322D03*
X1291146Y1385558D03*
X1320516D03*
X1425533Y601230D03*
X1487677Y649988D03*
X1524437Y650208D03*
X1700840Y1434362D03*
X1770442Y294776D03*
X1800002D03*
G54D14*
X443466Y594259D03*
G54D15*
X1701285Y208455D03*
X1731660D03*
%LPD*%
G75*
G36*
G01X73817Y1673951D02*
X71517D01*
Y1676251D01*
X73817D01*
Y1673951D01*
G37*
G36*
G01X257830Y271222D02*
Y273522D01*
X270980D01*
Y271222D01*
X257830D01*
G37*
G36*
G01X263055Y284022D02*
Y284772D01*
X265755D01*
Y284022D01*
X263055D01*
G37*
G36*
G01X304390Y54008D02*
Y65504D01*
X307539D01*
Y54008D01*
X304390D01*
G37*
G36*
G01X304394Y54005D02*
Y65501D01*
X307543D01*
Y54005D01*
X304394D01*
G37*
G36*
G01X302753Y108256D02*
Y109956D01*
X310553D01*
Y108256D01*
X302753D01*
G37*
G36*
G01Y108253D02*
Y109953D01*
X310553D01*
Y108253D01*
X302753D01*
G37*
G36*
G01X379698Y247764D02*
Y250913D01*
X391194D01*
Y247764D01*
X379698D01*
G37*
G36*
G01X379695Y247760D02*
Y250909D01*
X391191D01*
Y247760D01*
X379695D01*
G37*
G36*
G01X738971Y73490D02*
Y84986D01*
X742120D01*
Y73490D01*
X738971D01*
G37*
G36*
G01D02*
Y84986D01*
X742120D01*
Y73490D01*
X738971D01*
G37*
G36*
G01X738970D02*
Y84986D01*
X742119D01*
Y73490D01*
X738970D01*
G37*
G36*
G01X741927Y122619D02*
Y130419D01*
X743627D01*
Y122619D01*
X741927D01*
G37*
G36*
G01D02*
Y130419D01*
X743627D01*
Y122619D01*
X741927D01*
G37*
G36*
G01X741926D02*
Y130419D01*
X743626D01*
Y122619D01*
X741926D01*
G37*
G36*
G01X840604Y248473D02*
Y251622D01*
X852100D01*
Y248473D01*
X840604D01*
G37*
G36*
G01X1018124Y165114D02*
Y166814D01*
X1025924D01*
Y165114D01*
X1018124D01*
G37*
G36*
G01X1129008Y1562087D02*
X1130308D01*
Y1559087D01*
X1129008D01*
Y1562087D01*
G37*
G36*
G01X1676897Y379850D02*
Y391346D01*
X1680046D01*
Y379850D01*
X1676897D01*
G37*
G36*
G01X1776031Y55335D02*
Y66831D01*
X1779180D01*
Y55335D01*
X1776031D01*
G37*
G36*
G01X1776065Y55289D02*
Y66785D01*
X1779214D01*
Y55289D01*
X1776065D01*
G37*
G36*
G01X1772844Y109423D02*
Y111123D01*
X1780644D01*
Y109423D01*
X1772844D01*
G37*
G36*
G01X1772878Y109377D02*
Y111077D01*
X1780678D01*
Y109377D01*
X1772878D01*
G37*
G54D10*
G01X228952Y262804D02*
X234152D01*
X234052Y263504D01*
X233952Y263804D01*
X233752Y264204D01*
X233452Y264604D01*
X232952Y265004D01*
X232552Y265204D01*
X232252Y265304D01*
X231752Y265404D01*
X231352D01*
X230852Y265304D01*
X230552Y265204D01*
X230152Y265004D01*
X229752Y264704D01*
X229652Y264604D01*
X229352Y264204D01*
X229152Y263804D01*
X229052Y263504D01*
X228952Y262904D01*
Y262604D01*
X229052Y262104D01*
X229152Y261804D01*
X229352Y261404D01*
X229652Y261004D01*
X230152Y260604D01*
X230552Y260404D01*
X230852Y260304D01*
X231452Y260204D01*
X231552D01*
X232252Y260304D01*
X232552Y260404D01*
X232752Y260504D01*
X233352Y260904D01*
X233752Y261404D01*
G01X228252Y286604D02*
X230752D01*
G02Y281604I0J-2500D01*
G01X228252D01*
G01Y286604D02*
Y276504D01*
G01X235452Y264504D02*
X236552Y265104D01*
Y260104D01*
G01X239162Y278904D02*
G03I-2410J0D01*
G01X234352Y286604D02*
Y276504D01*
G01X384571Y930646D02*
Y930647D01*
G54D11*
G01X402803Y1446625D02*
X401633Y1447405D01*
X400268Y1447925D01*
X398708D01*
X396953Y1447145D01*
X395588Y1445845D01*
X394613Y1444285D01*
X393833Y1441685D01*
X393638Y1439345D01*
X394028Y1437005D01*
X394613Y1435445D01*
X395783Y1433885D01*
X397148Y1432845D01*
X398513Y1432325D01*
X399878D01*
X401243Y1432845D01*
X402413Y1433625D01*
X403388Y1434665D01*
G01X412513Y1432325D02*
Y1447925D01*
X417193D01*
X418753Y1447145D01*
X419923Y1445325D01*
X420313Y1443245D01*
X419923Y1441165D01*
X418948Y1439605D01*
X417193Y1438825D01*
X412513D01*
G01X430023Y1447925D02*
Y1436745D01*
X430803Y1434405D01*
X432363Y1432845D01*
X434313Y1432325D01*
X436263Y1432845D01*
X437823Y1434405D01*
X438603Y1436745D01*
Y1447925D01*
G01X452213Y1432325D02*
Y1447925D01*
X449873Y1444805D01*
G01Y1432325D02*
X454553D01*
G01X1441478Y1452882D02*
X1440308Y1453662D01*
X1438943Y1454182D01*
X1437383D01*
X1435628Y1453402D01*
X1434263Y1452102D01*
X1433288Y1450542D01*
X1432508Y1447942D01*
X1432313Y1445602D01*
X1432703Y1443262D01*
X1433288Y1441702D01*
X1434458Y1440142D01*
X1435823Y1439102D01*
X1437188Y1438582D01*
X1438553D01*
X1439918Y1439102D01*
X1441088Y1439882D01*
X1442063Y1440922D01*
G01X1451188Y1438582D02*
Y1454182D01*
X1455868D01*
X1457428Y1453402D01*
X1458598Y1451582D01*
X1458988Y1449502D01*
X1458598Y1447422D01*
X1457623Y1445862D01*
X1455868Y1445082D01*
X1451188D01*
G01X1468698Y1454182D02*
Y1443002D01*
X1469478Y1440662D01*
X1471038Y1439102D01*
X1472988Y1438582D01*
X1474938Y1439102D01*
X1476498Y1440662D01*
X1477278Y1443002D01*
Y1454182D01*
G01X1490888D02*
X1489328Y1453662D01*
X1488158Y1452362D01*
X1487378Y1450802D01*
X1486793Y1448722D01*
X1486598Y1446382D01*
X1486793Y1444042D01*
X1487378Y1441962D01*
X1488158Y1440402D01*
X1489328Y1439102D01*
X1490888Y1438582D01*
X1492448Y1439102D01*
X1493618Y1440402D01*
X1494398Y1441962D01*
X1494983Y1444042D01*
X1495178Y1446382D01*
X1494983Y1448722D01*
X1494398Y1450802D01*
X1493618Y1452362D01*
X1492448Y1453662D01*
X1490888Y1454182D01*
G54D12*
G01X-476840Y-884638D02*
Y2768362D01*
X5911000D01*
Y-884638D01*
X-476840D01*
G01X8000Y-625138D02*
Y-630138D01*
G01X6543Y-625138D02*
X9457D01*
G01X14367Y-630138D02*
X11833D01*
Y-625138D01*
X14367D01*
G01X13353Y-627555D02*
X11833D01*
G01X16933Y-625138D02*
Y-630138D01*
X19467D01*
G01X23300Y-630305D02*
X23173Y-630221D01*
Y-630055D01*
X23300Y-629971D01*
X23427Y-630055D01*
Y-630221D01*
X23300Y-630305D01*
G01Y-628055D02*
X23173Y-627971D01*
Y-627805D01*
X23300Y-627721D01*
X23427Y-627805D01*
Y-627971D01*
X23300Y-628055D01*
G01X28083Y-631805D02*
X27450Y-630971D01*
X27133Y-630138D01*
Y-626805D01*
X27450Y-625971D01*
X28083Y-625138D01*
G01X33500D02*
X32993Y-625305D01*
X32613Y-625721D01*
X32360Y-626221D01*
X32170Y-626888D01*
X32107Y-627638D01*
X32170Y-628388D01*
X32360Y-629055D01*
X32613Y-629555D01*
X32993Y-629971D01*
X33500Y-630138D01*
X34007Y-629971D01*
X34387Y-629555D01*
X34640Y-629055D01*
X34830Y-628388D01*
X34893Y-627638D01*
X34830Y-626888D01*
X34640Y-626221D01*
X34387Y-625721D01*
X34007Y-625305D01*
X33500Y-625138D01*
G01X37207Y-629138D02*
X37587Y-629721D01*
X38093Y-630055D01*
X38663Y-630138D01*
X39170Y-630055D01*
X39677Y-629638D01*
X39993Y-629138D01*
X40057Y-628638D01*
X39930Y-628055D01*
X39487Y-627638D01*
X39043Y-627471D01*
X38473D01*
G01X39043D02*
X39423Y-627221D01*
X39740Y-626805D01*
X39867Y-626305D01*
X39740Y-625805D01*
X39423Y-625388D01*
X38853Y-625138D01*
X38283Y-625221D01*
X37713Y-625555D01*
G01X44017Y-631805D02*
X44650Y-630971D01*
X44967Y-630138D01*
Y-626805D01*
X44650Y-625971D01*
X44017Y-625138D01*
G01X47407Y-629138D02*
X47787Y-629721D01*
X48293Y-630055D01*
X48863Y-630138D01*
X49370Y-630055D01*
X49877Y-629638D01*
X50193Y-629138D01*
X50257Y-628638D01*
X50130Y-628055D01*
X49687Y-627638D01*
X49243Y-627471D01*
X48673D01*
G01X49243D02*
X49623Y-627221D01*
X49940Y-626805D01*
X50067Y-626305D01*
X49940Y-625805D01*
X49623Y-625388D01*
X49053Y-625138D01*
X48483Y-625221D01*
X47913Y-625555D01*
G01X52697Y-625971D02*
X53077Y-625471D01*
X53520Y-625221D01*
X54027Y-625138D01*
X54660Y-625305D01*
X55103Y-625721D01*
X55230Y-626221D01*
X55167Y-626721D01*
X54913Y-627138D01*
X53647Y-627971D01*
X53077Y-628555D01*
X52697Y-629388D01*
X52570Y-630138D01*
X55230D01*
G01X58873D02*
X59000Y-629055D01*
X59190Y-628138D01*
X59443Y-627305D01*
X59760Y-626388D01*
X60267Y-625138D01*
X57733D01*
G01X63277Y-628471D02*
X64923D01*
G01X67997Y-625971D02*
X68377Y-625471D01*
X68820Y-625221D01*
X69327Y-625138D01*
X69960Y-625305D01*
X70403Y-625721D01*
X70530Y-626221D01*
X70467Y-626721D01*
X70213Y-627138D01*
X68947Y-627971D01*
X68377Y-628555D01*
X67997Y-629388D01*
X67870Y-630138D01*
X70530D01*
G01X72907Y-629138D02*
X73287Y-629721D01*
X73793Y-630055D01*
X74363Y-630138D01*
X74870Y-630055D01*
X75377Y-629638D01*
X75693Y-629138D01*
X75757Y-628638D01*
X75630Y-628055D01*
X75187Y-627638D01*
X74743Y-627471D01*
X74173D01*
G01X74743D02*
X75123Y-627221D01*
X75440Y-626805D01*
X75567Y-626305D01*
X75440Y-625805D01*
X75123Y-625388D01*
X74553Y-625138D01*
X73983Y-625221D01*
X73413Y-625555D01*
G01X80160Y-630138D02*
Y-625138D01*
X77817Y-628721D01*
X80983D01*
G01X83107Y-629388D02*
X83487Y-629805D01*
X83930Y-630055D01*
X84500Y-630138D01*
X85070Y-629971D01*
X85513Y-629638D01*
X85830Y-629055D01*
X85893Y-628388D01*
X85767Y-627721D01*
X85450Y-627305D01*
X85007Y-626971D01*
X84563Y-626888D01*
X84120Y-626971D01*
X83550Y-627305D01*
X83740Y-625138D01*
X85450D01*
G01X93497Y-630138D02*
Y-625138D01*
X95903D01*
G01X95017Y-627555D02*
X93497D01*
G01X98217Y-630138D02*
X99800Y-625138D01*
X101383Y-630138D01*
G01X100813Y-628388D02*
X98787D01*
G01X103570Y-630138D02*
X106230Y-625138D01*
G01X103570D02*
X106230Y-630138D01*
G01X110000Y-630305D02*
X109873Y-630221D01*
Y-630055D01*
X110000Y-629971D01*
X110127Y-630055D01*
Y-630221D01*
X110000Y-630305D01*
G01Y-628055D02*
X109873Y-627971D01*
Y-627805D01*
X110000Y-627721D01*
X110127Y-627805D01*
Y-627971D01*
X110000Y-628055D01*
G01X114783Y-631805D02*
X114150Y-630971D01*
X113833Y-630138D01*
Y-626805D01*
X114150Y-625971D01*
X114783Y-625138D01*
G01X120200D02*
X119693Y-625305D01*
X119313Y-625721D01*
X119060Y-626221D01*
X118870Y-626888D01*
X118807Y-627638D01*
X118870Y-628388D01*
X119060Y-629055D01*
X119313Y-629555D01*
X119693Y-629971D01*
X120200Y-630138D01*
X120707Y-629971D01*
X121087Y-629555D01*
X121340Y-629055D01*
X121530Y-628388D01*
X121593Y-627638D01*
X121530Y-626888D01*
X121340Y-626221D01*
X121087Y-625721D01*
X120707Y-625305D01*
X120200Y-625138D01*
G01X123907Y-629138D02*
X124287Y-629721D01*
X124793Y-630055D01*
X125363Y-630138D01*
X125870Y-630055D01*
X126377Y-629638D01*
X126693Y-629138D01*
X126757Y-628638D01*
X126630Y-628055D01*
X126187Y-627638D01*
X125743Y-627471D01*
X125173D01*
G01X125743D02*
X126123Y-627221D01*
X126440Y-626805D01*
X126567Y-626305D01*
X126440Y-625805D01*
X126123Y-625388D01*
X125553Y-625138D01*
X124983Y-625221D01*
X124413Y-625555D01*
G01X130717Y-631805D02*
X131350Y-630971D01*
X131667Y-630138D01*
Y-626805D01*
X131350Y-625971D01*
X130717Y-625138D01*
G01X134107Y-629138D02*
X134487Y-629721D01*
X134993Y-630055D01*
X135563Y-630138D01*
X136070Y-630055D01*
X136577Y-629638D01*
X136893Y-629138D01*
X136957Y-628638D01*
X136830Y-628055D01*
X136387Y-627638D01*
X135943Y-627471D01*
X135373D01*
G01X135943D02*
X136323Y-627221D01*
X136640Y-626805D01*
X136767Y-626305D01*
X136640Y-625805D01*
X136323Y-625388D01*
X135753Y-625138D01*
X135183Y-625221D01*
X134613Y-625555D01*
G01X139523Y-629555D02*
X139967Y-629971D01*
X140473Y-630138D01*
X140980Y-629971D01*
X141423Y-629471D01*
X141740Y-628721D01*
X141867Y-627971D01*
Y-627055D01*
X141740Y-626305D01*
X141423Y-625638D01*
X141043Y-625305D01*
X140600Y-625138D01*
X140093Y-625305D01*
X139713Y-625638D01*
X139460Y-626138D01*
X139333Y-626805D01*
X139460Y-627388D01*
X139777Y-627971D01*
X140157Y-628305D01*
X140600Y-628388D01*
X141107Y-628221D01*
X141487Y-627805D01*
X141867Y-627055D01*
G01X145573Y-630138D02*
X145700Y-629055D01*
X145890Y-628138D01*
X146143Y-627305D01*
X146460Y-626388D01*
X146967Y-625138D01*
X144433D01*
G01X149977Y-628471D02*
X151623D01*
G01X154507Y-629138D02*
X154887Y-629721D01*
X155393Y-630055D01*
X155963Y-630138D01*
X156470Y-630055D01*
X156977Y-629638D01*
X157293Y-629138D01*
X157357Y-628638D01*
X157230Y-628055D01*
X156787Y-627638D01*
X156343Y-627471D01*
X155773D01*
G01X156343D02*
X156723Y-627221D01*
X157040Y-626805D01*
X157167Y-626305D01*
X157040Y-625805D01*
X156723Y-625388D01*
X156153Y-625138D01*
X155583Y-625221D01*
X155013Y-625555D01*
G01X159797Y-628055D02*
X160240Y-627471D01*
X160620Y-627138D01*
X161127Y-626971D01*
X161570Y-627138D01*
X161887Y-627471D01*
X162140Y-627971D01*
X162203Y-628555D01*
X162140Y-629055D01*
X161887Y-629555D01*
X161507Y-629971D01*
X161063Y-630138D01*
X160557Y-629971D01*
X160113Y-629471D01*
X159860Y-628721D01*
X159797Y-627888D01*
X159923Y-626805D01*
X160113Y-626221D01*
X160430Y-625638D01*
X160873Y-625221D01*
X161317Y-625138D01*
X161760Y-625305D01*
X162077Y-625721D01*
G01X166100Y-630138D02*
Y-625138D01*
X165340Y-626138D01*
G01Y-630138D02*
X166860D01*
G01X171960D02*
Y-625138D01*
X169617Y-628721D01*
X172783D01*
G01X-4000Y-560138D02*
Y-635138D01*
X496000D01*
Y-560138D01*
X-4000D01*
G01X2306Y311361D02*
G03X0Y305794I5567J-5567D01*
G01Y54252D01*
G03X7874Y46378I7874J0D01*
G01X43709D01*
G02X51583Y38504I0J-7874D01*
G01Y1969D01*
G03X53551Y0I1968J0D01*
G01X319693D01*
G03X321661Y1969I0J1969D01*
G01Y38504D01*
G02X329535Y46378I7874J0D01*
G01X488591D01*
G02X496465Y38504I0J-7874D01*
G01Y22756D01*
G03X498433Y20787I1968J-1D01*
G01X764575D01*
G03X766543Y22756I-1J1969D01*
G01Y38504D01*
G02X774417Y46378I7874J0D01*
G01X871260D01*
G03X879134Y54252I0J7874D01*
G01Y134331D01*
G02X887008Y142205I7874J0D01*
G01X1011024D01*
G02X1018898Y134331I0J-7874D01*
G01Y54252D01*
G03X1026772Y46378I7874J0D01*
G01X1518118D01*
G02X1525992Y38504I0J-7874D01*
G01Y1969D01*
G03X1527961Y0I1969J0D01*
G01X1794102D01*
G03X1796071Y1969I0J1969D01*
G01Y38504D01*
G02X1803945Y46378I7874J0D01*
G01X1849606D01*
G03X1857480Y54252I0J7874D01*
G01Y305794D01*
G03X1855174Y311361I-7873J0D01*
G01X1846007Y320528D01*
G02X1843701Y326096I5568J5568D01*
G01Y1593983D01*
G03X1841395Y1599550I-7873J0D01*
G01X1834196Y1606749D01*
G02X1831890Y1612317I5568J5568D01*
G01Y1732244D01*
G03X1824016Y1740118I-7874J0D01*
G01X1091791D01*
G03X1089823Y1738150I0J-1968D01*
G01Y1736890D01*
G02X1087854Y1734921I-1969J0D01*
G01X769705D01*
G02X767736Y1736890I0J1969D01*
G01Y1738150D01*
G03X765768Y1740118I-1968J0D01*
G01X33465D01*
G03X25591Y1732244I0J-7874D01*
G01Y1612317D01*
G02X23284Y1606749I-7875J1D01*
G01X10180Y1593645D01*
G03X7874Y1588077I5568J-5568D01*
G01Y320191D01*
G02X5568Y314623I-7874J0D01*
G01X2306Y311361D01*
G01X38583Y87795D02*
G02X16535I-11024J0D01*
G02X38583I11024J0D01*
G01X34390Y1533228D02*
G02X19705I-7342J0D01*
G02X34390I7343J0D01*
G01X51732Y631890D02*
G02X29685I-11024J0D01*
G02X51732I11023J0D01*
G01Y1368898D02*
G02X29685I-11024J0D01*
G02X51732I11023J0D01*
G01X52141Y119148D02*
X56741Y123451D01*
G02X65079Y114538I4169J-4456D01*
G01X60479Y110235D01*
G02X52141Y119148I-4169J4456D01*
G01X40157Y1714961D02*
G02X62205I11024J0D01*
G02X40157I-11024J0D01*
G01X86933Y1369350D02*
G02X72248I-7343J0D01*
G02X86933I7342J0D01*
G01X137618Y605378D02*
G02X98248I-19685J0D01*
G02X137618I19685J0D01*
G01X146929Y1482244D02*
G02X129213I-8858J0D01*
G02X146929I8858J0D01*
G01X144626Y1533228D02*
G02X129941I-7343J0D01*
G02X144626I7342J0D01*
G01X172520Y1593661D02*
G02X154803I-8858J0D01*
G02X172520I8859J0D01*
G01X157728Y294335D02*
G02X197098I19685J0D01*
G01Y260083D01*
G02X157728I-19685J0D01*
G01Y294335D01*
G01X191000Y-560138D02*
Y-635138D01*
G01Y-610138D02*
X294000D01*
Y-585138D01*
G01X191000D02*
X294000D01*
G01X222760Y658012D02*
G02X208075I-7342J0D01*
G02X222760I7343J0D01*
G01X230121Y335725D02*
X233820Y339273D01*
G01X230039Y335873D02*
X233773Y339455D01*
G01X229956Y336021D02*
X233726Y339639D01*
G01X229873Y336169D02*
X233680Y339821D01*
G01X229791Y336317D02*
X233634Y340003D01*
G01X229708Y336465D02*
X233587Y340186D01*
G01X229626Y336613D02*
X233549Y340377D01*
G01X229556Y336774D02*
X233533Y340589D01*
G01X229491Y336938D02*
X233516Y340800D01*
G01X229425Y337102D02*
X233500Y341011D01*
G01X229359Y337266D02*
X233484Y341223D01*
G01X229293Y337430D02*
X233467Y341434D01*
G01X229228Y337595D02*
X233486Y341679D01*
G01X229171Y337767D02*
X233512Y341931D01*
G01X229120Y337946D02*
X233539Y342184D01*
G01X229069Y338124D02*
X233565Y342437D01*
G01X229019Y338303D02*
X233592Y342690D01*
G01X228968Y338482D02*
X233679Y343001D01*
G01X228918Y338661D02*
X233775Y343320D01*
G01X228880Y338852D02*
X233872Y343640D01*
G01X228843Y339044D02*
X234017Y344007D01*
G01X228806Y339235D02*
X234253Y344460D01*
G01X228769Y339427D02*
X234566Y344987D01*
G01X240581Y350986D02*
X228733Y339620D01*
G01X240372Y351011D02*
X228708Y339823D01*
G01X240162Y351037D02*
X228684Y340026D01*
G01X230121Y335725D02*
X233820Y339273D01*
G01X230039Y335873D02*
X233773Y339455D01*
G01X229956Y336021D02*
X233726Y339639D01*
G01X229873Y336169D02*
X233680Y339821D01*
G01X229791Y336317D02*
X233634Y340003D01*
G01X229708Y336465D02*
X233587Y340186D01*
G01X229626Y336613D02*
X233549Y340377D01*
G01X229556Y336774D02*
X233533Y340589D01*
G01X229491Y336938D02*
X233516Y340800D01*
G01X229425Y337102D02*
X233500Y341011D01*
G01X229359Y337266D02*
X233484Y341223D01*
G01X229293Y337430D02*
X233467Y341434D01*
G01X229228Y337595D02*
X233486Y341679D01*
G01X229171Y337767D02*
X233512Y341931D01*
G01X229120Y337946D02*
X233539Y342184D01*
G01X229069Y338124D02*
X233565Y342437D01*
G01X229019Y338303D02*
X233592Y342690D01*
G01X228968Y338482D02*
X233679Y343001D01*
G01X228918Y338661D02*
X233775Y343320D01*
G01X228880Y338852D02*
X233872Y343640D01*
G01X228843Y339044D02*
X234017Y344007D01*
G01X228806Y339235D02*
X234253Y344460D01*
G01X228769Y339427D02*
X234566Y344987D01*
G01X240581Y350986D02*
X228733Y339620D01*
G01X240372Y351011D02*
X228708Y339823D01*
G01X240162Y351037D02*
X228684Y340026D01*
G01X239952Y351064D02*
X228659Y340230D01*
G01X239732Y351080D02*
X228633Y340433D01*
G01X239504Y351089D02*
X228620Y340647D01*
G01X239277Y351098D02*
X228606Y340861D01*
G01X239049Y351106D02*
X228592Y341074D01*
G01X238822Y351115D02*
X228585Y341296D01*
G01X238576Y351106D02*
X228581Y341518D01*
G01X238328Y351096D02*
X228586Y341750D01*
G01X238079Y351084D02*
X228597Y341988D01*
G01X237830Y351073D02*
X228608Y342226D01*
G01X237582Y351062D02*
X228619Y342464D01*
G01X237305Y351023D02*
X228653Y342723D01*
G01X237027Y350984D02*
X228690Y342986D01*
G01X236749Y350945D02*
X228727Y343249D01*
G01X236472Y350906D02*
X228781Y343528D01*
G01X236160Y350834D02*
X228851Y343822D01*
G01X239952Y351064D02*
X228659Y340230D01*
G01X239732Y351080D02*
X228633Y340433D01*
G01X239504Y351089D02*
X228620Y340647D01*
G01X239277Y351098D02*
X228606Y340861D01*
G01X239049Y351106D02*
X228592Y341074D01*
G01X238822Y351115D02*
X228585Y341296D01*
G01X238576Y351106D02*
X228581Y341518D01*
G01X238328Y351096D02*
X228586Y341750D01*
G01X238079Y351084D02*
X228597Y341988D01*
G01X237830Y351073D02*
X228608Y342226D01*
G01X237582Y351062D02*
X228619Y342464D01*
G01X237305Y351023D02*
X228653Y342723D01*
G01X237027Y350984D02*
X228690Y342986D01*
G01X236749Y350945D02*
X228727Y343249D01*
G01X236472Y350906D02*
X228781Y343528D01*
G01X236160Y350834D02*
X228851Y343822D01*
G01X230416Y335326D02*
X234023Y338787D01*
G01X230314Y335456D02*
X233952Y338946D01*
G01X230213Y335586D02*
X233881Y339105D01*
G01X230416Y335326D02*
X234023Y338787D01*
G01X230314Y335456D02*
X233952Y338946D01*
G01X230213Y335586D02*
X233881Y339105D01*
G01X235844Y350757D02*
X228921Y344116D01*
G01X235526Y350680D02*
X229017Y344436D01*
G01X235180Y350576D02*
X229131Y344772D01*
G01X234807Y350444D02*
X229249Y345113D01*
G01X234432Y350312D02*
X229428Y345511D01*
G01X233977Y350103D02*
X229609Y345912D01*
G01X235844Y350757D02*
X228921Y344116D01*
G01X235526Y350680D02*
X229017Y344436D01*
G01X235180Y350576D02*
X229131Y344772D01*
G01X234807Y350444D02*
X229249Y345113D01*
G01X234432Y350312D02*
X229428Y345511D01*
G01X233977Y350103D02*
X229609Y345912D01*
G01X233509Y349882D02*
X229892Y346411D01*
G01X233509Y349882D02*
X229892Y346411D01*
G01X232881Y349506D02*
X230272Y347003D01*
G01X232881Y349506D02*
X230272Y347003D01*
G01X247177Y191535D02*
X253476D01*
G02Y178937I0J-6299D01*
G01X247177D01*
G02Y191535I0J6299D01*
G01X245034Y329810D02*
X246923Y331622D01*
G01X244866Y329875D02*
X246787Y331717D01*
G01X244698Y329940D02*
X246651Y331814D01*
G01X244529Y330006D02*
X246515Y331911D01*
G01X244361Y330072D02*
X246378Y332007D01*
G01X244192Y330138D02*
X246242Y332105D01*
G01X244024Y330203D02*
X246106Y332200D01*
G01X243855Y330268D02*
X245970Y332297D01*
G01X243686Y330333D02*
X245834Y332394D01*
G01X243517Y330398D02*
X245698Y332490D01*
G01X243348Y330464D02*
X245562Y332587D01*
G01X243179Y330529D02*
X245426Y332684D01*
G01X243009Y330594D02*
X245289Y332780D01*
G01X242840Y330658D02*
X245153Y332877D01*
G01X242669Y330721D02*
X245017Y332973D01*
G01X244881Y333070D02*
X242499Y330786D01*
G01X242329Y330850D02*
X244745Y333167D01*
G01X242159Y330914D02*
X247232Y335780D01*
G01X241988Y330976D02*
X247522Y336286D01*
G01X241817Y331040D02*
X247771Y336752D01*
G01X241645Y331102D02*
X247918Y337120D01*
G01X241473Y331165D02*
X248064Y337487D01*
G01X245034Y329810D02*
X246923Y331622D01*
G01X244866Y329875D02*
X246787Y331717D01*
G01X244698Y329940D02*
X246651Y331814D01*
G01X244529Y330006D02*
X246515Y331911D01*
G01X244361Y330072D02*
X246378Y332007D01*
G01X244192Y330138D02*
X246242Y332105D01*
G01X244024Y330203D02*
X246106Y332200D01*
G01X243855Y330268D02*
X245970Y332297D01*
G01X243686Y330333D02*
X245834Y332394D01*
G01X243517Y330398D02*
X245698Y332490D01*
G01X243348Y330464D02*
X245562Y332587D01*
G01X243179Y330529D02*
X245426Y332684D01*
G01X243009Y330594D02*
X245289Y332780D01*
G01X242840Y330658D02*
X245153Y332877D01*
G01X242669Y330721D02*
X245017Y332973D01*
G01X244881Y333070D02*
X242499Y330786D01*
G01X242329Y330850D02*
X244745Y333167D01*
G01X242159Y330914D02*
X247232Y335780D01*
G01X241988Y330976D02*
X247522Y336286D01*
G01X241817Y331040D02*
X247771Y336752D01*
G01X241645Y331102D02*
X247918Y337120D01*
G01X241473Y331165D02*
X248064Y337487D01*
G01X235912Y331965D02*
X239553Y335458D01*
G01X235728Y332015D02*
X239286Y335428D01*
G01X235545Y332067D02*
X239018Y335399D01*
G01X235360Y332117D02*
X238750Y335369D01*
G01X235176Y332167D02*
X238512Y335368D01*
G01X234992Y332219D02*
X238303Y335394D01*
G01X234808Y332269D02*
X238093Y335420D01*
G01X234633Y332329D02*
X237883Y335446D01*
G01X234466Y332395D02*
X237673Y335472D01*
G01X234298Y332461D02*
X237479Y335513D01*
G01X234131Y332528D02*
X237311Y335578D01*
G01X233963Y332594D02*
X237142Y335644D01*
G01X233796Y332661D02*
X236974Y335709D01*
G01X233628Y332727D02*
X236805Y335775D01*
G01X233477Y332809D02*
X236636Y335840D01*
G01X233326Y332892D02*
X236483Y335921D01*
G01X233175Y332974D02*
X236344Y336015D01*
G01X233024Y333057D02*
X236206Y336109D01*
G01X232873Y333140D02*
X236067Y336203D01*
G01X232722Y333222D02*
X235928Y336297D01*
G01X232577Y333310D02*
X235789Y336391D01*
G01X232442Y333408D02*
X235655Y336489D01*
G01X232308Y333506D02*
X235540Y336606D01*
G01X232173Y333603D02*
X235425Y336724D01*
G01X232038Y333702D02*
X235311Y336841D01*
G01X231904Y333799D02*
X235197Y336958D01*
G01X231769Y333898D02*
X235082Y337076D01*
G01X231643Y334004D02*
X234968Y337193D01*
G01X231524Y334118D02*
X234865Y337322D01*
G01X231405Y334230D02*
X234772Y337460D01*
G01X231286Y334343D02*
X234680Y337599D01*
G01X231167Y334456D02*
X234587Y337737D01*
G01X231048Y334569D02*
X234494Y337875D01*
G01X230928Y334682D02*
X234402Y338014D01*
G01X230821Y334807D02*
X234309Y338152D01*
G01X230720Y334936D02*
X234235Y338309D01*
G01X230618Y335066D02*
X234165Y338468D01*
G01X230517Y335196D02*
X234094Y338627D01*
G01X235912Y331965D02*
X239553Y335458D01*
G01X235728Y332015D02*
X239286Y335428D01*
G01X235545Y332067D02*
X239018Y335399D01*
G01X235360Y332117D02*
X238750Y335369D01*
G01X235176Y332167D02*
X238512Y335368D01*
G01X234992Y332219D02*
X238303Y335394D01*
G01X234808Y332269D02*
X238093Y335420D01*
G01X234633Y332329D02*
X237883Y335446D01*
G01X234466Y332395D02*
X237673Y335472D01*
G01X234298Y332461D02*
X237479Y335513D01*
G01X234131Y332528D02*
X237311Y335578D01*
G01X233963Y332594D02*
X237142Y335644D01*
G01X233796Y332661D02*
X236974Y335709D01*
G01X233628Y332727D02*
X236805Y335775D01*
G01X233477Y332809D02*
X236636Y335840D01*
G01X233326Y332892D02*
X236483Y335921D01*
G01X233175Y332974D02*
X236344Y336015D01*
G01X233024Y333057D02*
X236206Y336109D01*
G01X232873Y333140D02*
X236067Y336203D01*
G01X232722Y333222D02*
X235928Y336297D01*
G01X232577Y333310D02*
X235789Y336391D01*
G01X232442Y333408D02*
X235655Y336489D01*
G01X232308Y333506D02*
X235540Y336606D01*
G01X232173Y333603D02*
X235425Y336724D01*
G01X232038Y333702D02*
X235311Y336841D01*
G01X231904Y333799D02*
X235197Y336958D01*
G01X231769Y333898D02*
X235082Y337076D01*
G01X231643Y334004D02*
X234968Y337193D01*
G01X231524Y334118D02*
X234865Y337322D01*
G01X231405Y334230D02*
X234772Y337460D01*
G01X231286Y334343D02*
X234680Y337599D01*
G01X231167Y334456D02*
X234587Y337737D01*
G01X231048Y334569D02*
X234494Y337875D01*
G01X230928Y334682D02*
X234402Y338014D01*
G01X230821Y334807D02*
X234309Y338152D01*
G01X230720Y334936D02*
X234235Y338309D01*
G01X230618Y335066D02*
X234165Y338468D01*
G01X230517Y335196D02*
X234094Y338627D01*
G01X241301Y331226D02*
X248192Y337837D01*
G01X241127Y331287D02*
X248269Y338138D01*
G01X240953Y331348D02*
X248346Y338440D01*
G01X240777Y331405D02*
X248423Y338740D01*
G01X240600Y331462D02*
X248492Y339034D01*
G01X240417Y331516D02*
X248528Y339296D01*
G01X240217Y331550D02*
X248565Y339558D01*
G01X239987Y331557D02*
X248601Y339820D01*
G01X239757Y331562D02*
X248637Y340081D01*
G01X239527Y331570D02*
X248673Y340343D01*
G01X239297Y331576D02*
X248682Y340580D01*
G01X239066Y331583D02*
X248692Y340816D01*
G01X238836Y331589D02*
X248702Y341052D01*
G01X238611Y331600D02*
X248712Y341290D01*
G01X238396Y331621D02*
X248722Y341527D01*
G01X238180Y331641D02*
X248732Y341763D01*
G01X237964Y331661D02*
X248728Y341986D01*
G01X237749Y331682D02*
X248719Y342206D01*
G01X237533Y331702D02*
X248704Y342418D01*
G01X237317Y331722D02*
X248683Y342626D01*
G01X237113Y331752D02*
X248663Y342833D01*
G01X248637Y343035D02*
X236912Y331787D01*
G01X248604Y343231D02*
X242665Y337533D01*
G01X236712Y331823D02*
X241166Y336096D01*
G01X248572Y343427D02*
X243026Y338108D01*
G01X236512Y331858D02*
X240599Y335779D01*
G01X248538Y343623D02*
X243206Y338507D01*
G01X236312Y331893D02*
X240229Y335652D01*
G01X248501Y343814D02*
X243386Y338907D01*
G01X236111Y331928D02*
X239858Y335523D01*
G01X248455Y343997D02*
X243474Y339219D01*
G01X248410Y344180D02*
X243550Y339518D01*
G01X248363Y344363D02*
X243626Y339818D01*
G01X241301Y331226D02*
X248192Y337837D01*
G01X241127Y331287D02*
X248269Y338138D01*
G01X240953Y331348D02*
X248346Y338440D01*
G01X240777Y331405D02*
X248423Y338740D01*
G01X240600Y331462D02*
X248492Y339034D01*
G01X240417Y331516D02*
X248528Y339296D01*
G01X240217Y331550D02*
X248565Y339558D01*
G01X239987Y331557D02*
X248601Y339820D01*
G01X239757Y331562D02*
X248637Y340081D01*
G01X239527Y331570D02*
X248673Y340343D01*
G01X239297Y331576D02*
X248682Y340580D01*
G01X239066Y331583D02*
X248692Y340816D01*
G01X238836Y331589D02*
X248702Y341052D01*
G01X238611Y331600D02*
X248712Y341290D01*
G01X238396Y331621D02*
X248722Y341527D01*
G01X238180Y331641D02*
X248732Y341763D01*
G01X237964Y331661D02*
X248728Y341986D01*
G01X237749Y331682D02*
X248719Y342206D01*
G01X237533Y331702D02*
X248704Y342418D01*
G01X237317Y331722D02*
X248683Y342626D01*
G01X237113Y331752D02*
X248663Y342833D01*
G01X248637Y343035D02*
X236912Y331787D01*
G01X248604Y343231D02*
X242665Y337533D01*
G01X236712Y331823D02*
X241166Y336096D01*
G01X248572Y343427D02*
X243026Y338108D01*
G01X236512Y331858D02*
X240599Y335779D01*
G01X248538Y343623D02*
X243206Y338507D01*
G01X236312Y331893D02*
X240229Y335652D01*
G01X248501Y343814D02*
X243386Y338907D01*
G01X236111Y331928D02*
X239858Y335523D01*
G01X248455Y343997D02*
X243474Y339219D01*
G01X248410Y344180D02*
X243550Y339518D01*
G01X248363Y344363D02*
X243626Y339818D01*
G01X248317Y344546D02*
X243689Y340106D01*
G01X248265Y344723D02*
X243709Y340353D01*
G01X248205Y344893D02*
X243729Y340599D01*
G01X248146Y345063D02*
X243749Y340846D01*
G01X248085Y345233D02*
X243769Y341092D01*
G01X248026Y345403D02*
X243773Y341323D01*
G01X247966Y345572D02*
X243755Y341533D01*
G01X247893Y345730D02*
X243738Y341744D01*
G01X247818Y345885D02*
X243720Y341954D01*
G01X247743Y346040D02*
X243702Y342165D01*
G01X247668Y346196D02*
X243685Y342375D01*
G01X247594Y346351D02*
X243654Y342572D01*
G01X247518Y346506D02*
X243606Y342754D01*
G01X247432Y346651D02*
X243559Y342936D01*
G01X247341Y346791D02*
X243512Y343118D01*
G01X247250Y346930D02*
X243464Y343299D01*
G01X247158Y347070D02*
X243417Y343480D01*
G01X247067Y347210D02*
X243367Y343660D01*
G01X246975Y347349D02*
X243294Y343817D01*
G01X246884Y347488D02*
X243222Y343975D01*
G01X248317Y344546D02*
X243689Y340106D01*
G01X248265Y344723D02*
X243709Y340353D01*
G01X248205Y344893D02*
X243729Y340599D01*
G01X248146Y345063D02*
X243749Y340846D01*
G01X248085Y345233D02*
X243769Y341092D01*
G01X248026Y345403D02*
X243773Y341323D01*
G01X247966Y345572D02*
X243755Y341533D01*
G01X247893Y345730D02*
X243738Y341744D01*
G01X247818Y345885D02*
X243720Y341954D01*
G01X247743Y346040D02*
X243702Y342165D01*
G01X247668Y346196D02*
X243685Y342375D01*
G01X247594Y346351D02*
X243654Y342572D01*
G01X247518Y346506D02*
X243606Y342754D01*
G01X247432Y346651D02*
X243559Y342936D01*
G01X247341Y346791D02*
X243512Y343118D01*
G01X247250Y346930D02*
X243464Y343299D01*
G01X247158Y347070D02*
X243417Y343480D01*
G01X247067Y347210D02*
X243367Y343660D01*
G01X246975Y347349D02*
X243294Y343817D01*
G01X246884Y347488D02*
X243222Y343975D01*
G01X245370Y329677D02*
X247196Y331428D01*
G01X245202Y329742D02*
X247059Y331524D01*
G01X245370Y329677D02*
X247196Y331428D01*
G01X245202Y329742D02*
X247059Y331524D01*
G01X246776Y347612D02*
X243149Y344133D01*
G01X246666Y347734D02*
X243076Y344290D01*
G01X246557Y347856D02*
X243003Y344447D01*
G01X246447Y347978D02*
X242931Y344605D01*
G01X246337Y348100D02*
X242845Y344750D01*
G01X246227Y348221D02*
X242749Y344885D01*
G01X246117Y348343D02*
X242653Y345020D01*
G01X245997Y348455D02*
X242557Y345155D01*
G01X245872Y348563D02*
X242461Y345290D01*
G01X245746Y348670D02*
X242365Y345425D01*
G01X245622Y348777D02*
X242269Y345561D01*
G01X245496Y348883D02*
X242151Y345675D01*
G01X245371Y348990D02*
X242032Y345787D01*
G01X245238Y349091D02*
X241913Y345901D01*
G01X245101Y349186D02*
X241793Y346013D01*
G01X246776Y347612D02*
X243149Y344133D01*
G01X246666Y347734D02*
X243076Y344290D01*
G01X246557Y347856D02*
X243003Y344447D01*
G01X246447Y347978D02*
X242931Y344605D01*
G01X246337Y348100D02*
X242845Y344750D01*
G01X246227Y348221D02*
X242749Y344885D01*
G01X246117Y348343D02*
X242653Y345020D01*
G01X245997Y348455D02*
X242557Y345155D01*
G01X245872Y348563D02*
X242461Y345290D01*
G01X245746Y348670D02*
X242365Y345425D01*
G01X245622Y348777D02*
X242269Y345561D01*
G01X245496Y348883D02*
X242151Y345675D01*
G01X245371Y348990D02*
X242032Y345787D01*
G01X245238Y349091D02*
X241913Y345901D01*
G01X245101Y349186D02*
X241793Y346013D01*
G01X244964Y349281D02*
X241675Y346127D01*
G01X244827Y349377D02*
X241555Y346239D01*
G01X244689Y349473D02*
X241423Y346339D01*
G01X244552Y349568D02*
X241279Y346429D01*
G01X244405Y349654D02*
X241135Y346517D01*
G01X244255Y349738D02*
X240991Y346607D01*
G01X244105Y349821D02*
X240847Y346696D01*
G01X243955Y349905D02*
X240702Y346784D01*
G01X243805Y349988D02*
X240546Y346862D01*
G01X243654Y350069D02*
X240373Y346923D01*
G01X243489Y350140D02*
X240199Y346983D01*
G01X243326Y350210D02*
X240025Y347044D01*
G01X243163Y350280D02*
X239852Y347104D01*
G01X242999Y350351D02*
X239679Y347166D01*
G01X242836Y350421D02*
X239474Y347197D01*
G01X242662Y350482D02*
X239262Y347220D01*
G01X242484Y350539D02*
X239050Y347244D01*
G01X242306Y350595D02*
X238839Y347269D01*
G01X242128Y350651D02*
X238626Y347292D01*
G01X241950Y350708D02*
X238364Y347268D01*
G01X241765Y350758D02*
X238095Y347237D01*
G01X241572Y350800D02*
X237825Y347206D01*
G01X241378Y350841D02*
X237515Y347135D01*
G01X241185Y350883D02*
X237146Y347009D01*
G01X240992Y350925D02*
X236778Y346882D01*
G01X240792Y350960D02*
X236184Y346540D01*
G01X244964Y349281D02*
X241675Y346127D01*
G01X244827Y349377D02*
X241555Y346239D01*
G01X244689Y349473D02*
X241423Y346339D01*
G01X244552Y349568D02*
X241279Y346429D01*
G01X244405Y349654D02*
X241135Y346517D01*
G01X244255Y349738D02*
X240991Y346607D01*
G01X244105Y349821D02*
X240847Y346696D01*
G01X243955Y349905D02*
X240702Y346784D01*
G01X243805Y349988D02*
X240546Y346862D01*
G01X243654Y350069D02*
X240373Y346923D01*
G01X243489Y350140D02*
X240199Y346983D01*
G01X243326Y350210D02*
X240025Y347044D01*
G01X243163Y350280D02*
X239852Y347104D01*
G01X242999Y350351D02*
X239679Y347166D01*
G01X242836Y350421D02*
X239474Y347197D01*
G01X242662Y350482D02*
X239262Y347220D01*
G01X242484Y350539D02*
X239050Y347244D01*
G01X242306Y350595D02*
X238839Y347269D01*
G01X242128Y350651D02*
X238626Y347292D01*
G01X241950Y350708D02*
X238364Y347268D01*
G01X241765Y350758D02*
X238095Y347237D01*
G01X241572Y350800D02*
X237825Y347206D01*
G01X241378Y350841D02*
X237515Y347135D01*
G01X241185Y350883D02*
X237146Y347009D01*
G01X240992Y350925D02*
X236778Y346882D01*
G01X240792Y350960D02*
X236184Y346540D01*
G01X249233Y329975D02*
X249241Y329982D01*
G01X248910Y329891D02*
X249105Y330078D01*
G01X248587Y329810D02*
X248968Y330175D01*
G01X248265Y329727D02*
X248831Y330271D01*
G01X247942Y329644D02*
X248695Y330367D01*
G01X247619Y329563D02*
X248558Y330464D01*
G01X247296Y329479D02*
X248422Y330560D01*
G01X246974Y329397D02*
X248286Y330656D01*
G01X246650Y329315D02*
X248150Y330752D01*
G01X246376Y329278D02*
X248013Y330849D01*
G01X246209Y329346D02*
X247877Y330946D01*
G01X246041Y329411D02*
X247741Y331041D01*
G01X245873Y329479D02*
X247605Y331139D01*
G01X245706Y329544D02*
X247468Y331235D01*
G01X245538Y329610D02*
X247332Y331332D01*
G01X247619Y329563D02*
X247942Y329644D01*
G01X249233Y329975D02*
X248910Y329891D01*
G01X247296Y329479D02*
X247619Y329563D01*
G01X246974Y329397D02*
X247296Y329479D01*
G01X248587Y329810D02*
X248910Y329891D01*
G01X247942Y329644D02*
X248265Y329727D01*
G01D02*
X248587Y329810D01*
G01X246650Y329315D02*
X246974Y329397D01*
G01X249233Y329975D02*
X249241Y329982D01*
G01X248910Y329891D02*
X249105Y330078D01*
G01X248587Y329810D02*
X248968Y330175D01*
G01X248265Y329727D02*
X248831Y330271D01*
G01X247942Y329644D02*
X248695Y330367D01*
G01X247619Y329563D02*
X248558Y330464D01*
G01X247296Y329479D02*
X248422Y330560D01*
G01X246974Y329397D02*
X248286Y330656D01*
G01X246650Y329315D02*
X248150Y330752D01*
G01X246376Y329278D02*
X248013Y330849D01*
G01X246209Y329346D02*
X247877Y330946D01*
G01X246041Y329411D02*
X247741Y331041D01*
G01X245873Y329479D02*
X247605Y331139D01*
G01X245706Y329544D02*
X247468Y331235D01*
G01X245538Y329610D02*
X247332Y331332D01*
G01X247619Y329563D02*
X247942Y329644D01*
G01X249233Y329975D02*
X248910Y329891D01*
G01X247296Y329479D02*
X247619Y329563D01*
G01X246974Y329397D02*
X247296Y329479D01*
G01X248587Y329810D02*
X248910Y329891D01*
G01X247942Y329644D02*
X248265Y329727D01*
G01D02*
X248587Y329810D01*
G01X246650Y329315D02*
X246974Y329397D01*
G01X259756Y332429D02*
X264433Y336916D01*
G01X259519Y332429D02*
X264480Y337189D01*
G01X259281Y332429D02*
X264528Y337462D01*
G01X259239Y332615D02*
X264577Y337736D01*
G01X259287Y332889D02*
X264625Y338009D01*
G01X259334Y333161D02*
X264673Y338282D01*
G01X259383Y333435D02*
X264720Y338555D01*
G01X258879Y333178D02*
X264769Y338829D01*
G01X258274Y332825D02*
X264817Y339101D01*
G01X257804Y332602D02*
X264865Y339375D01*
G01X257417Y332457D02*
X264913Y339649D01*
G01X257084Y332365D02*
X264960Y339922D01*
G01X256750Y332273D02*
X265009Y340195D01*
G01X256427Y332190D02*
X265057Y340469D01*
G01X256165Y332166D02*
X265105Y340742D01*
G01X255903Y332141D02*
X265153Y341015D01*
G01X255641Y332118D02*
X265201Y341288D01*
G01X255379Y332094D02*
X265249Y341561D01*
G01X255129Y332080D02*
X265297Y341835D01*
G01X254913Y332101D02*
X265345Y342108D01*
G01X254697Y332121D02*
X265393Y342381D01*
G01X254481Y332140D02*
X265441Y342654D01*
G01X265489Y342928D02*
X254265Y332162D01*
G01X259663Y337566D02*
X265537Y343201D01*
G01X254049Y332181D02*
X258731Y336673D01*
G01X259924Y338043D02*
X265585Y343474D01*
G01X253833Y332200D02*
X258270Y336457D01*
G01X253634Y332236D02*
X257946Y336374D01*
G01X253457Y332295D02*
X257634Y336301D01*
G01X253281Y332353D02*
X257379Y336284D01*
G01X253105Y332411D02*
X257125Y336267D01*
G01X252928Y332468D02*
X256886Y336265D01*
G01X252751Y332527D02*
X256664Y336280D01*
G01X252575Y332585D02*
X256443Y336296D01*
G01X252418Y332662D02*
X256242Y336329D01*
G01X252279Y332756D02*
X256056Y336378D01*
G01X252140Y332849D02*
X255870Y336427D01*
G01X252002Y332944D02*
X255707Y336498D01*
G01X251863Y333038D02*
X255559Y336583D01*
G01X251724Y333131D02*
X255410Y336668D01*
G01X251586Y333226D02*
X255286Y336776D01*
G01X251468Y333340D02*
X255177Y336899D01*
G01X251365Y333469D02*
X255069Y337021D01*
G01X251262Y333597D02*
X254978Y337161D01*
G01X251159Y333726D02*
X254908Y337322D01*
G01X251056Y333854D02*
X254838Y337482D01*
G01X250954Y333983D02*
X254775Y337648D01*
G01X250850Y334111D02*
X254742Y337845D01*
G01X250771Y334263D02*
X254709Y338041D01*
G01X250703Y334424D02*
X254677Y338236D01*
G01X250634Y334585D02*
X254669Y338456D01*
G01X250566Y334747D02*
X254671Y338685D01*
G01X250497Y334908D02*
X254673Y338914D01*
G01X250429Y335070D02*
X254675Y339143D01*
G01X250360Y335231D02*
X254709Y339403D01*
G01X250319Y335419D02*
X254742Y339662D01*
G01X250284Y335613D02*
X254776Y339922D01*
G01X250250Y335807D02*
X254810Y340182D01*
G01X250214Y336000D02*
X254858Y340454D01*
G01X250180Y336194D02*
X254906Y340728D01*
G01X250145Y336388D02*
X254953Y341001D01*
G01X250111Y336582D02*
X255002Y341274D01*
G01X250109Y336808D02*
X255050Y341548D01*
G01X250107Y337034D02*
X255098Y341821D01*
G01X250105Y337259D02*
X255145Y342094D01*
G01X250104Y337485D02*
X255193Y342367D01*
G01X250102Y337710D02*
X255242Y342640D01*
G01X250100Y337936D02*
X255289Y342913D01*
G01X255337Y343187D02*
X250108Y338171D01*
G01X255385Y343460D02*
X250140Y338428D01*
G01X255434Y343733D02*
X250171Y338685D01*
G01X255481Y344007D02*
X250202Y338942D01*
G01X255529Y344280D02*
X250233Y339200D01*
G01X255577Y344553D02*
X250265Y339457D01*
G01X255625Y344826D02*
X250296Y339714D01*
G01X255673Y345099D02*
X250339Y339982D01*
G01X259519Y332429D02*
X259756D01*
G01D02*
X259992D01*
G01X259281D02*
X259519D01*
G01X259383Y333435D02*
X259334Y333161D01*
G01X259287Y332889D02*
X259239Y332615D01*
G01X259334Y333161D02*
X259287Y332889D01*
G01X259239Y332615D02*
X259207Y332429D01*
G01D02*
X259281D01*
G01X250387Y340256D02*
X250339Y339982D01*
G01X259756Y332429D02*
X264433Y336916D01*
G01X259519Y332429D02*
X264480Y337189D01*
G01X259281Y332429D02*
X264528Y337462D01*
G01X259239Y332615D02*
X264577Y337736D01*
G01X259287Y332889D02*
X264625Y338009D01*
G01X259334Y333161D02*
X264673Y338282D01*
G01X259383Y333435D02*
X264720Y338555D01*
G01X258879Y333178D02*
X264769Y338829D01*
G01X258274Y332825D02*
X264817Y339101D01*
G01X257804Y332602D02*
X264865Y339375D01*
G01X257417Y332457D02*
X264913Y339649D01*
G01X257084Y332365D02*
X264960Y339922D01*
G01X256750Y332273D02*
X265009Y340195D01*
G01X256427Y332190D02*
X265057Y340469D01*
G01X256165Y332166D02*
X265105Y340742D01*
G01X255903Y332141D02*
X265153Y341015D01*
G01X255641Y332118D02*
X265201Y341288D01*
G01X255379Y332094D02*
X265249Y341561D01*
G01X255129Y332080D02*
X265297Y341835D01*
G01X254913Y332101D02*
X265345Y342108D01*
G01X254697Y332121D02*
X265393Y342381D01*
G01X254481Y332140D02*
X265441Y342654D01*
G01X265489Y342928D02*
X254265Y332162D01*
G01X259663Y337566D02*
X265537Y343201D01*
G01X254049Y332181D02*
X258731Y336673D01*
G01X259924Y338043D02*
X265585Y343474D01*
G01X253833Y332200D02*
X258270Y336457D01*
G01X253634Y332236D02*
X257946Y336374D01*
G01X253457Y332295D02*
X257634Y336301D01*
G01X253281Y332353D02*
X257379Y336284D01*
G01X253105Y332411D02*
X257125Y336267D01*
G01X252928Y332468D02*
X256886Y336265D01*
G01X252751Y332527D02*
X256664Y336280D01*
G01X252575Y332585D02*
X256443Y336296D01*
G01X252418Y332662D02*
X256242Y336329D01*
G01X252279Y332756D02*
X256056Y336378D01*
G01X252140Y332849D02*
X255870Y336427D01*
G01X252002Y332944D02*
X255707Y336498D01*
G01X251863Y333038D02*
X255559Y336583D01*
G01X251724Y333131D02*
X255410Y336668D01*
G01X251586Y333226D02*
X255286Y336776D01*
G01X251468Y333340D02*
X255177Y336899D01*
G01X251365Y333469D02*
X255069Y337021D01*
G01X251262Y333597D02*
X254978Y337161D01*
G01X251159Y333726D02*
X254908Y337322D01*
G01X251056Y333854D02*
X254838Y337482D01*
G01X250954Y333983D02*
X254775Y337648D01*
G01X250850Y334111D02*
X254742Y337845D01*
G01X250771Y334263D02*
X254709Y338041D01*
G01X250703Y334424D02*
X254677Y338236D01*
G01X250634Y334585D02*
X254669Y338456D01*
G01X250566Y334747D02*
X254671Y338685D01*
G01X250497Y334908D02*
X254673Y338914D01*
G01X250429Y335070D02*
X254675Y339143D01*
G01X250360Y335231D02*
X254709Y339403D01*
G01X250319Y335419D02*
X254742Y339662D01*
G01X250284Y335613D02*
X254776Y339922D01*
G01X250250Y335807D02*
X254810Y340182D01*
G01X250214Y336000D02*
X254858Y340454D01*
G01X250180Y336194D02*
X254906Y340728D01*
G01X250145Y336388D02*
X254953Y341001D01*
G01X250111Y336582D02*
X255002Y341274D01*
G01X250109Y336808D02*
X255050Y341548D01*
G01X250107Y337034D02*
X255098Y341821D01*
G01X250105Y337259D02*
X255145Y342094D01*
G01X250104Y337485D02*
X255193Y342367D01*
G01X250102Y337710D02*
X255242Y342640D01*
G01X250100Y337936D02*
X255289Y342913D01*
G01X255337Y343187D02*
X250108Y338171D01*
G01X255385Y343460D02*
X250140Y338428D01*
G01X255434Y343733D02*
X250171Y338685D01*
G01X255481Y344007D02*
X250202Y338942D01*
G01X255529Y344280D02*
X250233Y339200D01*
G01X255577Y344553D02*
X250265Y339457D01*
G01X255625Y344826D02*
X250296Y339714D01*
G01X255673Y345099D02*
X250339Y339982D01*
G01X259519Y332429D02*
X259756D01*
G01D02*
X259992D01*
G01X259281D02*
X259519D01*
G01X259383Y333435D02*
X259334Y333161D01*
G01X259287Y332889D02*
X259239Y332615D01*
G01X259334Y333161D02*
X259287Y332889D01*
G01X259239Y332615D02*
X259207Y332429D01*
G01D02*
X259281D01*
G01X250387Y340256D02*
X250339Y339982D01*
G01X255721Y345372D02*
X250387Y340256D01*
G01X255769Y345646D02*
X250435Y340529D01*
G01X255817Y345919D02*
X250483Y340802D01*
G01X255865Y346192D02*
X250531Y341076D01*
G01X255913Y346466D02*
X250579Y341349D01*
G01X255961Y346738D02*
X250627Y341622D01*
G01X256009Y347012D02*
X250675Y341895D01*
G01X256057Y347285D02*
X250723Y342168D01*
G01X256105Y347559D02*
X250770Y342441D01*
G01X256152Y347831D02*
X250819Y342715D01*
G01X256201Y348104D02*
X250867Y342988D01*
G01X256249Y348378D02*
X250914Y343261D01*
G01X256296Y348651D02*
X250962Y343535D01*
G01X256344Y348925D02*
X251011Y343807D01*
G01X256392Y349197D02*
X251059Y344081D01*
G01X255002Y341274D02*
X255050Y341548D01*
G01X254858Y340454D02*
X254906Y340728D01*
G01X255050Y341548D02*
X255098Y341821D01*
G01X254810Y340182D02*
X254858Y340454D01*
G01X254953Y341001D02*
X255002Y341274D01*
G01X255193Y342367D02*
X255242Y342640D01*
G01X255145Y342094D02*
X255193Y342367D01*
G01X255098Y341821D02*
X255145Y342094D01*
G01X255289Y342913D02*
X255337Y343187D01*
G01D02*
X255385Y343460D01*
G01D02*
X255434Y343733D01*
G01D02*
X255481Y344007D01*
G01D02*
X255529Y344280D01*
G01X254906Y340728D02*
X254953Y341001D01*
G01X250627Y341622D02*
X250579Y341349D01*
G01X250770Y342441D02*
X250723Y342168D01*
G01D02*
X250675Y341895D01*
G01X250914Y343261D02*
X250867Y342988D01*
G01D02*
X250819Y342715D01*
G01D02*
X250770Y342441D01*
G01X250675Y341895D02*
X250627Y341622D01*
G01X250579Y341349D02*
X250531Y341076D01*
G01D02*
X250483Y340802D01*
G01X250962Y343535D02*
X250914Y343261D01*
G01X251011Y343807D02*
X250962Y343535D01*
G01X251059Y344081D02*
X251011Y343807D01*
G01X251106Y344354D02*
X251059Y344081D01*
G01X250483Y340802D02*
X250435Y340529D01*
G01X255289Y342913D02*
X255242Y342640D01*
G01X250435Y340529D02*
X250387Y340256D01*
G01X255721Y345372D02*
X250387Y340256D01*
G01X255769Y345646D02*
X250435Y340529D01*
G01X255817Y345919D02*
X250483Y340802D01*
G01X255865Y346192D02*
X250531Y341076D01*
G01X255913Y346466D02*
X250579Y341349D01*
G01X255961Y346738D02*
X250627Y341622D01*
G01X256009Y347012D02*
X250675Y341895D01*
G01X256057Y347285D02*
X250723Y342168D01*
G01X256105Y347559D02*
X250770Y342441D01*
G01X256152Y347831D02*
X250819Y342715D01*
G01X256201Y348104D02*
X250867Y342988D01*
G01X256249Y348378D02*
X250914Y343261D01*
G01X256296Y348651D02*
X250962Y343535D01*
G01X256344Y348925D02*
X251011Y343807D01*
G01X256392Y349197D02*
X251059Y344081D01*
G01X255002Y341274D02*
X255050Y341548D01*
G01X254858Y340454D02*
X254906Y340728D01*
G01X255050Y341548D02*
X255098Y341821D01*
G01X254810Y340182D02*
X254858Y340454D01*
G01X254953Y341001D02*
X255002Y341274D01*
G01X255193Y342367D02*
X255242Y342640D01*
G01X255145Y342094D02*
X255193Y342367D01*
G01X255098Y341821D02*
X255145Y342094D01*
G01X255289Y342913D02*
X255337Y343187D01*
G01D02*
X255385Y343460D01*
G01D02*
X255434Y343733D01*
G01D02*
X255481Y344007D01*
G01D02*
X255529Y344280D01*
G01X254906Y340728D02*
X254953Y341001D01*
G01X250627Y341622D02*
X250579Y341349D01*
G01X250770Y342441D02*
X250723Y342168D01*
G01D02*
X250675Y341895D01*
G01X250914Y343261D02*
X250867Y342988D01*
G01D02*
X250819Y342715D01*
G01D02*
X250770Y342441D01*
G01X250675Y341895D02*
X250627Y341622D01*
G01X250579Y341349D02*
X250531Y341076D01*
G01D02*
X250483Y340802D01*
G01X250962Y343535D02*
X250914Y343261D01*
G01X251011Y343807D02*
X250962Y343535D01*
G01X251059Y344081D02*
X251011Y343807D01*
G01X251106Y344354D02*
X251059Y344081D01*
G01X250483Y340802D02*
X250435Y340529D01*
G01X255289Y342913D02*
X255242Y342640D01*
G01X250435Y340529D02*
X250387Y340256D01*
G01X260229Y332429D02*
X264337Y336369D01*
G01X259992Y332429D02*
X264385Y336642D01*
G01X260102Y338442D02*
X265633Y343748D01*
G01X260223Y338785D02*
X265681Y344022D01*
G01X259992Y332429D02*
X260229D01*
G01D02*
X260466D01*
G01X260229D02*
X264337Y336369D01*
G01X259992Y332429D02*
X264385Y336642D01*
G01X260102Y338442D02*
X265633Y343748D01*
G01X260223Y338785D02*
X265681Y344022D01*
G01X259992Y332429D02*
X260229D01*
G01D02*
X260466D01*
G01X256277Y349314D02*
X251106Y344354D01*
G01X256040Y349314D02*
X251154Y344628D01*
G01X255803Y349314D02*
X251202Y344900D01*
G01X255566Y349314D02*
X251250Y345173D01*
G01X255329Y349314D02*
X251298Y345447D01*
G01X255092Y349314D02*
X251346Y345720D01*
G01X254856Y349314D02*
X251394Y345994D01*
G01X255673Y345099D02*
X255721Y345372D01*
G01X255769Y345646D02*
X255817Y345919D01*
G01X255625Y344826D02*
X255673Y345099D01*
G01X255721Y345372D02*
X255769Y345646D01*
G01X255577Y344553D02*
X255625Y344826D01*
G01X255529Y344280D02*
X255577Y344553D01*
G01X255817Y345919D02*
X255865Y346192D01*
G01X251442Y346266D02*
X251394Y345994D01*
G01X251298Y345447D02*
X251250Y345173D01*
G01D02*
X251202Y344900D01*
G01X251394Y345994D02*
X251346Y345720D01*
G01D02*
X251298Y345447D01*
G01X251202Y344900D02*
X251154Y344628D01*
G01D02*
X251106Y344354D01*
G01X256277Y349314D02*
X251106Y344354D01*
G01X256040Y349314D02*
X251154Y344628D01*
G01X255803Y349314D02*
X251202Y344900D01*
G01X255566Y349314D02*
X251250Y345173D01*
G01X255329Y349314D02*
X251298Y345447D01*
G01X255092Y349314D02*
X251346Y345720D01*
G01X254856Y349314D02*
X251394Y345994D01*
G01X255673Y345099D02*
X255721Y345372D01*
G01X255769Y345646D02*
X255817Y345919D01*
G01X255625Y344826D02*
X255673Y345099D01*
G01X255721Y345372D02*
X255769Y345646D01*
G01X255577Y344553D02*
X255625Y344826D01*
G01X255529Y344280D02*
X255577Y344553D01*
G01X255817Y345919D02*
X255865Y346192D01*
G01X251442Y346266D02*
X251394Y345994D01*
G01X251298Y345447D02*
X251250Y345173D01*
G01D02*
X251202Y344900D01*
G01X251394Y345994D02*
X251346Y345720D01*
G01D02*
X251298Y345447D01*
G01X251202Y344900D02*
X251154Y344628D01*
G01D02*
X251106Y344354D01*
G01X254619Y349314D02*
X251442Y346266D01*
G01X254382Y349314D02*
X251490Y346540D01*
G01X254145Y349314D02*
X251538Y346813D01*
G01X253908Y349314D02*
X251586Y347086D01*
G01X253672Y349314D02*
X251634Y347359D01*
G01X253434Y349314D02*
X251682Y347633D01*
G01X253198Y349314D02*
X251730Y347906D01*
G01X252961Y349314D02*
X251778Y348179D01*
G01X252724Y349314D02*
X251826Y348452D01*
G01X252487Y349314D02*
X251874Y348725D01*
G01X252250Y349314D02*
X251922Y348999D01*
G01X252014Y349314D02*
X251969Y349272D01*
G01X255329Y349314D02*
X255092D01*
G01D02*
X254856D01*
G01X254382D02*
X254145D01*
G01X254856D02*
X254619D01*
G01D02*
X254382D01*
G01X256277D02*
X256040D01*
G01D02*
X255803D01*
G01X255566D02*
X255329D01*
G01X255803D02*
X255566D01*
G01X256392Y349197D02*
X256413Y349314D01*
G01D02*
X256277D01*
G01X252487D02*
X252250D01*
G01X254145D02*
X253908D01*
G01X252250D02*
X252014D01*
G01X252724D02*
X252487D01*
G01X253908D02*
X253672D01*
G01D02*
X253434D01*
G01D02*
X253198D01*
G01X252961D02*
X252724D01*
G01X253198D02*
X252961D01*
G01X256344Y348925D02*
X256392Y349197D01*
G01X256201Y348104D02*
X256249Y348378D01*
G01X256152Y347831D02*
X256201Y348104D01*
G01X256296Y348651D02*
X256344Y348925D01*
G01X256249Y348378D02*
X256296Y348651D01*
G01X255961Y346738D02*
X256009Y347012D01*
G01X255865Y346192D02*
X255913Y346466D01*
G01D02*
X255961Y346738D01*
G01X256057Y347285D02*
X256105Y347559D01*
G01D02*
X256152Y347831D01*
G01X256009Y347012D02*
X256057Y347285D01*
G01X251730Y347906D02*
X251778Y348179D01*
G01X251826Y348452D02*
X251874Y348725D01*
G01X251778Y348179D02*
X251826Y348452D01*
G01X251682Y347633D02*
X251730Y347906D01*
G01X251874Y348725D02*
X251922Y348999D01*
G01X251538Y346813D02*
X251490Y346540D01*
G01X251634Y347359D02*
X251682Y347633D01*
G01X251586Y347086D02*
X251634Y347359D01*
G01X251538Y346813D02*
X251586Y347086D01*
G01X252014Y349314D02*
X251977D01*
G01D02*
X251969Y349272D01*
G01X251490Y346540D02*
X251442Y346266D01*
G01X251922Y348999D02*
X251969Y349272D01*
G01X254619Y349314D02*
X251442Y346266D01*
G01X254382Y349314D02*
X251490Y346540D01*
G01X254145Y349314D02*
X251538Y346813D01*
G01X253908Y349314D02*
X251586Y347086D01*
G01X253672Y349314D02*
X251634Y347359D01*
G01X253434Y349314D02*
X251682Y347633D01*
G01X253198Y349314D02*
X251730Y347906D01*
G01X252961Y349314D02*
X251778Y348179D01*
G01X252724Y349314D02*
X251826Y348452D01*
G01X252487Y349314D02*
X251874Y348725D01*
G01X252250Y349314D02*
X251922Y348999D01*
G01X252014Y349314D02*
X251969Y349272D01*
G01X255329Y349314D02*
X255092D01*
G01D02*
X254856D01*
G01X254382D02*
X254145D01*
G01X254856D02*
X254619D01*
G01D02*
X254382D01*
G01X256277D02*
X256040D01*
G01D02*
X255803D01*
G01X255566D02*
X255329D01*
G01X255803D02*
X255566D01*
G01X256392Y349197D02*
X256413Y349314D01*
G01D02*
X256277D01*
G01X252487D02*
X252250D01*
G01X254145D02*
X253908D01*
G01X252250D02*
X252014D01*
G01X252724D02*
X252487D01*
G01X253908D02*
X253672D01*
G01D02*
X253434D01*
G01D02*
X253198D01*
G01X252961D02*
X252724D01*
G01X253198D02*
X252961D01*
G01X256344Y348925D02*
X256392Y349197D01*
G01X256201Y348104D02*
X256249Y348378D01*
G01X256152Y347831D02*
X256201Y348104D01*
G01X256296Y348651D02*
X256344Y348925D01*
G01X256249Y348378D02*
X256296Y348651D01*
G01X255961Y346738D02*
X256009Y347012D01*
G01X255865Y346192D02*
X255913Y346466D01*
G01D02*
X255961Y346738D01*
G01X256057Y347285D02*
X256105Y347559D01*
G01D02*
X256152Y347831D01*
G01X256009Y347012D02*
X256057Y347285D01*
G01X251730Y347906D02*
X251778Y348179D01*
G01X251826Y348452D02*
X251874Y348725D01*
G01X251778Y348179D02*
X251826Y348452D01*
G01X251682Y347633D02*
X251730Y347906D01*
G01X251874Y348725D02*
X251922Y348999D01*
G01X251538Y346813D02*
X251490Y346540D01*
G01X251634Y347359D02*
X251682Y347633D01*
G01X251586Y347086D02*
X251634Y347359D01*
G01X251538Y346813D02*
X251586Y347086D01*
G01X252014Y349314D02*
X251977D01*
G01D02*
X251969Y349272D01*
G01X251490Y346540D02*
X251442Y346266D01*
G01X251922Y348999D02*
X251969Y349272D01*
G01X284579Y185236D02*
G02X269618I-7481J0D01*
G02X284579I7481J0D01*
G01X274593Y332575D02*
X281691Y339385D01*
G01X274212Y332437D02*
X281740Y339658D01*
G01X273875Y332341D02*
X281787Y339931D01*
G01X273538Y332246D02*
X281835Y340204D01*
G01X273231Y332178D02*
X281883Y340477D01*
G01X272968Y332154D02*
X281931Y340751D01*
G01X272704Y332126D02*
X281978Y341023D01*
G01X272441Y332102D02*
X282027Y341297D01*
G01X272177Y332075D02*
X282075Y341571D01*
G01X271950Y332084D02*
X282122Y341843D01*
G01X271722Y332094D02*
X282171Y342116D01*
G01X282219Y342390D02*
X271501Y332109D01*
G01X271290Y332135D02*
X275848Y336506D01*
G01X271080Y332159D02*
X275327Y336233D01*
G01X270880Y332194D02*
X274945Y336094D01*
G01X270685Y332235D02*
X274571Y335963D01*
G01X270490Y332274D02*
X274300Y335930D01*
G01X270307Y332327D02*
X274029Y335896D01*
G01X270127Y332381D02*
X273758Y335863D01*
G01X269946Y332436D02*
X273497Y335841D01*
G01X269778Y332501D02*
X273277Y335857D01*
G01X269612Y332569D02*
X273057Y335873D01*
G01X269446Y332636D02*
X272847Y335898D01*
G01X269291Y332715D02*
X272660Y335947D01*
G01X269139Y332796D02*
X272474Y335996D01*
G01X268987Y332878D02*
X272303Y336059D01*
G01X268844Y332968D02*
X272150Y336139D01*
G01X268706Y333062D02*
X271997Y336220D01*
G01X268568Y333157D02*
X271870Y336326D01*
G01X268437Y333259D02*
X271750Y336438D01*
G01X268313Y333367D02*
X271640Y336559D01*
G01X268189Y333475D02*
X271554Y336703D01*
G01X268069Y333588D02*
X271467Y336848D01*
G01X267959Y333710D02*
X271414Y337023D01*
G01X267850Y333832D02*
X271362Y337201D01*
G01X267742Y333955D02*
X271340Y337407D01*
G01X267648Y334093D02*
X271325Y337620D01*
G01X267554Y334230D02*
X271345Y337866D01*
G01X267460Y334367D02*
X271381Y338128D01*
G01X267380Y334517D02*
X271506Y338475D01*
G01X272695Y339843D02*
X276514Y343507D01*
G01X267302Y334670D02*
X271632Y338823D01*
G01X267225Y334823D02*
X276314Y343541D01*
G01X267158Y334986D02*
X276114Y343577D01*
G01X267099Y335156D02*
X275913Y343611D01*
G01X267039Y335326D02*
X275701Y343636D01*
G01X266988Y335504D02*
X275476Y343647D01*
G01X266947Y335692D02*
X275252Y343659D01*
G01X263545Y332429D02*
X263664Y332543D01*
G01X263308Y332429D02*
X263713Y332817D01*
G01X266907Y335881D02*
X275027Y343671D01*
G01X263071Y332429D02*
X263760Y333090D01*
G01X266872Y336075D02*
X274803Y343683D01*
G01X266854Y336284D02*
X274555Y343672D01*
G01X262834Y332429D02*
X263808Y333363D01*
G01X266835Y336494D02*
X274302Y343657D01*
G01X262598Y332429D02*
X263856Y333636D01*
G01X262360Y332429D02*
X263905Y333910D01*
G01X266821Y336708D02*
X274049Y343641D01*
G01X266827Y336940D02*
X273795Y343625D01*
G01X262124Y332429D02*
X263953Y334183D01*
G01X266832Y337173D02*
X273542Y343610D01*
G01X261887Y332429D02*
X264000Y334456D01*
G01X261650Y332429D02*
X264048Y334729D01*
G01X266844Y337411D02*
X273278Y343583D01*
G01X266876Y337670D02*
X272980Y343525D01*
G01X261414Y332429D02*
X264096Y335003D01*
G01X266910Y337929D02*
X272682Y343467D01*
G01X261176Y332429D02*
X264145Y335277D01*
G01X260940Y332429D02*
X264193Y335549D01*
G01X266962Y338206D02*
X272385Y343408D01*
G01X267049Y338517D02*
X272087Y343350D01*
G01X260703Y332429D02*
X264240Y335822D01*
G01X260466Y332429D02*
X264288Y336096D01*
G01X267136Y338827D02*
X271732Y343236D01*
G01X267224Y339139D02*
X271357Y343104D01*
G01X267333Y339471D02*
X270983Y342972D01*
G01X267571Y339926D02*
X270532Y342766D01*
G01X265729Y344294D02*
X260335Y339120D01*
G01X265777Y344567D02*
X260400Y339409D01*
G01X265825Y344841D02*
X260466Y339700D01*
G01X265873Y345114D02*
X260531Y339990D01*
G01X264720Y338555D02*
X264769Y338829D01*
G01X263308Y332429D02*
X263545D01*
G01X262360D02*
X262598D01*
G01D02*
X262834D01*
G01X261887D02*
X262124D01*
G01D02*
X262360D01*
G01X263071D02*
X263308D01*
G01X262834D02*
X263071D01*
G01X261650D02*
X261887D01*
G01X261414D02*
X261650D01*
G01X261176D02*
X261414D01*
G01X260940D02*
X261176D01*
G01X260703D02*
X260940D01*
G01X260466D02*
X260703D01*
G01X263808Y333363D02*
X263760Y333090D01*
G01D02*
X263713Y332817D01*
G01X263856Y333636D02*
X263808Y333363D01*
G01X263713Y332817D02*
X263664Y332543D01*
G01X263545Y332429D02*
X263644D01*
G01D02*
X263664Y332543D01*
G01X264048Y334729D02*
X264000Y334456D01*
G01D02*
X263953Y334183D01*
G01D02*
X263905Y333910D01*
G01D02*
X263856Y333636D01*
G01X264096Y335003D02*
X264048Y334729D01*
G01X264817Y339101D02*
X264865Y339375D01*
G01X264625Y338009D02*
X264673Y338282D01*
G01D02*
X264720Y338555D01*
G01X264769Y338829D02*
X264817Y339101D01*
G01X264865Y339375D02*
X264913Y339649D01*
G01D02*
X264960Y339922D01*
G01D02*
X265009Y340195D01*
G01X264240Y335822D02*
X264193Y335549D01*
G01X264337Y336369D02*
X264288Y336096D01*
G01D02*
X264240Y335822D01*
G01X264145Y335277D02*
X264096Y335003D01*
G01X264193Y335549D02*
X264145Y335277D01*
G01X264385Y336642D02*
X264337Y336369D01*
G01X264528Y337462D02*
X264480Y337189D01*
G01X264528Y337462D02*
X264577Y337736D01*
G01X264433Y336916D02*
X264385Y336642D01*
G01X264480Y337189D02*
X264433Y336916D01*
G01X264577Y337736D02*
X264625Y338009D01*
G01X274593Y332575D02*
X281691Y339385D01*
G01X274212Y332437D02*
X281740Y339658D01*
G01X273875Y332341D02*
X281787Y339931D01*
G01X273538Y332246D02*
X281835Y340204D01*
G01X273231Y332178D02*
X281883Y340477D01*
G01X272968Y332154D02*
X281931Y340751D01*
G01X272704Y332126D02*
X281978Y341023D01*
G01X272441Y332102D02*
X282027Y341297D01*
G01X272177Y332075D02*
X282075Y341571D01*
G01X271950Y332084D02*
X282122Y341843D01*
G01X271722Y332094D02*
X282171Y342116D01*
G01X282219Y342390D02*
X271501Y332109D01*
G01X271290Y332135D02*
X275848Y336506D01*
G01X271080Y332159D02*
X275327Y336233D01*
G01X270880Y332194D02*
X274945Y336094D01*
G01X270685Y332235D02*
X274571Y335963D01*
G01X270490Y332274D02*
X274300Y335930D01*
G01X270307Y332327D02*
X274029Y335896D01*
G01X270127Y332381D02*
X273758Y335863D01*
G01X269946Y332436D02*
X273497Y335841D01*
G01X269778Y332501D02*
X273277Y335857D01*
G01X269612Y332569D02*
X273057Y335873D01*
G01X269446Y332636D02*
X272847Y335898D01*
G01X269291Y332715D02*
X272660Y335947D01*
G01X269139Y332796D02*
X272474Y335996D01*
G01X268987Y332878D02*
X272303Y336059D01*
G01X268844Y332968D02*
X272150Y336139D01*
G01X268706Y333062D02*
X271997Y336220D01*
G01X268568Y333157D02*
X271870Y336326D01*
G01X268437Y333259D02*
X271750Y336438D01*
G01X268313Y333367D02*
X271640Y336559D01*
G01X268189Y333475D02*
X271554Y336703D01*
G01X268069Y333588D02*
X271467Y336848D01*
G01X267959Y333710D02*
X271414Y337023D01*
G01X267850Y333832D02*
X271362Y337201D01*
G01X267742Y333955D02*
X271340Y337407D01*
G01X267648Y334093D02*
X271325Y337620D01*
G01X267554Y334230D02*
X271345Y337866D01*
G01X267460Y334367D02*
X271381Y338128D01*
G01X267380Y334517D02*
X271506Y338475D01*
G01X272695Y339843D02*
X276514Y343507D01*
G01X267302Y334670D02*
X271632Y338823D01*
G01X267225Y334823D02*
X276314Y343541D01*
G01X267158Y334986D02*
X276114Y343577D01*
G01X267099Y335156D02*
X275913Y343611D01*
G01X267039Y335326D02*
X275701Y343636D01*
G01X266988Y335504D02*
X275476Y343647D01*
G01X266947Y335692D02*
X275252Y343659D01*
G01X263545Y332429D02*
X263664Y332543D01*
G01X263308Y332429D02*
X263713Y332817D01*
G01X266907Y335881D02*
X275027Y343671D01*
G01X263071Y332429D02*
X263760Y333090D01*
G01X266872Y336075D02*
X274803Y343683D01*
G01X266854Y336284D02*
X274555Y343672D01*
G01X262834Y332429D02*
X263808Y333363D01*
G01X266835Y336494D02*
X274302Y343657D01*
G01X262598Y332429D02*
X263856Y333636D01*
G01X262360Y332429D02*
X263905Y333910D01*
G01X266821Y336708D02*
X274049Y343641D01*
G01X266827Y336940D02*
X273795Y343625D01*
G01X262124Y332429D02*
X263953Y334183D01*
G01X266832Y337173D02*
X273542Y343610D01*
G01X261887Y332429D02*
X264000Y334456D01*
G01X261650Y332429D02*
X264048Y334729D01*
G01X266844Y337411D02*
X273278Y343583D01*
G01X266876Y337670D02*
X272980Y343525D01*
G01X261414Y332429D02*
X264096Y335003D01*
G01X266910Y337929D02*
X272682Y343467D01*
G01X261176Y332429D02*
X264145Y335277D01*
G01X260940Y332429D02*
X264193Y335549D01*
G01X266962Y338206D02*
X272385Y343408D01*
G01X267049Y338517D02*
X272087Y343350D01*
G01X260703Y332429D02*
X264240Y335822D01*
G01X260466Y332429D02*
X264288Y336096D01*
G01X267136Y338827D02*
X271732Y343236D01*
G01X267224Y339139D02*
X271357Y343104D01*
G01X267333Y339471D02*
X270983Y342972D01*
G01X267571Y339926D02*
X270532Y342766D01*
G01X265729Y344294D02*
X260335Y339120D01*
G01X265777Y344567D02*
X260400Y339409D01*
G01X265825Y344841D02*
X260466Y339700D01*
G01X265873Y345114D02*
X260531Y339990D01*
G01X264720Y338555D02*
X264769Y338829D01*
G01X263308Y332429D02*
X263545D01*
G01X262360D02*
X262598D01*
G01D02*
X262834D01*
G01X261887D02*
X262124D01*
G01D02*
X262360D01*
G01X263071D02*
X263308D01*
G01X262834D02*
X263071D01*
G01X261650D02*
X261887D01*
G01X261414D02*
X261650D01*
G01X261176D02*
X261414D01*
G01X260940D02*
X261176D01*
G01X260703D02*
X260940D01*
G01X260466D02*
X260703D01*
G01X263808Y333363D02*
X263760Y333090D01*
G01D02*
X263713Y332817D01*
G01X263856Y333636D02*
X263808Y333363D01*
G01X263713Y332817D02*
X263664Y332543D01*
G01X263545Y332429D02*
X263644D01*
G01D02*
X263664Y332543D01*
G01X264048Y334729D02*
X264000Y334456D01*
G01D02*
X263953Y334183D01*
G01D02*
X263905Y333910D01*
G01D02*
X263856Y333636D01*
G01X264096Y335003D02*
X264048Y334729D01*
G01X264817Y339101D02*
X264865Y339375D01*
G01X264625Y338009D02*
X264673Y338282D01*
G01D02*
X264720Y338555D01*
G01X264769Y338829D02*
X264817Y339101D01*
G01X264865Y339375D02*
X264913Y339649D01*
G01D02*
X264960Y339922D01*
G01D02*
X265009Y340195D01*
G01X264240Y335822D02*
X264193Y335549D01*
G01X264337Y336369D02*
X264288Y336096D01*
G01D02*
X264240Y335822D01*
G01X264145Y335277D02*
X264096Y335003D01*
G01X264193Y335549D02*
X264145Y335277D01*
G01X264385Y336642D02*
X264337Y336369D01*
G01X264528Y337462D02*
X264480Y337189D01*
G01X264528Y337462D02*
X264577Y337736D01*
G01X264433Y336916D02*
X264385Y336642D01*
G01X264480Y337189D02*
X264433Y336916D01*
G01X264577Y337736D02*
X264625Y338009D01*
G01X277732Y343084D02*
X274730Y340205D01*
G01X277573Y343159D02*
X274498Y340210D01*
G01X277414Y343233D02*
X274258Y340206D01*
G01X277243Y343298D02*
X273986Y340172D01*
G01X273713Y340138D02*
X277065Y343354D01*
G01X273441Y340104D02*
X276887Y343410D01*
G01X273160Y340062D02*
X276708Y343466D01*
G01X267809Y340382D02*
X269980Y342464D01*
G01X265921Y345387D02*
X260584Y340268D01*
G01X265969Y345660D02*
X260632Y340541D01*
G01X266017Y345934D02*
X260680Y340814D01*
G01X266065Y346207D02*
X260728Y341088D01*
G01X266113Y346481D02*
X260776Y341360D01*
G01X266161Y346753D02*
X260824Y341633D01*
G01X266209Y347027D02*
X260872Y341907D01*
G01X266257Y347300D02*
X260920Y342180D01*
G01X266305Y347574D02*
X260967Y342453D01*
G01X266353Y347846D02*
X261015Y342726D01*
G01X266402Y348120D02*
X261063Y342999D01*
G01X266450Y348394D02*
X261111Y343273D01*
G01X266497Y348667D02*
X261159Y343545D01*
G01X266545Y348940D02*
X261207Y343818D01*
G01X265585Y343474D02*
X265633Y343748D01*
G01X265537Y343201D02*
X265585Y343474D01*
G01X265105Y340742D02*
X265153Y341015D01*
G01X265201Y341288D02*
X265249Y341561D01*
G01X265153Y341015D02*
X265201Y341288D01*
G01X265489Y342928D02*
X265441Y342654D01*
G01X265297Y341835D02*
X265345Y342108D01*
G01X265441Y342654D02*
X265393Y342381D01*
G01X265345Y342108D02*
X265393Y342381D01*
G01X265249Y341561D02*
X265297Y341835D01*
G01X265489Y342928D02*
X265537Y343201D01*
G01X265681Y344022D02*
X265729Y344294D01*
G01X265057Y340469D02*
X265105Y340742D01*
G01X260680Y340814D02*
X260632Y340541D01*
G01X265681Y344022D02*
X265633Y343748D01*
G01X260632Y340541D02*
X260584Y340268D01*
G01X260728Y341088D02*
X260680Y340814D01*
G01X265009Y340195D02*
X265057Y340469D01*
G01X261159Y343545D02*
X261111Y343273D01*
G01X260776Y341360D02*
X260728Y341088D01*
G01X261111Y343273D02*
X261063Y342999D01*
G01X261255Y344092D02*
X261207Y343818D01*
G01X261063Y342999D02*
X261015Y342726D01*
G01X261207Y343818D02*
X261159Y343545D01*
G01X260872Y341907D02*
X260824Y341633D01*
G01D02*
X260776Y341360D01*
G01X261015Y342726D02*
X260967Y342453D01*
G01X260920Y342180D02*
X260872Y341907D01*
G01X260967Y342453D02*
X260920Y342180D01*
G01X277732Y343084D02*
X274730Y340205D01*
G01X277573Y343159D02*
X274498Y340210D01*
G01X277414Y343233D02*
X274258Y340206D01*
G01X277243Y343298D02*
X273986Y340172D01*
G01X273713Y340138D02*
X277065Y343354D01*
G01X273441Y340104D02*
X276887Y343410D01*
G01X273160Y340062D02*
X276708Y343466D01*
G01X267809Y340382D02*
X269980Y342464D01*
G01X265921Y345387D02*
X260584Y340268D01*
G01X265969Y345660D02*
X260632Y340541D01*
G01X266017Y345934D02*
X260680Y340814D01*
G01X266065Y346207D02*
X260728Y341088D01*
G01X266113Y346481D02*
X260776Y341360D01*
G01X266161Y346753D02*
X260824Y341633D01*
G01X266209Y347027D02*
X260872Y341907D01*
G01X266257Y347300D02*
X260920Y342180D01*
G01X266305Y347574D02*
X260967Y342453D01*
G01X266353Y347846D02*
X261015Y342726D01*
G01X266402Y348120D02*
X261063Y342999D01*
G01X266450Y348394D02*
X261111Y343273D01*
G01X266497Y348667D02*
X261159Y343545D01*
G01X266545Y348940D02*
X261207Y343818D01*
G01X265585Y343474D02*
X265633Y343748D01*
G01X265537Y343201D02*
X265585Y343474D01*
G01X265105Y340742D02*
X265153Y341015D01*
G01X265201Y341288D02*
X265249Y341561D01*
G01X265153Y341015D02*
X265201Y341288D01*
G01X265489Y342928D02*
X265441Y342654D01*
G01X265297Y341835D02*
X265345Y342108D01*
G01X265441Y342654D02*
X265393Y342381D01*
G01X265345Y342108D02*
X265393Y342381D01*
G01X265249Y341561D02*
X265297Y341835D01*
G01X265489Y342928D02*
X265537Y343201D01*
G01X265681Y344022D02*
X265729Y344294D01*
G01X265057Y340469D02*
X265105Y340742D01*
G01X260680Y340814D02*
X260632Y340541D01*
G01X265681Y344022D02*
X265633Y343748D01*
G01X260632Y340541D02*
X260584Y340268D01*
G01X260728Y341088D02*
X260680Y340814D01*
G01X265009Y340195D02*
X265057Y340469D01*
G01X261159Y343545D02*
X261111Y343273D01*
G01X260776Y341360D02*
X260728Y341088D01*
G01X261111Y343273D02*
X261063Y342999D01*
G01X261255Y344092D02*
X261207Y343818D01*
G01X261063Y342999D02*
X261015Y342726D01*
G01X261207Y343818D02*
X261159Y343545D01*
G01X260872Y341907D02*
X260824Y341633D01*
G01D02*
X260776Y341360D01*
G01X261015Y342726D02*
X260967Y342453D01*
G01X260920Y342180D02*
X260872Y341907D01*
G01X260967Y342453D02*
X260920Y342180D01*
G01X275067Y332803D02*
X281643Y339112D01*
G01X275067Y332803D02*
X281643Y339112D01*
G01X282157Y346876D02*
X275179Y340181D01*
G01X282091Y347039D02*
X274957Y340196D01*
G01X282157Y346876D02*
X275179Y340181D01*
G01X282091Y347039D02*
X274957Y340196D01*
G01X278478Y349481D02*
X274802Y345954D01*
G01X278286Y349524D02*
X274540Y345931D01*
G01X278095Y349568D02*
X274267Y345895D01*
G01X277874Y349583D02*
X273990Y345857D01*
G01X277654Y349598D02*
X273691Y345797D01*
G01X277432Y349613D02*
X273383Y345729D01*
G01X277211Y349629D02*
X273050Y345637D01*
G01X276990Y349644D02*
X272694Y345522D01*
G01X276769Y349658D02*
X272315Y345385D01*
G01X276537Y349664D02*
X271893Y345208D01*
G01X276293Y349657D02*
X271437Y344998D01*
G01X276049Y349650D02*
X271147Y344947D01*
G01X275806Y349644D02*
X271084Y345114D01*
G01X275554Y349630D02*
X271021Y345281D01*
G01X275293Y349606D02*
X270958Y345448D01*
G01X275032Y349583D02*
X270896Y345615D01*
G01X274772Y349560D02*
X270833Y345782D01*
G01X274488Y349516D02*
X270770Y345949D01*
G01X266593Y349213D02*
X261255Y344092D01*
G01X266461Y349314D02*
X261302Y344365D01*
G01X266225Y349314D02*
X261351Y344638D01*
G01X265988Y349314D02*
X261398Y344911D01*
G01X265751Y349314D02*
X261446Y345184D01*
G01X265514Y349314D02*
X261494Y345458D01*
G01X265277Y349314D02*
X261542Y345731D01*
G01X265040Y349314D02*
X261590Y346003D01*
G01X271084Y345114D02*
X271147Y344947D01*
G01X270770Y345949D02*
X270833Y345782D01*
G01X270707Y346116D02*
X270770Y345949D01*
G01X270833Y345782D02*
X270896Y345615D01*
G01X271021Y345281D02*
X271084Y345114D01*
G01X270896Y345615D02*
X270958Y345448D01*
G01D02*
X271021Y345281D01*
G01X261351Y344638D02*
X261302Y344365D01*
G01X265921Y345387D02*
X265969Y345660D01*
G01X265873Y345114D02*
X265921Y345387D01*
G01X266017Y345934D02*
X266065Y346207D01*
G01X265777Y344567D02*
X265825Y344841D01*
G01D02*
X265873Y345114D01*
G01X265729Y344294D02*
X265777Y344567D01*
G01X265969Y345660D02*
X266017Y345934D01*
G01X261590Y346003D02*
X261542Y345731D01*
G01X261637Y346277D02*
X261590Y346003D01*
G01X261494Y345458D02*
X261446Y345184D01*
G01X261302Y344365D02*
X261255Y344092D01*
G01X261398Y344911D02*
X261351Y344638D01*
G01X261446Y345184D02*
X261398Y344911D01*
G01X261542Y345731D02*
X261494Y345458D01*
G01X278478Y349481D02*
X274802Y345954D01*
G01X278286Y349524D02*
X274540Y345931D01*
G01X278095Y349568D02*
X274267Y345895D01*
G01X277874Y349583D02*
X273990Y345857D01*
G01X277654Y349598D02*
X273691Y345797D01*
G01X277432Y349613D02*
X273383Y345729D01*
G01X277211Y349629D02*
X273050Y345637D01*
G01X276990Y349644D02*
X272694Y345522D01*
G01X276769Y349658D02*
X272315Y345385D01*
G01X276537Y349664D02*
X271893Y345208D01*
G01X276293Y349657D02*
X271437Y344998D01*
G01X276049Y349650D02*
X271147Y344947D01*
G01X275806Y349644D02*
X271084Y345114D01*
G01X275554Y349630D02*
X271021Y345281D01*
G01X275293Y349606D02*
X270958Y345448D01*
G01X275032Y349583D02*
X270896Y345615D01*
G01X274772Y349560D02*
X270833Y345782D01*
G01X274488Y349516D02*
X270770Y345949D01*
G01X266593Y349213D02*
X261255Y344092D01*
G01X266461Y349314D02*
X261302Y344365D01*
G01X266225Y349314D02*
X261351Y344638D01*
G01X265988Y349314D02*
X261398Y344911D01*
G01X265751Y349314D02*
X261446Y345184D01*
G01X265514Y349314D02*
X261494Y345458D01*
G01X265277Y349314D02*
X261542Y345731D01*
G01X265040Y349314D02*
X261590Y346003D01*
G01X271084Y345114D02*
X271147Y344947D01*
G01X270770Y345949D02*
X270833Y345782D01*
G01X270707Y346116D02*
X270770Y345949D01*
G01X270833Y345782D02*
X270896Y345615D01*
G01X271021Y345281D02*
X271084Y345114D01*
G01X270896Y345615D02*
X270958Y345448D01*
G01D02*
X271021Y345281D01*
G01X261351Y344638D02*
X261302Y344365D01*
G01X265921Y345387D02*
X265969Y345660D01*
G01X265873Y345114D02*
X265921Y345387D01*
G01X266017Y345934D02*
X266065Y346207D01*
G01X265777Y344567D02*
X265825Y344841D01*
G01D02*
X265873Y345114D01*
G01X265729Y344294D02*
X265777Y344567D01*
G01X265969Y345660D02*
X266017Y345934D01*
G01X261590Y346003D02*
X261542Y345731D01*
G01X261637Y346277D02*
X261590Y346003D01*
G01X261494Y345458D02*
X261446Y345184D01*
G01X261302Y344365D02*
X261255Y344092D01*
G01X261398Y344911D02*
X261351Y344638D01*
G01X261446Y345184D02*
X261398Y344911D01*
G01X261542Y345731D02*
X261494Y345458D01*
G01X274204Y349471D02*
X270707Y346116D01*
G01X273920Y349425D02*
X270644Y346283D01*
G01X273608Y349353D02*
X270581Y346449D01*
G01X273294Y349280D02*
X270519Y346616D01*
G01X272966Y349192D02*
X270456Y346784D01*
G01X272616Y349083D02*
X270393Y346951D01*
G01X272257Y348965D02*
X270330Y347117D01*
G01X271862Y348814D02*
X270267Y347284D01*
G01X271453Y348649D02*
X270204Y347452D01*
G01X271009Y348451D02*
X270142Y347618D01*
G01X270538Y348225D02*
X270079Y347785D01*
G01X270041Y347976D02*
X270016Y347952D01*
G01X264804Y349314D02*
X261637Y346277D01*
G01X264566Y349314D02*
X261686Y346550D01*
G01X264330Y349314D02*
X261733Y346823D01*
G01X264093Y349314D02*
X261781Y347096D01*
G01X263856Y349314D02*
X261829Y347369D01*
G01X263619Y349314D02*
X261877Y347643D01*
G01X263382Y349314D02*
X261925Y347916D01*
G01X263146Y349314D02*
X261972Y348188D01*
G01X262909Y349314D02*
X262021Y348462D01*
G01X262672Y349314D02*
X262069Y348735D01*
G01X262435Y349314D02*
X262116Y349008D01*
G01X262198Y349314D02*
X262164Y349281D01*
G01X270204Y347452D02*
X270142Y347618D01*
G01X270204Y347452D02*
X270267Y347284D01*
G01X270142Y347618D02*
X270079Y347785D01*
G01D02*
X270016Y347952D01*
G01X270267Y347284D02*
X270330Y347117D01*
G01X270456Y346784D02*
X270519Y346616D01*
G01X270393Y346951D02*
X270456Y346784D01*
G01X270330Y347117D02*
X270393Y346951D01*
G01X270519Y346616D02*
X270581Y346449D01*
G01X270644Y346283D02*
X270707Y346116D01*
G01X270581Y346449D02*
X270644Y346283D01*
G01X265040Y349314D02*
X264804D01*
G01X265277D02*
X265040D01*
G01X264566D02*
X264330D01*
G01D02*
X264093D01*
G01X266225D02*
X265988D01*
G01X265514D02*
X265277D01*
G01X265988D02*
X265751D01*
G01D02*
X265514D01*
G01X263146D02*
X262909D01*
G01D02*
X262672D01*
G01D02*
X262435D01*
G01D02*
X262198D01*
G01X263856D02*
X263619D01*
G01X263382D02*
X263146D01*
G01X266461D02*
X266225D01*
G01X263619D02*
X263382D01*
G01X264093D02*
X263856D01*
G01X266065Y346207D02*
X266113Y346481D01*
G01X266593Y349213D02*
X266611Y349314D01*
G01D02*
X266461D01*
G01X266402Y348120D02*
X266450Y348394D01*
G01D02*
X266497Y348667D01*
G01X266113Y346481D02*
X266161Y346753D01*
G01X266497Y348667D02*
X266545Y348940D01*
G01D02*
X266593Y349213D01*
G01X266209Y347027D02*
X266257Y347300D01*
G01X266161Y346753D02*
X266209Y347027D01*
G01X266353Y347846D02*
X266402Y348120D01*
G01X266305Y347574D02*
X266353Y347846D01*
G01X266257Y347300D02*
X266305Y347574D01*
G01X264804Y349314D02*
X264566D01*
G01X262116Y349008D02*
X262164Y349281D01*
G01X262021Y348462D02*
X262069Y348735D01*
G01X262198Y349314D02*
X262170D01*
G01D02*
X262164Y349281D01*
G01X261829Y347369D02*
X261877Y347643D01*
G01X261925Y347916D02*
X261972Y348188D01*
G01D02*
X262021Y348462D01*
G01X261877Y347643D02*
X261925Y347916D01*
G01X261781Y347096D02*
X261829Y347369D01*
G01X262069Y348735D02*
X262116Y349008D01*
G01X261733Y346823D02*
X261781Y347096D01*
G01X261686Y346550D02*
X261733Y346823D01*
G01X261686Y346550D02*
X261637Y346277D01*
G01X274204Y349471D02*
X270707Y346116D01*
G01X273920Y349425D02*
X270644Y346283D01*
G01X273608Y349353D02*
X270581Y346449D01*
G01X273294Y349280D02*
X270519Y346616D01*
G01X272966Y349192D02*
X270456Y346784D01*
G01X272616Y349083D02*
X270393Y346951D01*
G01X272257Y348965D02*
X270330Y347117D01*
G01X271862Y348814D02*
X270267Y347284D01*
G01X271453Y348649D02*
X270204Y347452D01*
G01X271009Y348451D02*
X270142Y347618D01*
G01X270538Y348225D02*
X270079Y347785D01*
G01X270041Y347976D02*
X270016Y347952D01*
G01X264804Y349314D02*
X261637Y346277D01*
G01X264566Y349314D02*
X261686Y346550D01*
G01X264330Y349314D02*
X261733Y346823D01*
G01X264093Y349314D02*
X261781Y347096D01*
G01X263856Y349314D02*
X261829Y347369D01*
G01X263619Y349314D02*
X261877Y347643D01*
G01X263382Y349314D02*
X261925Y347916D01*
G01X263146Y349314D02*
X261972Y348188D01*
G01X262909Y349314D02*
X262021Y348462D01*
G01X262672Y349314D02*
X262069Y348735D01*
G01X262435Y349314D02*
X262116Y349008D01*
G01X262198Y349314D02*
X262164Y349281D01*
G01X270204Y347452D02*
X270142Y347618D01*
G01X270204Y347452D02*
X270267Y347284D01*
G01X270142Y347618D02*
X270079Y347785D01*
G01D02*
X270016Y347952D01*
G01X270267Y347284D02*
X270330Y347117D01*
G01X270456Y346784D02*
X270519Y346616D01*
G01X270393Y346951D02*
X270456Y346784D01*
G01X270330Y347117D02*
X270393Y346951D01*
G01X270519Y346616D02*
X270581Y346449D01*
G01X270644Y346283D02*
X270707Y346116D01*
G01X270581Y346449D02*
X270644Y346283D01*
G01X265040Y349314D02*
X264804D01*
G01X265277D02*
X265040D01*
G01X264566D02*
X264330D01*
G01D02*
X264093D01*
G01X266225D02*
X265988D01*
G01X265514D02*
X265277D01*
G01X265988D02*
X265751D01*
G01D02*
X265514D01*
G01X263146D02*
X262909D01*
G01D02*
X262672D01*
G01D02*
X262435D01*
G01D02*
X262198D01*
G01X263856D02*
X263619D01*
G01X263382D02*
X263146D01*
G01X266461D02*
X266225D01*
G01X263619D02*
X263382D01*
G01X264093D02*
X263856D01*
G01X266065Y346207D02*
X266113Y346481D01*
G01X266593Y349213D02*
X266611Y349314D01*
G01D02*
X266461D01*
G01X266402Y348120D02*
X266450Y348394D01*
G01D02*
X266497Y348667D01*
G01X266113Y346481D02*
X266161Y346753D01*
G01X266497Y348667D02*
X266545Y348940D01*
G01D02*
X266593Y349213D01*
G01X266209Y347027D02*
X266257Y347300D01*
G01X266161Y346753D02*
X266209Y347027D01*
G01X266353Y347846D02*
X266402Y348120D01*
G01X266305Y347574D02*
X266353Y347846D01*
G01X266257Y347300D02*
X266305Y347574D01*
G01X264804Y349314D02*
X264566D01*
G01X262116Y349008D02*
X262164Y349281D01*
G01X262021Y348462D02*
X262069Y348735D01*
G01X262198Y349314D02*
X262170D01*
G01D02*
X262164Y349281D01*
G01X261829Y347369D02*
X261877Y347643D01*
G01X261925Y347916D02*
X261972Y348188D01*
G01D02*
X262021Y348462D01*
G01X261877Y347643D02*
X261925Y347916D01*
G01X261781Y347096D02*
X261829Y347369D01*
G01X262069Y348735D02*
X262116Y349008D01*
G01X261733Y346823D02*
X261781Y347096D01*
G01X261686Y346550D02*
X261733Y346823D01*
G01X261686Y346550D02*
X261637Y346277D01*
G01X278669Y349437D02*
X275056Y345971D01*
G01X278669Y349437D02*
X275056Y345971D01*
G01X282795Y1019252D02*
G02X267047I-7874J0D01*
G02X282795I7874J0D01*
G01X283783Y1357539D02*
G02X269098I-7342J0D01*
G02X283783I7343J0D01*
G01X287705Y332429D02*
X287767Y332490D01*
G01X287468Y332429D02*
X287815Y332763D01*
G01X287230Y332429D02*
X287862Y333035D01*
G01X286994Y332429D02*
X287911Y333309D01*
G01X286757Y332429D02*
X287960Y333583D01*
G01X286519Y332429D02*
X288007Y333856D01*
G01X286283Y332429D02*
X288055Y334129D01*
G01X286046Y332429D02*
X288104Y334402D01*
G01X285809Y332429D02*
X288152Y334676D01*
G01X285573Y332429D02*
X288200Y334949D01*
G01X285337Y332429D02*
X288247Y335222D01*
G01X285098Y332429D02*
X288296Y335496D01*
G01X284862Y332429D02*
X288344Y335770D01*
G01X284626Y332429D02*
X288391Y336042D01*
G01X284389Y332429D02*
X288440Y336315D01*
G01X284151Y332429D02*
X288489Y336589D01*
G01X283914Y332429D02*
X288536Y336863D01*
G01X283678Y332429D02*
X288584Y337136D01*
G01X283441Y332429D02*
X288633Y337409D01*
G01X283342Y332560D02*
X288681Y337683D01*
G01X283389Y332834D02*
X288729Y337956D01*
G01X283438Y333107D02*
X288776Y338229D01*
G01X283485Y333380D02*
X288825Y338502D01*
G01X283533Y333654D02*
X288873Y338776D01*
G01X283582Y333928D02*
X288920Y339049D01*
G01X283629Y334200D02*
X288969Y339322D01*
G01X283677Y334473D02*
X289018Y339596D01*
G01X283725Y334747D02*
X289065Y339869D01*
G01X283774Y335020D02*
X289113Y340143D01*
G01X283820Y335293D02*
X289162Y340416D01*
G01X289209Y340689D02*
X283869Y335566D01*
G01X280362Y332429D02*
X280495Y332555D01*
G01X289257Y340962D02*
X283918Y335839D01*
G01X289305Y341236D02*
X283965Y336113D01*
G01X280124Y332429D02*
X280542Y332829D01*
G01X289354Y341509D02*
X284013Y336386D01*
G01X279888Y332429D02*
X280590Y333102D01*
G01X279652Y332429D02*
X280638Y333375D01*
G01X289408Y341789D02*
X284062Y336659D01*
G01X279414Y332429D02*
X280684Y333648D01*
G01X289474Y342079D02*
X284109Y336933D01*
G01X289539Y342368D02*
X284157Y337206D01*
G01X279177Y332429D02*
X280733Y333922D01*
G01X289602Y342656D02*
X284206Y337479D01*
G01X278940Y332429D02*
X280782Y334195D01*
G01X278704Y332429D02*
X280828Y334467D01*
G01X289720Y342996D02*
X284253Y337752D01*
G01X278467Y332429D02*
X280877Y334741D01*
G01X289840Y343339D02*
X284300Y338025D01*
G01X290030Y343748D02*
X284349Y338299D01*
G01X278230Y332429D02*
X280926Y335014D01*
G01X290344Y344277D02*
X284397Y338572D01*
G01X277994Y332429D02*
X280972Y335287D01*
G01X277757Y332429D02*
X281021Y335560D01*
G01X295639Y349584D02*
X284444Y338844D01*
G01X295422Y349604D02*
X284493Y339118D01*
G01X277519Y332429D02*
X281068Y335833D01*
G01X277282Y332429D02*
X281116Y336107D01*
G01X295207Y349623D02*
X284541Y339392D01*
G01X294991Y349644D02*
X284588Y339664D01*
G01X277045Y332429D02*
X281165Y336380D01*
G01X276809Y332429D02*
X281212Y336653D01*
G01X294774Y349663D02*
X284637Y339938D01*
G01X276572Y332429D02*
X281260Y336927D01*
G01X276335Y332429D02*
X281308Y337200D01*
G01X276099Y332429D02*
X281356Y337472D01*
G01X276065Y332624D02*
X281403Y337746D01*
G01X276114Y332898D02*
X281452Y338019D01*
G01X276162Y333172D02*
X281500Y338292D01*
G01X276211Y333445D02*
X281547Y338565D01*
G01X275664Y333148D02*
X281596Y338838D01*
G01X282266Y342663D02*
X276933Y337546D01*
G01X282315Y342936D02*
X276980Y337819D01*
G01X282362Y343209D02*
X277028Y338092D01*
G01X282410Y343482D02*
X277076Y338366D01*
G01X282457Y343756D02*
X277124Y338639D01*
G01X282478Y344002D02*
X277172Y338912D01*
G01X282498Y344248D02*
X277220Y339185D01*
G01X282518Y344495D02*
X277268Y339459D01*
G01X282537Y344741D02*
X277158Y339581D01*
G01X282558Y344987D02*
X277018Y339672D01*
G01X282551Y345208D02*
X276866Y339754D01*
G01X282524Y345409D02*
X276710Y339833D01*
G01X282497Y345610D02*
X276546Y339902D01*
G01X282469Y345811D02*
X276374Y339964D01*
G01X282441Y346011D02*
X276195Y340019D01*
G01X287960Y333583D02*
X287911Y333309D01*
G01X288200Y334949D02*
X288247Y335222D01*
G01X288055Y334129D02*
X288007Y333856D01*
G01X287911Y333309D02*
X287862Y333035D01*
G01X288007Y333856D02*
X287960Y333583D01*
G01X288440Y336315D02*
X288489Y336589D01*
G01X288152Y334676D02*
X288104Y334402D01*
G01X288391Y336042D02*
X288440Y336315D01*
G01X288584Y337136D02*
X288633Y337409D01*
G01X288536Y336863D02*
X288584Y337136D01*
G01X288489Y336589D02*
X288536Y336863D01*
G01X288247Y335222D02*
X288296Y335496D01*
G01X288200Y334949D02*
X288152Y334676D01*
G01X288344Y335770D02*
X288391Y336042D01*
G01X288296Y335496D02*
X288344Y335770D01*
G01X288873Y338776D02*
X288920Y339049D01*
G01X288104Y334402D02*
X288055Y334129D01*
G01X288920Y339049D02*
X288969Y339322D01*
G01X289018Y339596D02*
X289065Y339869D01*
G01X288969Y339322D02*
X289018Y339596D01*
G01X288776Y338229D02*
X288825Y338502D01*
G01X288681Y337683D02*
X288729Y337956D01*
G01X288633Y337409D02*
X288681Y337683D01*
G01X288825Y338502D02*
X288873Y338776D01*
G01X288729Y337956D02*
X288776Y338229D01*
G01X289065Y339869D02*
X289113Y340143D01*
G01X283774Y335020D02*
X283725Y334747D01*
G01X283820Y335293D02*
X283774Y335020D01*
G01X283869Y335566D02*
X283820Y335293D01*
G01X283869Y335566D02*
X283918Y335839D01*
G01X283725Y334747D02*
X283677Y334473D01*
G01D02*
X283629Y334200D01*
G01X287468Y332429D02*
X287705D01*
G01X286994D02*
X287230D01*
G01D02*
X287468D01*
G01X286757D02*
X286994D01*
G01X286519D02*
X286757D01*
G01X283438Y333107D02*
X283389Y332834D01*
G01X283678Y332429D02*
X283914D01*
G01X286283D02*
X286519D01*
G01X283342Y332560D02*
X283318Y332429D01*
G01D02*
X283441D01*
G01X283389Y332834D02*
X283342Y332560D01*
G01X283629Y334200D02*
X283582Y333928D01*
G01D02*
X283533Y333654D01*
G01D02*
X283485Y333380D01*
G01D02*
X283438Y333107D01*
G01X283441Y332429D02*
X283678D01*
G01X285573D02*
X285809D01*
G01X286046D02*
X286283D01*
G01X285337D02*
X285573D01*
G01X285809D02*
X286046D01*
G01X284626D02*
X284862D01*
G01X284389D02*
X284626D01*
G01X284151D02*
X284389D01*
G01X285098D02*
X285337D01*
G01X284862D02*
X285098D01*
G01X283914D02*
X284151D01*
G01X284300Y338025D02*
X284253Y337752D01*
G01X284157Y337206D02*
X284109Y336933D01*
G01X284062Y336659D02*
X284013Y336386D01*
G01X284253Y337752D02*
X284206Y337479D01*
G01D02*
X284157Y337206D01*
G01X284109Y336933D02*
X284062Y336659D01*
G01X284013Y336386D02*
X283965Y336113D01*
G01D02*
X283918Y335839D01*
G01X284349Y338299D02*
X284300Y338025D01*
G01X284444Y338844D02*
X284397Y338572D01*
G01D02*
X284349Y338299D01*
G01X284541Y339392D02*
X284493Y339118D01*
G01X284637Y339938D02*
X284588Y339664D01*
G01D02*
X284541Y339392D01*
G01X284493Y339118D02*
X284444Y338844D01*
G01X287815Y332763D02*
X287767Y332490D01*
G01X287862Y333035D02*
X287815Y332763D01*
G01X287705Y332429D02*
X287756D01*
G01D02*
X287767Y332490D01*
G01X284684Y340211D02*
X284637Y339938D01*
G01X276980Y337819D02*
X276933Y337546D01*
G01X277220Y339185D02*
X277172Y338912D01*
G01X277268Y339459D02*
X277220Y339185D01*
G01X281547Y338565D02*
X281596Y338838D01*
G01X277124Y338639D02*
X277076Y338366D01*
G01D02*
X277028Y338092D01*
G01X277172Y338912D02*
X277124Y338639D01*
G01X277028Y338092D02*
X276980Y337819D01*
G01X281356Y337472D02*
X281403Y337746D01*
G01X278230Y332429D02*
X278467D01*
G01X278704D02*
X278940D01*
G01D02*
X279177D01*
G01X278467D02*
X278704D01*
G01X279888D02*
X280124D01*
G01D02*
X280362D01*
G01X279414D02*
X279652D01*
G01D02*
X279888D01*
G01X277994D02*
X278230D01*
G01X279177D02*
X279414D01*
G01X277757D02*
X277994D01*
G01X276572D02*
X276809D01*
G01X276335D02*
X276572D01*
G01X276065Y332624D02*
X276031Y332429D01*
G01D02*
X276099D01*
G01D02*
X276335D01*
G01X276114Y332898D02*
X276065Y332624D01*
G01X277519Y332429D02*
X277757D01*
G01X277045D02*
X277282D01*
G01X276809D02*
X277045D01*
G01X277282D02*
X277519D01*
G01X276211Y333445D02*
X276162Y333172D01*
G01D02*
X276114Y332898D01*
G01X281165Y336380D02*
X281212Y336653D01*
G01X281452Y338019D02*
X281500Y338292D01*
G01D02*
X281547Y338565D01*
G01X281308Y337200D02*
X281356Y337472D01*
G01X281403Y337746D02*
X281452Y338019D01*
G01X281643Y339112D02*
X281691Y339385D01*
G01X281596Y338838D02*
X281643Y339112D01*
G01X280972Y335287D02*
X281021Y335560D01*
G01X280782Y334195D02*
X280828Y334467D01*
G01X280926Y335014D02*
X280972Y335287D01*
G01X280877Y334741D02*
X280926Y335014D01*
G01X280828Y334467D02*
X280877Y334741D01*
G01X281116Y336107D02*
X281165Y336380D01*
G01X281212Y336653D02*
X281260Y336927D01*
G01D02*
X281308Y337200D01*
G01X281068Y335833D02*
X281116Y336107D01*
G01X281021Y335560D02*
X281068Y335833D01*
G01X281740Y339658D02*
X281787Y339931D01*
G01D02*
X281835Y340204D01*
G01X281691Y339385D02*
X281740Y339658D01*
G01X280733Y333922D02*
X280782Y334195D01*
G01X280362Y332429D02*
X280472D01*
G01D02*
X280495Y332555D01*
G01D02*
X280542Y332829D01*
G01X280638Y333375D02*
X280684Y333648D01*
G01D02*
X280733Y333922D01*
G01X280542Y332829D02*
X280590Y333102D01*
G01D02*
X280638Y333375D01*
G01X287705Y332429D02*
X287767Y332490D01*
G01X287468Y332429D02*
X287815Y332763D01*
G01X287230Y332429D02*
X287862Y333035D01*
G01X286994Y332429D02*
X287911Y333309D01*
G01X286757Y332429D02*
X287960Y333583D01*
G01X286519Y332429D02*
X288007Y333856D01*
G01X286283Y332429D02*
X288055Y334129D01*
G01X286046Y332429D02*
X288104Y334402D01*
G01X285809Y332429D02*
X288152Y334676D01*
G01X285573Y332429D02*
X288200Y334949D01*
G01X285337Y332429D02*
X288247Y335222D01*
G01X285098Y332429D02*
X288296Y335496D01*
G01X284862Y332429D02*
X288344Y335770D01*
G01X284626Y332429D02*
X288391Y336042D01*
G01X284389Y332429D02*
X288440Y336315D01*
G01X284151Y332429D02*
X288489Y336589D01*
G01X283914Y332429D02*
X288536Y336863D01*
G01X283678Y332429D02*
X288584Y337136D01*
G01X283441Y332429D02*
X288633Y337409D01*
G01X283342Y332560D02*
X288681Y337683D01*
G01X283389Y332834D02*
X288729Y337956D01*
G01X283438Y333107D02*
X288776Y338229D01*
G01X283485Y333380D02*
X288825Y338502D01*
G01X283533Y333654D02*
X288873Y338776D01*
G01X283582Y333928D02*
X288920Y339049D01*
G01X283629Y334200D02*
X288969Y339322D01*
G01X283677Y334473D02*
X289018Y339596D01*
G01X283725Y334747D02*
X289065Y339869D01*
G01X283774Y335020D02*
X289113Y340143D01*
G01X283820Y335293D02*
X289162Y340416D01*
G01X289209Y340689D02*
X283869Y335566D01*
G01X280362Y332429D02*
X280495Y332555D01*
G01X289257Y340962D02*
X283918Y335839D01*
G01X289305Y341236D02*
X283965Y336113D01*
G01X280124Y332429D02*
X280542Y332829D01*
G01X289354Y341509D02*
X284013Y336386D01*
G01X279888Y332429D02*
X280590Y333102D01*
G01X279652Y332429D02*
X280638Y333375D01*
G01X289408Y341789D02*
X284062Y336659D01*
G01X279414Y332429D02*
X280684Y333648D01*
G01X289474Y342079D02*
X284109Y336933D01*
G01X289539Y342368D02*
X284157Y337206D01*
G01X279177Y332429D02*
X280733Y333922D01*
G01X289602Y342656D02*
X284206Y337479D01*
G01X278940Y332429D02*
X280782Y334195D01*
G01X278704Y332429D02*
X280828Y334467D01*
G01X289720Y342996D02*
X284253Y337752D01*
G01X278467Y332429D02*
X280877Y334741D01*
G01X289840Y343339D02*
X284300Y338025D01*
G01X290030Y343748D02*
X284349Y338299D01*
G01X278230Y332429D02*
X280926Y335014D01*
G01X290344Y344277D02*
X284397Y338572D01*
G01X277994Y332429D02*
X280972Y335287D01*
G01X277757Y332429D02*
X281021Y335560D01*
G01X295639Y349584D02*
X284444Y338844D01*
G01X295422Y349604D02*
X284493Y339118D01*
G01X277519Y332429D02*
X281068Y335833D01*
G01X277282Y332429D02*
X281116Y336107D01*
G01X295207Y349623D02*
X284541Y339392D01*
G01X294991Y349644D02*
X284588Y339664D01*
G01X277045Y332429D02*
X281165Y336380D01*
G01X276809Y332429D02*
X281212Y336653D01*
G01X294774Y349663D02*
X284637Y339938D01*
G01X276572Y332429D02*
X281260Y336927D01*
G01X276335Y332429D02*
X281308Y337200D01*
G01X276099Y332429D02*
X281356Y337472D01*
G01X276065Y332624D02*
X281403Y337746D01*
G01X276114Y332898D02*
X281452Y338019D01*
G01X276162Y333172D02*
X281500Y338292D01*
G01X276211Y333445D02*
X281547Y338565D01*
G01X275664Y333148D02*
X281596Y338838D01*
G01X282266Y342663D02*
X276933Y337546D01*
G01X282315Y342936D02*
X276980Y337819D01*
G01X282362Y343209D02*
X277028Y338092D01*
G01X282410Y343482D02*
X277076Y338366D01*
G01X282457Y343756D02*
X277124Y338639D01*
G01X282478Y344002D02*
X277172Y338912D01*
G01X282498Y344248D02*
X277220Y339185D01*
G01X282518Y344495D02*
X277268Y339459D01*
G01X282537Y344741D02*
X277158Y339581D01*
G01X282558Y344987D02*
X277018Y339672D01*
G01X282551Y345208D02*
X276866Y339754D01*
G01X282524Y345409D02*
X276710Y339833D01*
G01X282497Y345610D02*
X276546Y339902D01*
G01X282469Y345811D02*
X276374Y339964D01*
G01X282441Y346011D02*
X276195Y340019D01*
G01X287960Y333583D02*
X287911Y333309D01*
G01X288200Y334949D02*
X288247Y335222D01*
G01X288055Y334129D02*
X288007Y333856D01*
G01X287911Y333309D02*
X287862Y333035D01*
G01X288007Y333856D02*
X287960Y333583D01*
G01X288440Y336315D02*
X288489Y336589D01*
G01X288152Y334676D02*
X288104Y334402D01*
G01X288391Y336042D02*
X288440Y336315D01*
G01X288584Y337136D02*
X288633Y337409D01*
G01X288536Y336863D02*
X288584Y337136D01*
G01X288489Y336589D02*
X288536Y336863D01*
G01X288247Y335222D02*
X288296Y335496D01*
G01X288200Y334949D02*
X288152Y334676D01*
G01X288344Y335770D02*
X288391Y336042D01*
G01X288296Y335496D02*
X288344Y335770D01*
G01X288873Y338776D02*
X288920Y339049D01*
G01X288104Y334402D02*
X288055Y334129D01*
G01X288920Y339049D02*
X288969Y339322D01*
G01X289018Y339596D02*
X289065Y339869D01*
G01X288969Y339322D02*
X289018Y339596D01*
G01X288776Y338229D02*
X288825Y338502D01*
G01X288681Y337683D02*
X288729Y337956D01*
G01X288633Y337409D02*
X288681Y337683D01*
G01X288825Y338502D02*
X288873Y338776D01*
G01X288729Y337956D02*
X288776Y338229D01*
G01X289065Y339869D02*
X289113Y340143D01*
G01X283774Y335020D02*
X283725Y334747D01*
G01X283820Y335293D02*
X283774Y335020D01*
G01X283869Y335566D02*
X283820Y335293D01*
G01X283869Y335566D02*
X283918Y335839D01*
G01X283725Y334747D02*
X283677Y334473D01*
G01D02*
X283629Y334200D01*
G01X287468Y332429D02*
X287705D01*
G01X286994D02*
X287230D01*
G01D02*
X287468D01*
G01X286757D02*
X286994D01*
G01X286519D02*
X286757D01*
G01X283438Y333107D02*
X283389Y332834D01*
G01X283678Y332429D02*
X283914D01*
G01X286283D02*
X286519D01*
G01X283342Y332560D02*
X283318Y332429D01*
G01D02*
X283441D01*
G01X283389Y332834D02*
X283342Y332560D01*
G01X283629Y334200D02*
X283582Y333928D01*
G01D02*
X283533Y333654D01*
G01D02*
X283485Y333380D01*
G01D02*
X283438Y333107D01*
G01X283441Y332429D02*
X283678D01*
G01X285573D02*
X285809D01*
G01X286046D02*
X286283D01*
G01X285337D02*
X285573D01*
G01X285809D02*
X286046D01*
G01X284626D02*
X284862D01*
G01X284389D02*
X284626D01*
G01X284151D02*
X284389D01*
G01X285098D02*
X285337D01*
G01X284862D02*
X285098D01*
G01X283914D02*
X284151D01*
G01X284300Y338025D02*
X284253Y337752D01*
G01X284157Y337206D02*
X284109Y336933D01*
G01X284062Y336659D02*
X284013Y336386D01*
G01X284253Y337752D02*
X284206Y337479D01*
G01D02*
X284157Y337206D01*
G01X284109Y336933D02*
X284062Y336659D01*
G01X284013Y336386D02*
X283965Y336113D01*
G01D02*
X283918Y335839D01*
G01X284349Y338299D02*
X284300Y338025D01*
G01X284444Y338844D02*
X284397Y338572D01*
G01D02*
X284349Y338299D01*
G01X284541Y339392D02*
X284493Y339118D01*
G01X284637Y339938D02*
X284588Y339664D01*
G01D02*
X284541Y339392D01*
G01X284493Y339118D02*
X284444Y338844D01*
G01X287815Y332763D02*
X287767Y332490D01*
G01X287862Y333035D02*
X287815Y332763D01*
G01X287705Y332429D02*
X287756D01*
G01D02*
X287767Y332490D01*
G01X284684Y340211D02*
X284637Y339938D01*
G01X276980Y337819D02*
X276933Y337546D01*
G01X277220Y339185D02*
X277172Y338912D01*
G01X277268Y339459D02*
X277220Y339185D01*
G01X281547Y338565D02*
X281596Y338838D01*
G01X277124Y338639D02*
X277076Y338366D01*
G01D02*
X277028Y338092D01*
G01X277172Y338912D02*
X277124Y338639D01*
G01X277028Y338092D02*
X276980Y337819D01*
G01X281356Y337472D02*
X281403Y337746D01*
G01X278230Y332429D02*
X278467D01*
G01X278704D02*
X278940D01*
G01D02*
X279177D01*
G01X278467D02*
X278704D01*
G01X279888D02*
X280124D01*
G01D02*
X280362D01*
G01X279414D02*
X279652D01*
G01D02*
X279888D01*
G01X277994D02*
X278230D01*
G01X279177D02*
X279414D01*
G01X277757D02*
X277994D01*
G01X276572D02*
X276809D01*
G01X276335D02*
X276572D01*
G01X276065Y332624D02*
X276031Y332429D01*
G01D02*
X276099D01*
G01D02*
X276335D01*
G01X276114Y332898D02*
X276065Y332624D01*
G01X277519Y332429D02*
X277757D01*
G01X277045D02*
X277282D01*
G01X276809D02*
X277045D01*
G01X277282D02*
X277519D01*
G01X276211Y333445D02*
X276162Y333172D01*
G01D02*
X276114Y332898D01*
G01X281165Y336380D02*
X281212Y336653D01*
G01X281452Y338019D02*
X281500Y338292D01*
G01D02*
X281547Y338565D01*
G01X281308Y337200D02*
X281356Y337472D01*
G01X281403Y337746D02*
X281452Y338019D01*
G01X281643Y339112D02*
X281691Y339385D01*
G01X281596Y338838D02*
X281643Y339112D01*
G01X280972Y335287D02*
X281021Y335560D01*
G01X280782Y334195D02*
X280828Y334467D01*
G01X280926Y335014D02*
X280972Y335287D01*
G01X280877Y334741D02*
X280926Y335014D01*
G01X280828Y334467D02*
X280877Y334741D01*
G01X281116Y336107D02*
X281165Y336380D01*
G01X281212Y336653D02*
X281260Y336927D01*
G01D02*
X281308Y337200D01*
G01X281068Y335833D02*
X281116Y336107D01*
G01X281021Y335560D02*
X281068Y335833D01*
G01X281740Y339658D02*
X281787Y339931D01*
G01D02*
X281835Y340204D01*
G01X281691Y339385D02*
X281740Y339658D01*
G01X280733Y333922D02*
X280782Y334195D01*
G01X280362Y332429D02*
X280472D01*
G01D02*
X280495Y332555D01*
G01D02*
X280542Y332829D01*
G01X280638Y333375D02*
X280684Y333648D01*
G01D02*
X280733Y333922D01*
G01X280542Y332829D02*
X280590Y333102D01*
G01D02*
X280638Y333375D01*
G01X294520Y349646D02*
X284684Y340211D01*
G01X294259Y349623D02*
X284732Y340484D01*
G01X293996Y349598D02*
X284781Y340757D01*
G01X293735Y349574D02*
X284828Y341030D01*
G01X293472Y349550D02*
X284876Y341304D01*
G01X293141Y349460D02*
X284924Y341577D01*
G01X292809Y349368D02*
X284972Y341850D01*
G01X292476Y349275D02*
X285019Y342123D01*
G01X292075Y349118D02*
X285068Y342397D01*
G01X291604Y348895D02*
X285116Y342670D01*
G01X290955Y348498D02*
X285163Y342943D01*
G01X290548Y348335D02*
X285212Y343216D01*
G01X290597Y348609D02*
X285261Y343490D01*
G01X290644Y348882D02*
X285307Y343763D01*
G01X290692Y349155D02*
X285356Y344036D01*
G01X282414Y346212D02*
X276005Y340065D01*
G01X282358Y346388D02*
X275810Y340106D01*
G01X282293Y346550D02*
X275606Y340136D01*
G01X282225Y346713D02*
X275397Y340163D01*
G01X282025Y347202D02*
X277937Y343281D01*
G01X281942Y347350D02*
X277984Y343554D01*
G01X281840Y347480D02*
X278031Y343827D01*
G01X281740Y347610D02*
X278057Y344078D01*
G01X289162Y340416D02*
X289113Y340143D01*
G01X289209Y340689D02*
X289162Y340416D01*
G01X289257Y340962D02*
X289209Y340689D01*
G01X289305Y341236D02*
X289257Y340962D01*
G01X285212Y343216D02*
X285163Y342943D01*
G01X289354Y341509D02*
X289305Y341236D01*
G01X285163Y342943D02*
X285116Y342670D01*
G01X284876Y341304D02*
X284828Y341030D01*
G01X284924Y341577D02*
X284876Y341304D01*
G01X284828Y341030D02*
X284781Y340757D01*
G01D02*
X284732Y340484D01*
G01D02*
X284684Y340211D01*
G01X285261Y343490D02*
X285212Y343216D01*
G01X285307Y343763D02*
X285261Y343490D01*
G01X285356Y344036D02*
X285307Y343763D01*
G01X285405Y344309D02*
X285356Y344036D01*
G01X285116Y342670D02*
X285068Y342397D01*
G01X285019Y342123D02*
X284972Y341850D01*
G01X285068Y342397D02*
X285019Y342123D01*
G01X284972Y341850D02*
X284924Y341577D01*
G01X282219Y342390D02*
X282171Y342116D01*
G01X282362Y343209D02*
X282315Y342936D01*
G01X282410Y343482D02*
X282362Y343209D01*
G01X282266Y342663D02*
X282219Y342390D01*
G01X282315Y342936D02*
X282266Y342663D01*
G01X282027Y341297D02*
X282075Y341571D01*
G01X281978Y341023D02*
X282027Y341297D01*
G01X282075Y341571D02*
X282122Y341843D01*
G01X282171Y342116D02*
X282122Y341843D01*
G01X281883Y340477D02*
X281931Y340751D01*
G01X281835Y340204D02*
X281883Y340477D01*
G01X281931Y340751D02*
X281978Y341023D01*
G01X277984Y343554D02*
X277937Y343281D01*
G01X278031Y343827D02*
X277984Y343554D01*
G01X294520Y349646D02*
X284684Y340211D01*
G01X294259Y349623D02*
X284732Y340484D01*
G01X293996Y349598D02*
X284781Y340757D01*
G01X293735Y349574D02*
X284828Y341030D01*
G01X293472Y349550D02*
X284876Y341304D01*
G01X293141Y349460D02*
X284924Y341577D01*
G01X292809Y349368D02*
X284972Y341850D01*
G01X292476Y349275D02*
X285019Y342123D01*
G01X292075Y349118D02*
X285068Y342397D01*
G01X291604Y348895D02*
X285116Y342670D01*
G01X290955Y348498D02*
X285163Y342943D01*
G01X290548Y348335D02*
X285212Y343216D01*
G01X290597Y348609D02*
X285261Y343490D01*
G01X290644Y348882D02*
X285307Y343763D01*
G01X290692Y349155D02*
X285356Y344036D01*
G01X282414Y346212D02*
X276005Y340065D01*
G01X282358Y346388D02*
X275810Y340106D01*
G01X282293Y346550D02*
X275606Y340136D01*
G01X282225Y346713D02*
X275397Y340163D01*
G01X282025Y347202D02*
X277937Y343281D01*
G01X281942Y347350D02*
X277984Y343554D01*
G01X281840Y347480D02*
X278031Y343827D01*
G01X281740Y347610D02*
X278057Y344078D01*
G01X289162Y340416D02*
X289113Y340143D01*
G01X289209Y340689D02*
X289162Y340416D01*
G01X289257Y340962D02*
X289209Y340689D01*
G01X289305Y341236D02*
X289257Y340962D01*
G01X285212Y343216D02*
X285163Y342943D01*
G01X289354Y341509D02*
X289305Y341236D01*
G01X285163Y342943D02*
X285116Y342670D01*
G01X284876Y341304D02*
X284828Y341030D01*
G01X284924Y341577D02*
X284876Y341304D01*
G01X284828Y341030D02*
X284781Y340757D01*
G01D02*
X284732Y340484D01*
G01D02*
X284684Y340211D01*
G01X285261Y343490D02*
X285212Y343216D01*
G01X285307Y343763D02*
X285261Y343490D01*
G01X285356Y344036D02*
X285307Y343763D01*
G01X285405Y344309D02*
X285356Y344036D01*
G01X285116Y342670D02*
X285068Y342397D01*
G01X285019Y342123D02*
X284972Y341850D01*
G01X285068Y342397D02*
X285019Y342123D01*
G01X284972Y341850D02*
X284924Y341577D01*
G01X282219Y342390D02*
X282171Y342116D01*
G01X282362Y343209D02*
X282315Y342936D01*
G01X282410Y343482D02*
X282362Y343209D01*
G01X282266Y342663D02*
X282219Y342390D01*
G01X282315Y342936D02*
X282266Y342663D01*
G01X282027Y341297D02*
X282075Y341571D01*
G01X281978Y341023D02*
X282027Y341297D01*
G01X282075Y341571D02*
X282122Y341843D01*
G01X282171Y342116D02*
X282122Y341843D01*
G01X281883Y340477D02*
X281931Y340751D01*
G01X281835Y340204D02*
X281883Y340477D01*
G01X281931Y340751D02*
X281978Y341023D01*
G01X277984Y343554D02*
X277937Y343281D01*
G01X278031Y343827D02*
X277984Y343554D01*
G01X290621Y349314D02*
X285405Y344309D01*
G01X290384Y349314D02*
X285451Y344582D01*
G01X290146Y349314D02*
X285499Y344856D01*
G01X289910Y349314D02*
X285548Y345129D01*
G01X289674Y349314D02*
X285596Y345402D01*
G01X289437Y349314D02*
X285643Y345675D01*
G01X289200Y349314D02*
X285692Y345949D01*
G01X281638Y347740D02*
X278071Y344319D01*
G01X281536Y347870D02*
X278050Y344525D01*
G01X281436Y348000D02*
X278020Y344724D01*
G01X281333Y348131D02*
X277962Y344896D01*
G01X281201Y348230D02*
X277901Y345064D01*
G01X281070Y348331D02*
X277810Y345204D01*
G01X280937Y348431D02*
X277718Y345343D01*
G01X280804Y348531D02*
X277602Y345459D01*
G01X280671Y348631D02*
X277479Y345568D01*
G01X280539Y348731D02*
X277344Y345666D01*
G01X280397Y348821D02*
X277191Y345746D01*
G01X280234Y348893D02*
X277037Y345826D01*
G01X280071Y348965D02*
X276854Y345878D01*
G01X279910Y349037D02*
X276669Y345927D01*
G01X279748Y349108D02*
X276470Y345964D01*
G01X279586Y349180D02*
X276251Y345981D01*
G01X279424Y349252D02*
X276032Y345998D01*
G01X279243Y349305D02*
X275794Y345996D01*
G01X279051Y349349D02*
X275551Y345992D01*
G01X278860Y349393D02*
X275309Y345987D01*
G01X285692Y345949D02*
X285740Y346222D01*
G01X285596Y345402D02*
X285548Y345129D01*
G01D02*
X285499Y344856D01*
G01X285643Y345675D02*
X285692Y345949D01*
G01X285596Y345402D02*
X285643Y345675D01*
G01X285499Y344856D02*
X285451Y344582D01*
G01D02*
X285405Y344309D01*
G01X290621Y349314D02*
X285405Y344309D01*
G01X290384Y349314D02*
X285451Y344582D01*
G01X290146Y349314D02*
X285499Y344856D01*
G01X289910Y349314D02*
X285548Y345129D01*
G01X289674Y349314D02*
X285596Y345402D01*
G01X289437Y349314D02*
X285643Y345675D01*
G01X289200Y349314D02*
X285692Y345949D01*
G01X281638Y347740D02*
X278071Y344319D01*
G01X281536Y347870D02*
X278050Y344525D01*
G01X281436Y348000D02*
X278020Y344724D01*
G01X281333Y348131D02*
X277962Y344896D01*
G01X281201Y348230D02*
X277901Y345064D01*
G01X281070Y348331D02*
X277810Y345204D01*
G01X280937Y348431D02*
X277718Y345343D01*
G01X280804Y348531D02*
X277602Y345459D01*
G01X280671Y348631D02*
X277479Y345568D01*
G01X280539Y348731D02*
X277344Y345666D01*
G01X280397Y348821D02*
X277191Y345746D01*
G01X280234Y348893D02*
X277037Y345826D01*
G01X280071Y348965D02*
X276854Y345878D01*
G01X279910Y349037D02*
X276669Y345927D01*
G01X279748Y349108D02*
X276470Y345964D01*
G01X279586Y349180D02*
X276251Y345981D01*
G01X279424Y349252D02*
X276032Y345998D01*
G01X279243Y349305D02*
X275794Y345996D01*
G01X279051Y349349D02*
X275551Y345992D01*
G01X278860Y349393D02*
X275309Y345987D01*
G01X285692Y345949D02*
X285740Y346222D01*
G01X285596Y345402D02*
X285548Y345129D01*
G01D02*
X285499Y344856D01*
G01X285643Y345675D02*
X285692Y345949D01*
G01X285596Y345402D02*
X285643Y345675D01*
G01X285499Y344856D02*
X285451Y344582D01*
G01D02*
X285405Y344309D01*
G01X288964Y349314D02*
X285740Y346222D01*
G01X288726Y349314D02*
X285787Y346495D01*
G01X288489Y349314D02*
X285836Y346768D01*
G01X288253Y349314D02*
X285883Y347041D01*
G01X288015Y349314D02*
X285931Y347315D01*
G01X287778Y349314D02*
X285980Y347587D01*
G01X287542Y349314D02*
X286027Y347861D01*
G01X287305Y349314D02*
X286075Y348135D01*
G01X287067Y349314D02*
X286123Y348407D01*
G01X286831Y349314D02*
X286171Y348681D01*
G01X286594Y349314D02*
X286218Y348954D01*
G01X286357Y349314D02*
X286267Y349227D01*
G01X289910Y349314D02*
X289674D01*
G01D02*
X289437D01*
G01X288015D02*
X287778D01*
G01X286831D02*
X286594D01*
G01X287305D02*
X287067D01*
G01X289437D02*
X289200D01*
G01X287542D02*
X287305D01*
G01X287778D02*
X287542D01*
G01X287067D02*
X286831D01*
G01X288726D02*
X288489D01*
G01X288964D02*
X288726D01*
G01X288253D02*
X288015D01*
G01X289200D02*
X288964D01*
G01X286594D02*
X286357D01*
G01X288489D02*
X288253D01*
G01X285740Y346222D02*
X285787Y346495D01*
G01X285836Y346768D02*
X285883Y347041D01*
G01D02*
X285931Y347315D01*
G01X285787Y346495D02*
X285836Y346768D01*
G01X286357Y349314D02*
X286282D01*
G01D02*
X286267Y349227D01*
G01X286218Y348954D02*
X286267Y349227D01*
G01X285980Y347587D02*
X286027Y347861D01*
G01X285931Y347315D02*
X285980Y347587D01*
G01X286171Y348681D02*
X286218Y348954D01*
G01X286027Y347861D02*
X286075Y348135D01*
G01D02*
X286123Y348407D01*
G01D02*
X286171Y348681D01*
G01X288964Y349314D02*
X285740Y346222D01*
G01X288726Y349314D02*
X285787Y346495D01*
G01X288489Y349314D02*
X285836Y346768D01*
G01X288253Y349314D02*
X285883Y347041D01*
G01X288015Y349314D02*
X285931Y347315D01*
G01X287778Y349314D02*
X285980Y347587D01*
G01X287542Y349314D02*
X286027Y347861D01*
G01X287305Y349314D02*
X286075Y348135D01*
G01X287067Y349314D02*
X286123Y348407D01*
G01X286831Y349314D02*
X286171Y348681D01*
G01X286594Y349314D02*
X286218Y348954D01*
G01X286357Y349314D02*
X286267Y349227D01*
G01X289910Y349314D02*
X289674D01*
G01D02*
X289437D01*
G01X288015D02*
X287778D01*
G01X286831D02*
X286594D01*
G01X287305D02*
X287067D01*
G01X289437D02*
X289200D01*
G01X287542D02*
X287305D01*
G01X287778D02*
X287542D01*
G01X287067D02*
X286831D01*
G01X288726D02*
X288489D01*
G01X288964D02*
X288726D01*
G01X288253D02*
X288015D01*
G01X289200D02*
X288964D01*
G01X286594D02*
X286357D01*
G01X288489D02*
X288253D01*
G01X285740Y346222D02*
X285787Y346495D01*
G01X285836Y346768D02*
X285883Y347041D01*
G01D02*
X285931Y347315D01*
G01X285787Y346495D02*
X285836Y346768D01*
G01X286357Y349314D02*
X286282D01*
G01D02*
X286267Y349227D01*
G01X286218Y348954D02*
X286267Y349227D01*
G01X285980Y347587D02*
X286027Y347861D01*
G01X285931Y347315D02*
X285980Y347587D01*
G01X286171Y348681D02*
X286218Y348954D01*
G01X286027Y347861D02*
X286075Y348135D01*
G01D02*
X286123Y348407D01*
G01D02*
X286171Y348681D01*
G01X290146Y349314D02*
X289910D01*
G01X290146D02*
X289910D01*
G01X296000Y-560138D02*
Y-635138D01*
G01X294000Y-560138D02*
Y-635138D01*
G01X301507Y-620138D02*
Y-615138D01*
X302773D01*
X303280Y-615388D01*
X303660Y-615721D01*
X303977Y-616221D01*
X304230Y-616805D01*
X304293Y-617638D01*
X304230Y-618471D01*
X303977Y-619055D01*
X303660Y-619555D01*
X303280Y-619888D01*
X302773Y-620138D01*
X301507D01*
G01X306417D02*
X308000Y-615138D01*
X309583Y-620138D01*
G01X309013Y-618388D02*
X306987D01*
G01X313100Y-615138D02*
Y-620138D01*
G01X311643Y-615138D02*
X314557D01*
G01X319467Y-620138D02*
X316933D01*
Y-615138D01*
X319467D01*
G01X318453Y-617555D02*
X316933D01*
G01X323300Y-620305D02*
X323173Y-620221D01*
Y-620055D01*
X323300Y-619971D01*
X323427Y-620055D01*
Y-620221D01*
X323300Y-620305D01*
G01Y-618055D02*
X323173Y-617971D01*
Y-617805D01*
X323300Y-617721D01*
X323427Y-617805D01*
Y-617971D01*
X323300Y-618055D01*
G01X296000Y-610138D02*
X496000D01*
G01X301633Y-595138D02*
Y-590138D01*
X303153D01*
X303660Y-590388D01*
X304040Y-590971D01*
X304167Y-591638D01*
X304040Y-592305D01*
X303723Y-592805D01*
X303153Y-593055D01*
X301633D01*
G01X306860Y-595305D02*
X309140Y-590138D01*
G01X311643Y-595138D02*
Y-590138D01*
X314557Y-595138D01*
Y-590138D01*
G01X318200Y-595305D02*
X318073Y-595221D01*
Y-595055D01*
X318200Y-594971D01*
X318327Y-595055D01*
Y-595221D01*
X318200Y-595305D01*
G01Y-593055D02*
X318073Y-592971D01*
Y-592805D01*
X318200Y-592721D01*
X318327Y-592805D01*
Y-592971D01*
X318200Y-593055D01*
G01X296000Y-585138D02*
X496000D01*
G01X301633Y-570138D02*
Y-565138D01*
X303153D01*
X303660Y-565388D01*
X304040Y-565971D01*
X304167Y-566638D01*
X304040Y-567305D01*
X303723Y-567805D01*
X303153Y-568055D01*
X301633D01*
G01X306733Y-570138D02*
Y-565138D01*
X308317D01*
X308823Y-565388D01*
X309140Y-565721D01*
X309267Y-566388D01*
X309140Y-567055D01*
X308760Y-567471D01*
X308317Y-567721D01*
X306733D01*
G01X308317D02*
X309267Y-570138D01*
G01X313100D02*
X312593Y-570055D01*
X312150Y-569721D01*
X311770Y-569221D01*
X311517Y-568638D01*
X311390Y-567971D01*
Y-567305D01*
X311517Y-566638D01*
X311770Y-566055D01*
X312150Y-565555D01*
X312593Y-565221D01*
X313100Y-565138D01*
X313607Y-565221D01*
X314050Y-565555D01*
X314430Y-566055D01*
X314683Y-566638D01*
X314810Y-567305D01*
Y-567971D01*
X314683Y-568638D01*
X314430Y-569221D01*
X314050Y-569721D01*
X313607Y-570055D01*
X313100Y-570138D01*
G01X316933Y-569138D02*
X317250Y-569638D01*
X317630Y-569971D01*
X318073Y-570138D01*
X318580Y-569971D01*
X318960Y-569638D01*
X319340Y-569138D01*
X319467Y-568471D01*
Y-565138D01*
G01X324567Y-570138D02*
X322033D01*
Y-565138D01*
X324567D01*
G01X323553Y-567555D02*
X322033D01*
G01X329793Y-565555D02*
X329413Y-565305D01*
X328970Y-565138D01*
X328463D01*
X327893Y-565388D01*
X327450Y-565805D01*
X327133Y-566305D01*
X326880Y-567138D01*
X326817Y-567888D01*
X326943Y-568638D01*
X327133Y-569138D01*
X327513Y-569638D01*
X327957Y-569971D01*
X328400Y-570138D01*
X328843D01*
X329287Y-569971D01*
X329667Y-569721D01*
X329983Y-569388D01*
G01X333500Y-565138D02*
Y-570138D01*
G01X332043Y-565138D02*
X334957D01*
G01X338600Y-570305D02*
X338473Y-570221D01*
Y-570055D01*
X338600Y-569971D01*
X338727Y-570055D01*
Y-570221D01*
X338600Y-570305D01*
G01Y-568055D02*
X338473Y-567971D01*
Y-567805D01*
X338600Y-567721D01*
X338727Y-567805D01*
Y-567971D01*
X338600Y-568055D01*
G01X304651Y333009D02*
X308466Y336667D01*
G01X304541Y333131D02*
X308366Y336799D01*
G01X304431Y333252D02*
X308289Y336952D01*
G01X304321Y333374D02*
X308238Y337131D01*
G01X304212Y333496D02*
X308201Y337322D01*
G01X304129Y333644D02*
X308194Y337542D01*
G01X304050Y333795D02*
X308192Y337769D01*
G01X303970Y333945D02*
X308221Y338022D01*
G01X303890Y334096D02*
X308253Y338281D01*
G01X303810Y334247D02*
X308297Y338551D01*
G01X303761Y334427D02*
X308346Y338824D01*
G01X303712Y334607D02*
X308393Y339097D01*
G01X303664Y334788D02*
X308442Y339371D01*
G01X303615Y334969D02*
X308489Y339645D01*
G01X303573Y335155D02*
X308537Y339917D01*
G01X303559Y335368D02*
X308586Y340190D01*
G01X303544Y335581D02*
X308633Y340464D01*
G01X303529Y335795D02*
X308682Y340738D01*
G01X303514Y336008D02*
X308729Y341010D01*
G01X303524Y336244D02*
X308777Y341283D01*
G01X303548Y336495D02*
X308826Y341557D01*
G01X303574Y336747D02*
X308873Y341830D01*
G01X303598Y336997D02*
X308922Y342104D01*
G01X303632Y337256D02*
X308970Y342376D01*
G01X303680Y337529D02*
X309017Y342650D01*
G01X303727Y337803D02*
X309066Y342924D01*
G01X309113Y343197D02*
X303776Y338076D01*
G01X297888Y332429D02*
X297964Y332501D01*
G01X303824Y338349D02*
X309162Y343469D01*
G01X297652Y332429D02*
X298013Y332775D01*
G01X303871Y338622D02*
X309210Y343743D01*
G01X297416Y332429D02*
X298061Y333048D01*
G01X297178Y332429D02*
X298108Y333321D01*
G01X303920Y338896D02*
X309258Y344017D01*
G01X296942Y332429D02*
X298157Y333594D01*
G01X303967Y339169D02*
X309306Y344289D01*
G01X304015Y339441D02*
X309353Y344563D01*
G01X296706Y332429D02*
X298204Y333867D01*
G01X296468Y332429D02*
X298252Y334141D01*
G01X304062Y339715D02*
X309402Y344836D01*
G01X304111Y339988D02*
X309450Y345110D01*
G01X296231Y332429D02*
X298301Y334415D01*
G01X295995Y332429D02*
X298348Y334687D01*
G01X295757Y332429D02*
X298396Y334960D01*
G01X295520Y332429D02*
X298444Y335234D01*
G01X295284Y332429D02*
X298492Y335507D01*
G01X295047Y332429D02*
X298539Y335780D01*
G01X294809Y332429D02*
X298588Y336053D01*
G01X294573Y332429D02*
X298636Y336326D01*
G01X294336Y332429D02*
X298683Y336600D01*
G01X294099Y332429D02*
X298732Y336872D01*
G01X293863Y332429D02*
X298779Y337146D01*
G01X293625Y332429D02*
X298827Y337419D01*
G01X293534Y332569D02*
X298876Y337693D01*
G01X293583Y332842D02*
X298923Y337965D01*
G01X293631Y333115D02*
X298971Y338238D01*
G01X293678Y333389D02*
X299019Y338511D01*
G01X293727Y333662D02*
X299067Y338785D01*
G01X293775Y333935D02*
X299114Y339058D01*
G01X293822Y334208D02*
X299163Y339331D01*
G01X293871Y334482D02*
X299211Y339605D01*
G01X293920Y334756D02*
X299258Y339878D01*
G01X293967Y335028D02*
X299307Y340151D01*
G01X294015Y335302D02*
X299354Y340424D01*
G01X294063Y335575D02*
X299402Y340697D01*
G01X294111Y335849D02*
X299451Y340971D01*
G01X294158Y336122D02*
X299498Y341244D01*
G01X294207Y336395D02*
X299546Y341516D01*
G01X294256Y336668D02*
X299595Y341790D01*
G01X294303Y336941D02*
X299635Y342057D01*
G01X294351Y337215D02*
X299666Y342314D01*
G01X294400Y337488D02*
X299698Y342570D01*
G01X294447Y337761D02*
X299729Y342828D01*
G01X294495Y338035D02*
X299760Y343086D01*
G01X294544Y338308D02*
X299793Y343343D01*
G01X294591Y338581D02*
X299822Y343600D01*
G01X294638Y338855D02*
X299828Y343832D01*
G01X299825Y344057D02*
X294687Y339128D01*
G01X294736Y339401D02*
X299824Y344283D01*
G01X294784Y339674D02*
X299822Y344508D01*
G01X294831Y339948D02*
X299820Y344734D01*
G01X303727Y337803D02*
X303680Y337529D01*
G01X304159Y340261D02*
X304111Y339988D01*
G01D02*
X304062Y339715D01*
G01D02*
X304015Y339441D01*
G01X303967Y339169D02*
X303920Y338896D01*
G01D02*
X303871Y338622D01*
G01X304015Y339441D02*
X303967Y339169D01*
G01X303871Y338622D02*
X303824Y338349D01*
G01X303727Y337803D02*
X303776Y338076D01*
G01X303824Y338349D02*
X303776Y338076D01*
G01X303680Y337529D02*
X303632Y337256D01*
G01X295284Y332429D02*
X295520D01*
G01X295995D02*
X296231D01*
G01X295757D02*
X295995D01*
G01X295520D02*
X295757D01*
G01X296231D02*
X296468D01*
G01D02*
X296706D01*
G01D02*
X296942D01*
G01X293583Y332842D02*
X293534Y332569D01*
G01X293631Y333115D02*
X293583Y332842D01*
G01X293625Y332429D02*
X293863D01*
G01D02*
X294099D01*
G01X293678Y333389D02*
X293631Y333115D01*
G01X293534Y332569D02*
X293510Y332429D01*
G01D02*
X293625D01*
G01X293775Y333935D02*
X293727Y333662D01*
G01D02*
X293678Y333389D01*
G01X295047Y332429D02*
X295284D01*
G01X294099D02*
X294336D01*
G01X294809D02*
X295047D01*
G01X294336D02*
X294573D01*
G01D02*
X294809D01*
G01X293822Y334208D02*
X293775Y333935D01*
G01X294158Y336122D02*
X294111Y335849D01*
G01X294591Y338581D02*
X294544Y338308D01*
G01D02*
X294495Y338035D01*
G01X294400Y337488D02*
X294351Y337215D01*
G01X294447Y337761D02*
X294400Y337488D01*
G01X294495Y338035D02*
X294447Y337761D01*
G01X294063Y335575D02*
X294015Y335302D01*
G01D02*
X293967Y335028D01*
G01X294351Y337215D02*
X294303Y336941D01*
G01X293967Y335028D02*
X293920Y334756D01*
G01D02*
X293871Y334482D01*
G01X294303Y336941D02*
X294256Y336668D01*
G01D02*
X294207Y336395D01*
G01X293871Y334482D02*
X293822Y334208D01*
G01X294111Y335849D02*
X294063Y335575D01*
G01X294207Y336395D02*
X294158Y336122D01*
G01X294638Y338855D02*
X294591Y338581D01*
G01X294880Y340221D02*
X294831Y339948D01*
G01X294736Y339401D02*
X294687Y339128D01*
G01X294831Y339948D02*
X294784Y339674D01*
G01X298157Y333594D02*
X298108Y333321D01*
G01X298061Y333048D02*
X298013Y332775D01*
G01X298683Y336600D02*
X298636Y336326D01*
G01X298108Y333321D02*
X298061Y333048D01*
G01X298732Y336872D02*
X298683Y336600D01*
G01X298827Y337419D02*
X298779Y337146D01*
G01X298013Y332775D02*
X297964Y332501D01*
G01X298876Y337693D02*
X298827Y337419D01*
G01X298779Y337146D02*
X298732Y336872D01*
G01X297888Y332429D02*
X297952D01*
G01D02*
X297964Y332501D01*
G01X298396Y334960D02*
X298348Y334687D01*
G01X298492Y335507D02*
X298444Y335234D01*
G01D02*
X298396Y334960D01*
G01X298539Y335780D02*
X298492Y335507D01*
G01X298588Y336053D02*
X298539Y335780D01*
G01X298252Y334141D02*
X298204Y333867D01*
G01X298636Y336326D02*
X298588Y336053D01*
G01X298204Y333867D02*
X298157Y333594D01*
G01X298301Y334415D02*
X298252Y334141D01*
G01X298348Y334687D02*
X298301Y334415D01*
G01X299211Y339605D02*
X299163Y339331D01*
G01X299307Y340151D02*
X299258Y339878D01*
G01X298923Y337965D02*
X298876Y337693D01*
G01X297178Y332429D02*
X297416D01*
G01X296942D02*
X297178D01*
G01X297416D02*
X297652D01*
G01X299067Y338785D02*
X299019Y338511D01*
G01X299114Y339058D02*
X299067Y338785D01*
G01X299019Y338511D02*
X298971Y338238D01*
G01D02*
X298923Y337965D01*
G01X297652Y332429D02*
X297888D01*
G01X299258Y339878D02*
X299211Y339605D01*
G01X299163Y339331D02*
X299114Y339058D01*
G01X294638Y338855D02*
X294687Y339128D01*
G01X294784Y339674D02*
X294736Y339401D01*
G01X304651Y333009D02*
X308466Y336667D01*
G01X304541Y333131D02*
X308366Y336799D01*
G01X304431Y333252D02*
X308289Y336952D01*
G01X304321Y333374D02*
X308238Y337131D01*
G01X304212Y333496D02*
X308201Y337322D01*
G01X304129Y333644D02*
X308194Y337542D01*
G01X304050Y333795D02*
X308192Y337769D01*
G01X303970Y333945D02*
X308221Y338022D01*
G01X303890Y334096D02*
X308253Y338281D01*
G01X303810Y334247D02*
X308297Y338551D01*
G01X303761Y334427D02*
X308346Y338824D01*
G01X303712Y334607D02*
X308393Y339097D01*
G01X303664Y334788D02*
X308442Y339371D01*
G01X303615Y334969D02*
X308489Y339645D01*
G01X303573Y335155D02*
X308537Y339917D01*
G01X303559Y335368D02*
X308586Y340190D01*
G01X303544Y335581D02*
X308633Y340464D01*
G01X303529Y335795D02*
X308682Y340738D01*
G01X303514Y336008D02*
X308729Y341010D01*
G01X303524Y336244D02*
X308777Y341283D01*
G01X303548Y336495D02*
X308826Y341557D01*
G01X303574Y336747D02*
X308873Y341830D01*
G01X303598Y336997D02*
X308922Y342104D01*
G01X303632Y337256D02*
X308970Y342376D01*
G01X303680Y337529D02*
X309017Y342650D01*
G01X303727Y337803D02*
X309066Y342924D01*
G01X309113Y343197D02*
X303776Y338076D01*
G01X297888Y332429D02*
X297964Y332501D01*
G01X303824Y338349D02*
X309162Y343469D01*
G01X297652Y332429D02*
X298013Y332775D01*
G01X303871Y338622D02*
X309210Y343743D01*
G01X297416Y332429D02*
X298061Y333048D01*
G01X297178Y332429D02*
X298108Y333321D01*
G01X303920Y338896D02*
X309258Y344017D01*
G01X296942Y332429D02*
X298157Y333594D01*
G01X303967Y339169D02*
X309306Y344289D01*
G01X304015Y339441D02*
X309353Y344563D01*
G01X296706Y332429D02*
X298204Y333867D01*
G01X296468Y332429D02*
X298252Y334141D01*
G01X304062Y339715D02*
X309402Y344836D01*
G01X304111Y339988D02*
X309450Y345110D01*
G01X296231Y332429D02*
X298301Y334415D01*
G01X295995Y332429D02*
X298348Y334687D01*
G01X295757Y332429D02*
X298396Y334960D01*
G01X295520Y332429D02*
X298444Y335234D01*
G01X295284Y332429D02*
X298492Y335507D01*
G01X295047Y332429D02*
X298539Y335780D01*
G01X294809Y332429D02*
X298588Y336053D01*
G01X294573Y332429D02*
X298636Y336326D01*
G01X294336Y332429D02*
X298683Y336600D01*
G01X294099Y332429D02*
X298732Y336872D01*
G01X293863Y332429D02*
X298779Y337146D01*
G01X293625Y332429D02*
X298827Y337419D01*
G01X293534Y332569D02*
X298876Y337693D01*
G01X293583Y332842D02*
X298923Y337965D01*
G01X293631Y333115D02*
X298971Y338238D01*
G01X293678Y333389D02*
X299019Y338511D01*
G01X293727Y333662D02*
X299067Y338785D01*
G01X293775Y333935D02*
X299114Y339058D01*
G01X293822Y334208D02*
X299163Y339331D01*
G01X293871Y334482D02*
X299211Y339605D01*
G01X293920Y334756D02*
X299258Y339878D01*
G01X293967Y335028D02*
X299307Y340151D01*
G01X294015Y335302D02*
X299354Y340424D01*
G01X294063Y335575D02*
X299402Y340697D01*
G01X294111Y335849D02*
X299451Y340971D01*
G01X294158Y336122D02*
X299498Y341244D01*
G01X294207Y336395D02*
X299546Y341516D01*
G01X294256Y336668D02*
X299595Y341790D01*
G01X294303Y336941D02*
X299635Y342057D01*
G01X294351Y337215D02*
X299666Y342314D01*
G01X294400Y337488D02*
X299698Y342570D01*
G01X294447Y337761D02*
X299729Y342828D01*
G01X294495Y338035D02*
X299760Y343086D01*
G01X294544Y338308D02*
X299793Y343343D01*
G01X294591Y338581D02*
X299822Y343600D01*
G01X294638Y338855D02*
X299828Y343832D01*
G01X299825Y344057D02*
X294687Y339128D01*
G01X294736Y339401D02*
X299824Y344283D01*
G01X294784Y339674D02*
X299822Y344508D01*
G01X294831Y339948D02*
X299820Y344734D01*
G01X303727Y337803D02*
X303680Y337529D01*
G01X304159Y340261D02*
X304111Y339988D01*
G01D02*
X304062Y339715D01*
G01D02*
X304015Y339441D01*
G01X303967Y339169D02*
X303920Y338896D01*
G01D02*
X303871Y338622D01*
G01X304015Y339441D02*
X303967Y339169D01*
G01X303871Y338622D02*
X303824Y338349D01*
G01X303727Y337803D02*
X303776Y338076D01*
G01X303824Y338349D02*
X303776Y338076D01*
G01X303680Y337529D02*
X303632Y337256D01*
G01X295284Y332429D02*
X295520D01*
G01X295995D02*
X296231D01*
G01X295757D02*
X295995D01*
G01X295520D02*
X295757D01*
G01X296231D02*
X296468D01*
G01D02*
X296706D01*
G01D02*
X296942D01*
G01X293583Y332842D02*
X293534Y332569D01*
G01X293631Y333115D02*
X293583Y332842D01*
G01X293625Y332429D02*
X293863D01*
G01D02*
X294099D01*
G01X293678Y333389D02*
X293631Y333115D01*
G01X293534Y332569D02*
X293510Y332429D01*
G01D02*
X293625D01*
G01X293775Y333935D02*
X293727Y333662D01*
G01D02*
X293678Y333389D01*
G01X295047Y332429D02*
X295284D01*
G01X294099D02*
X294336D01*
G01X294809D02*
X295047D01*
G01X294336D02*
X294573D01*
G01D02*
X294809D01*
G01X293822Y334208D02*
X293775Y333935D01*
G01X294158Y336122D02*
X294111Y335849D01*
G01X294591Y338581D02*
X294544Y338308D01*
G01D02*
X294495Y338035D01*
G01X294400Y337488D02*
X294351Y337215D01*
G01X294447Y337761D02*
X294400Y337488D01*
G01X294495Y338035D02*
X294447Y337761D01*
G01X294063Y335575D02*
X294015Y335302D01*
G01D02*
X293967Y335028D01*
G01X294351Y337215D02*
X294303Y336941D01*
G01X293967Y335028D02*
X293920Y334756D01*
G01D02*
X293871Y334482D01*
G01X294303Y336941D02*
X294256Y336668D01*
G01D02*
X294207Y336395D01*
G01X293871Y334482D02*
X293822Y334208D01*
G01X294111Y335849D02*
X294063Y335575D01*
G01X294207Y336395D02*
X294158Y336122D01*
G01X294638Y338855D02*
X294591Y338581D01*
G01X294880Y340221D02*
X294831Y339948D01*
G01X294736Y339401D02*
X294687Y339128D01*
G01X294831Y339948D02*
X294784Y339674D01*
G01X298157Y333594D02*
X298108Y333321D01*
G01X298061Y333048D02*
X298013Y332775D01*
G01X298683Y336600D02*
X298636Y336326D01*
G01X298108Y333321D02*
X298061Y333048D01*
G01X298732Y336872D02*
X298683Y336600D01*
G01X298827Y337419D02*
X298779Y337146D01*
G01X298013Y332775D02*
X297964Y332501D01*
G01X298876Y337693D02*
X298827Y337419D01*
G01X298779Y337146D02*
X298732Y336872D01*
G01X297888Y332429D02*
X297952D01*
G01D02*
X297964Y332501D01*
G01X298396Y334960D02*
X298348Y334687D01*
G01X298492Y335507D02*
X298444Y335234D01*
G01D02*
X298396Y334960D01*
G01X298539Y335780D02*
X298492Y335507D01*
G01X298588Y336053D02*
X298539Y335780D01*
G01X298252Y334141D02*
X298204Y333867D01*
G01X298636Y336326D02*
X298588Y336053D01*
G01X298204Y333867D02*
X298157Y333594D01*
G01X298301Y334415D02*
X298252Y334141D01*
G01X298348Y334687D02*
X298301Y334415D01*
G01X299211Y339605D02*
X299163Y339331D01*
G01X299307Y340151D02*
X299258Y339878D01*
G01X298923Y337965D02*
X298876Y337693D01*
G01X297178Y332429D02*
X297416D01*
G01X296942D02*
X297178D01*
G01X297416D02*
X297652D01*
G01X299067Y338785D02*
X299019Y338511D01*
G01X299114Y339058D02*
X299067Y338785D01*
G01X299019Y338511D02*
X298971Y338238D01*
G01D02*
X298923Y337965D01*
G01X297652Y332429D02*
X297888D01*
G01X299258Y339878D02*
X299211Y339605D01*
G01X299163Y339331D02*
X299114Y339058D01*
G01X294638Y338855D02*
X294687Y339128D01*
G01X294784Y339674D02*
X294736Y339401D01*
G01X304159Y340261D02*
X313596Y349314D01*
G01X313360D02*
X304206Y340534D01*
G01X313123Y349314D02*
X304255Y340808D01*
G01X312885Y349314D02*
X304302Y341081D01*
G01X312648Y349314D02*
X304350Y341354D01*
G01X312412Y349314D02*
X304399Y341626D01*
G01X312175Y349314D02*
X304446Y341900D01*
G01X311937Y349314D02*
X304494Y342174D01*
G01X311701Y349314D02*
X304542Y342447D01*
G01X311464Y349314D02*
X304590Y342719D01*
G01X311228Y349314D02*
X304637Y342993D01*
G01X310990Y349314D02*
X304686Y343266D01*
G01X294880Y340221D02*
X299820Y344959D01*
G01X294927Y340494D02*
X299814Y345181D01*
G01X294975Y340767D02*
X299779Y345375D01*
G01X295024Y341041D02*
X299744Y345569D01*
G01X299708Y345763D02*
X295073Y341314D01*
G01X299675Y345956D02*
X295119Y341586D01*
G01X299639Y346150D02*
X295151Y341845D01*
G01X299605Y346344D02*
X295186Y342105D01*
G01X299559Y346529D02*
X295219Y342365D01*
G01X299491Y346690D02*
X295250Y342621D01*
G01X299424Y346852D02*
X295252Y342850D01*
G01X299354Y347013D02*
X295254Y343080D01*
G01X299285Y347175D02*
X295257Y343309D01*
G01X299217Y347336D02*
X295246Y343526D01*
G01X299150Y347497D02*
X295214Y343722D01*
G01X299066Y347646D02*
X295181Y343918D01*
G01X304734Y343539D02*
X304686Y343266D01*
G01X304255Y340808D02*
X304206Y340534D01*
G01X304350Y341354D02*
X304302Y341081D01*
G01D02*
X304255Y340808D01*
G01X304206Y340534D02*
X304159Y340261D01*
G01X304399Y341626D02*
X304350Y341354D01*
G01X304542Y342447D02*
X304494Y342174D01*
G01X304590Y342719D02*
X304542Y342447D01*
G01X304637Y342993D02*
X304590Y342719D01*
G01X304686Y343266D02*
X304637Y342993D01*
G01X304446Y341900D02*
X304399Y341626D01*
G01X304494Y342174D02*
X304446Y341900D01*
G01X295073Y341314D02*
X295024Y341041D01*
G01X299498Y341244D02*
X299451Y340971D01*
G01X299546Y341516D02*
X299498Y341244D01*
G01X295024Y341041D02*
X294975Y340767D01*
G01X299402Y340697D02*
X299354Y340424D01*
G01D02*
X299307Y340151D01*
G01X299451Y340971D02*
X299402Y340697D01*
G01X294927Y340494D02*
X294880Y340221D01*
G01X299595Y341790D02*
X299546Y341516D01*
G01X294975Y340767D02*
X294927Y340494D01*
G01X304159Y340261D02*
X313596Y349314D01*
G01X313360D02*
X304206Y340534D01*
G01X313123Y349314D02*
X304255Y340808D01*
G01X312885Y349314D02*
X304302Y341081D01*
G01X312648Y349314D02*
X304350Y341354D01*
G01X312412Y349314D02*
X304399Y341626D01*
G01X312175Y349314D02*
X304446Y341900D01*
G01X311937Y349314D02*
X304494Y342174D01*
G01X311701Y349314D02*
X304542Y342447D01*
G01X311464Y349314D02*
X304590Y342719D01*
G01X311228Y349314D02*
X304637Y342993D01*
G01X310990Y349314D02*
X304686Y343266D01*
G01X294880Y340221D02*
X299820Y344959D01*
G01X294927Y340494D02*
X299814Y345181D01*
G01X294975Y340767D02*
X299779Y345375D01*
G01X295024Y341041D02*
X299744Y345569D01*
G01X299708Y345763D02*
X295073Y341314D01*
G01X299675Y345956D02*
X295119Y341586D01*
G01X299639Y346150D02*
X295151Y341845D01*
G01X299605Y346344D02*
X295186Y342105D01*
G01X299559Y346529D02*
X295219Y342365D01*
G01X299491Y346690D02*
X295250Y342621D01*
G01X299424Y346852D02*
X295252Y342850D01*
G01X299354Y347013D02*
X295254Y343080D01*
G01X299285Y347175D02*
X295257Y343309D01*
G01X299217Y347336D02*
X295246Y343526D01*
G01X299150Y347497D02*
X295214Y343722D01*
G01X299066Y347646D02*
X295181Y343918D01*
G01X304734Y343539D02*
X304686Y343266D01*
G01X304255Y340808D02*
X304206Y340534D01*
G01X304350Y341354D02*
X304302Y341081D01*
G01D02*
X304255Y340808D01*
G01X304206Y340534D02*
X304159Y340261D01*
G01X304399Y341626D02*
X304350Y341354D01*
G01X304542Y342447D02*
X304494Y342174D01*
G01X304590Y342719D02*
X304542Y342447D01*
G01X304637Y342993D02*
X304590Y342719D01*
G01X304686Y343266D02*
X304637Y342993D01*
G01X304446Y341900D02*
X304399Y341626D01*
G01X304494Y342174D02*
X304446Y341900D01*
G01X295073Y341314D02*
X295024Y341041D01*
G01X299498Y341244D02*
X299451Y340971D01*
G01X299546Y341516D02*
X299498Y341244D01*
G01X295024Y341041D02*
X294975Y340767D01*
G01X299402Y340697D02*
X299354Y340424D01*
G01D02*
X299307Y340151D01*
G01X299451Y340971D02*
X299402Y340697D01*
G01X294927Y340494D02*
X294880Y340221D01*
G01X299595Y341790D02*
X299546Y341516D01*
G01X294975Y340767D02*
X294927Y340494D01*
G01X304907Y332799D02*
X308735Y336471D01*
G01X304766Y332891D02*
X308583Y336553D01*
G01X304907Y332799D02*
X308735Y336471D01*
G01X304766Y332891D02*
X308583Y336553D01*
G01X310753Y349314D02*
X304734Y343539D01*
G01X310517Y349314D02*
X304781Y343812D01*
G01D02*
X304734Y343539D01*
G01X304830Y344085D02*
X304781Y343812D01*
G01X310753Y349314D02*
X304734Y343539D01*
G01X310517Y349314D02*
X304781Y343812D01*
G01D02*
X304734Y343539D01*
G01X304830Y344085D02*
X304781Y343812D01*
G01X296071Y349544D02*
X291615Y345269D01*
G01X295855Y349564D02*
X291153Y345053D01*
G01X296071Y349544D02*
X291615Y345269D01*
G01X295855Y349564D02*
X291153Y345053D01*
G01X304499Y345132D02*
X310453Y350844D01*
G01X304263Y345132D02*
X310502Y351117D01*
G01X304026Y345132D02*
X310550Y351391D01*
G01X303788Y345132D02*
X310599Y351664D01*
G01X303552Y345132D02*
X310646Y351937D01*
G01X303315Y345132D02*
X310693Y352210D01*
G01X303079Y345132D02*
X310742Y352484D01*
G01X302842Y345132D02*
X310790Y352758D01*
G01X302604Y345132D02*
X310837Y353030D01*
G01X302368Y345132D02*
X310886Y353303D01*
G01X302195Y345193D02*
X310934Y353577D01*
G01X310982Y353851D02*
X302242Y345467D01*
G01X311030Y354124D02*
X302291Y345740D01*
G01X311079Y354396D02*
X302338Y346013D01*
G01X298962Y347774D02*
X295148Y344114D01*
G01X298859Y347902D02*
X295082Y344278D01*
G01X298756Y348030D02*
X295013Y344438D01*
G01X298653Y348159D02*
X294942Y344598D01*
G01X298550Y348287D02*
X294847Y344736D01*
G01X298447Y348415D02*
X294739Y344858D01*
G01X298328Y348527D02*
X294630Y344981D01*
G01X298188Y348621D02*
X294503Y345086D01*
G01X298048Y348714D02*
X294354Y345170D01*
G01X297910Y348809D02*
X294207Y345256D01*
G01X297772Y348902D02*
X294040Y345323D01*
G01X297633Y348997D02*
X293855Y345372D01*
G01X297494Y349091D02*
X293667Y345421D01*
G01X297332Y349163D02*
X293464Y345452D01*
G01X297157Y349222D02*
X293243Y345467D01*
G01X296980Y349280D02*
X293022Y345482D01*
G01X296803Y349338D02*
X292779Y345477D01*
G01X296627Y349396D02*
X292524Y345459D01*
G01X296451Y349454D02*
X292268Y345440D01*
G01X296274Y349512D02*
X291952Y345365D01*
G01X303552Y345132D02*
X303788D01*
G01X303315D02*
X303552D01*
G01X303079D02*
X303315D01*
G01X304263D02*
X304499D01*
G01X303788D02*
X304026D01*
G01D02*
X304263D01*
G01X304499D02*
X304736D01*
G01X302842D02*
X303079D01*
G01X302291Y345740D02*
X302242Y345467D01*
G01X302338Y346013D02*
X302291Y345740D01*
G01X302242Y345467D02*
X302195Y345193D01*
G01X302338Y346013D02*
X302387Y346287D01*
G01X302604Y345132D02*
X302842D01*
G01X302195Y345193D02*
X302184Y345132D01*
G01D02*
X302368D01*
G01D02*
X302604D01*
G01X304499D02*
X310453Y350844D01*
G01X304263Y345132D02*
X310502Y351117D01*
G01X304026Y345132D02*
X310550Y351391D01*
G01X303788Y345132D02*
X310599Y351664D01*
G01X303552Y345132D02*
X310646Y351937D01*
G01X303315Y345132D02*
X310693Y352210D01*
G01X303079Y345132D02*
X310742Y352484D01*
G01X302842Y345132D02*
X310790Y352758D01*
G01X302604Y345132D02*
X310837Y353030D01*
G01X302368Y345132D02*
X310886Y353303D01*
G01X302195Y345193D02*
X310934Y353577D01*
G01X310982Y353851D02*
X302242Y345467D01*
G01X311030Y354124D02*
X302291Y345740D01*
G01X311079Y354396D02*
X302338Y346013D01*
G01X298962Y347774D02*
X295148Y344114D01*
G01X298859Y347902D02*
X295082Y344278D01*
G01X298756Y348030D02*
X295013Y344438D01*
G01X298653Y348159D02*
X294942Y344598D01*
G01X298550Y348287D02*
X294847Y344736D01*
G01X298447Y348415D02*
X294739Y344858D01*
G01X298328Y348527D02*
X294630Y344981D01*
G01X298188Y348621D02*
X294503Y345086D01*
G01X298048Y348714D02*
X294354Y345170D01*
G01X297910Y348809D02*
X294207Y345256D01*
G01X297772Y348902D02*
X294040Y345323D01*
G01X297633Y348997D02*
X293855Y345372D01*
G01X297494Y349091D02*
X293667Y345421D01*
G01X297332Y349163D02*
X293464Y345452D01*
G01X297157Y349222D02*
X293243Y345467D01*
G01X296980Y349280D02*
X293022Y345482D01*
G01X296803Y349338D02*
X292779Y345477D01*
G01X296627Y349396D02*
X292524Y345459D01*
G01X296451Y349454D02*
X292268Y345440D01*
G01X296274Y349512D02*
X291952Y345365D01*
G01X303552Y345132D02*
X303788D01*
G01X303315D02*
X303552D01*
G01X303079D02*
X303315D01*
G01X304263D02*
X304499D01*
G01X303788D02*
X304026D01*
G01D02*
X304263D01*
G01X304499D02*
X304736D01*
G01X302842D02*
X303079D01*
G01X302291Y345740D02*
X302242Y345467D01*
G01X302338Y346013D02*
X302291Y345740D01*
G01X302242Y345467D02*
X302195Y345193D01*
G01X302338Y346013D02*
X302387Y346287D01*
G01X302604Y345132D02*
X302842D01*
G01X302195Y345193D02*
X302184Y345132D01*
G01D02*
X302368D01*
G01D02*
X302604D01*
G01X290692Y349155D02*
X290720Y349314D01*
G01D02*
X290621D01*
G01X290644Y348882D02*
X290692Y349155D01*
G01X290548Y348335D02*
X290597Y348609D01*
G01D02*
X290644Y348882D01*
G01X290621Y349314D02*
X290384D01*
G01D02*
X290146D01*
G01X290692Y349155D02*
X290720Y349314D01*
G01D02*
X290621D01*
G01X290644Y348882D02*
X290692Y349155D01*
G01X290548Y348335D02*
X290597Y348609D01*
G01D02*
X290644Y348882D01*
G01X290621Y349314D02*
X290384D01*
G01D02*
X290146D01*
G01X302387Y346287D02*
X305542Y349314D01*
G01X302435Y346560D02*
X305306Y349314D01*
G01X302482Y346833D02*
X305069Y349314D01*
G01X302531Y347106D02*
X304833Y349314D01*
G01X302578Y347380D02*
X304595Y349314D01*
G01X302627Y347653D02*
X304358Y349314D01*
G01X302675Y347926D02*
X304122Y349314D01*
G01X302724Y348199D02*
X303885Y349314D01*
G01X303647D02*
X302771Y348473D01*
G01X302819Y348746D02*
X303411Y349314D01*
G01X302867Y349020D02*
X303174Y349314D01*
G01X302915Y349292D02*
X302938Y349314D01*
G01X302482Y346833D02*
X302531Y347106D01*
G01X302819Y348746D02*
X302867Y349020D01*
G01X302771Y348473D02*
X302724Y348199D01*
G01X302819Y348746D02*
X302771Y348473D01*
G01X302578Y347380D02*
X302627Y347653D01*
G01X302675Y347926D02*
X302724Y348199D01*
G01X302627Y347653D02*
X302675Y347926D01*
G01X302435Y346560D02*
X302482Y346833D01*
G01X302387Y346287D02*
X302435Y346560D01*
G01X302531Y347106D02*
X302578Y347380D01*
G01X304595Y349314D02*
X304358D01*
G01X304833D02*
X304595D01*
G01X302867Y349020D02*
X302915Y349292D01*
G01D02*
X302919Y349314D01*
G01D02*
X302938D01*
G01X303411D02*
X303174D01*
G01D02*
X302938D01*
G01X304122D02*
X303885D01*
G01X304358D02*
X304122D01*
G01X303411D02*
X303647D01*
G01D02*
X303885D01*
G01X302387Y346287D02*
X305542Y349314D01*
G01X302435Y346560D02*
X305306Y349314D01*
G01X302482Y346833D02*
X305069Y349314D01*
G01X302531Y347106D02*
X304833Y349314D01*
G01X302578Y347380D02*
X304595Y349314D01*
G01X302627Y347653D02*
X304358Y349314D01*
G01X302675Y347926D02*
X304122Y349314D01*
G01X302724Y348199D02*
X303885Y349314D01*
G01X303647D02*
X302771Y348473D01*
G01X302819Y348746D02*
X303411Y349314D01*
G01X302867Y349020D02*
X303174Y349314D01*
G01X302915Y349292D02*
X302938Y349314D01*
G01X302482Y346833D02*
X302531Y347106D01*
G01X302819Y348746D02*
X302867Y349020D01*
G01X302771Y348473D02*
X302724Y348199D01*
G01X302819Y348746D02*
X302771Y348473D01*
G01X302578Y347380D02*
X302627Y347653D01*
G01X302675Y347926D02*
X302724Y348199D01*
G01X302627Y347653D02*
X302675Y347926D01*
G01X302435Y346560D02*
X302482Y346833D01*
G01X302387Y346287D02*
X302435Y346560D01*
G01X302531Y347106D02*
X302578Y347380D01*
G01X304595Y349314D02*
X304358D01*
G01X304833D02*
X304595D01*
G01X302867Y349020D02*
X302915Y349292D01*
G01D02*
X302919Y349314D01*
G01D02*
X302938D01*
G01X303411D02*
X303174D01*
G01D02*
X302938D01*
G01X304122D02*
X303885D01*
G01X304358D02*
X304122D01*
G01X303411D02*
X303647D01*
G01D02*
X303885D01*
G01X310280D02*
X304830Y344085D01*
G01X304877Y344359D02*
X310213Y349478D01*
G01X310262Y349751D02*
X304925Y344632D01*
G01X310310Y350024D02*
X304974Y344904D01*
G01Y345132D02*
X310357Y350297D01*
G01X304736Y345132D02*
X310406Y350571D01*
G01X304974Y345132D02*
X305013D01*
G01D02*
X304974Y344904D01*
G01X304877Y344359D02*
X304830Y344085D01*
G01X304736Y345132D02*
X304974D01*
G01Y344904D02*
X304925Y344632D01*
G01D02*
X304877Y344359D01*
G01X310280Y349314D02*
X304830Y344085D01*
G01X304877Y344359D02*
X310213Y349478D01*
G01X310262Y349751D02*
X304925Y344632D01*
G01X310310Y350024D02*
X304974Y344904D01*
G01Y345132D02*
X310357Y350297D01*
G01X304736Y345132D02*
X310406Y350571D01*
G01X304974Y345132D02*
X305013D01*
G01D02*
X304974Y344904D01*
G01X304877Y344359D02*
X304830Y344085D01*
G01X304736Y345132D02*
X304974D01*
G01Y344904D02*
X304925Y344632D01*
G01D02*
X304877Y344359D01*
G01X305069Y349314D02*
X304833D01*
G01X305069D02*
X304833D01*
G01X319556Y332083D02*
X329681Y341796D01*
G01X319328Y332091D02*
X329730Y342069D01*
G01X329777Y342342D02*
X319105Y332105D01*
G01X318894Y332129D02*
X323531Y336578D01*
G01X318684Y332155D02*
X322959Y336256D01*
G01X318482Y332187D02*
X322578Y336117D01*
G01X318286Y332227D02*
X322197Y335978D01*
G01X318091Y332267D02*
X321914Y335936D01*
G01X317905Y332318D02*
X321642Y335902D01*
G01X317725Y332371D02*
X321371Y335869D01*
G01X317544Y332425D02*
X321102Y335838D01*
G01X317375Y332490D02*
X320882Y335854D01*
G01X317208Y332558D02*
X320663Y335871D01*
G01X317041Y332625D02*
X320446Y335890D01*
G01X316885Y332702D02*
X320260Y335939D01*
G01X316732Y332783D02*
X320074Y335987D01*
G01X316580Y332864D02*
X319896Y336046D01*
G01X316435Y332952D02*
X319744Y336126D01*
G01X316298Y333046D02*
X319591Y336206D01*
G01X316158Y333141D02*
X319458Y336307D01*
G01X316025Y333241D02*
X319339Y336419D01*
G01X315902Y333348D02*
X319222Y336535D01*
G01X315777Y333456D02*
X319135Y336678D01*
G01X315655Y333567D02*
X319050Y336823D01*
G01X315545Y333689D02*
X318990Y336994D01*
G01X315437Y333811D02*
X318939Y337171D01*
G01X315327Y333934D02*
X318910Y337370D01*
G01X315232Y334069D02*
X318894Y337583D01*
G01X315137Y334206D02*
X318906Y337822D01*
G01X315043Y334343D02*
X318932Y338073D01*
G01X314960Y334491D02*
X319050Y338414D01*
G01X314883Y334644D02*
X319176Y338762D01*
G01X314806Y334797D02*
X319838Y339625D01*
G01X314735Y334957D02*
X323716Y343571D01*
G01X314676Y335127D02*
X323515Y343606D01*
G01X314616Y335297D02*
X323306Y343634D01*
G01X314562Y335472D02*
X323082Y343645D01*
G01X314521Y335660D02*
X322857Y343657D01*
G01X314482Y335848D02*
X322633Y343669D01*
G01X314444Y336039D02*
X322410Y343681D01*
G01X314425Y336249D02*
X322165Y343675D01*
G01X314406Y336458D02*
X321913Y343659D01*
G01X310430Y332872D02*
X310923Y333344D01*
G01X321659Y343644D02*
X314388Y336668D01*
G01X309946Y332634D02*
X311027Y333672D01*
G01X314394Y336901D02*
X321406Y343627D01*
G01X314399Y337133D02*
X321152Y343612D01*
G01X309560Y332491D02*
X311132Y333999D01*
G01X314406Y337367D02*
X320896Y343593D01*
G01X309188Y332361D02*
X311235Y334326D01*
G01X308880Y332292D02*
X311339Y334652D01*
G01X314438Y337626D02*
X320599Y343535D01*
G01X308571Y332224D02*
X311444Y334979D01*
G01X314472Y337885D02*
X320300Y343476D01*
G01X308263Y332156D02*
X311548Y335307D01*
G01X314516Y338155D02*
X320002Y343417D01*
G01X308005Y332135D02*
X311651Y335633D01*
G01X314602Y338465D02*
X319705Y343359D01*
G01X307747Y332116D02*
X311755Y335960D01*
G01X314689Y338775D02*
X319362Y343258D01*
G01X307490Y332097D02*
X311859Y336287D01*
G01X314777Y339086D02*
X318987Y343126D01*
G01X314864Y339397D02*
X318613Y342993D01*
G01X307232Y332075D02*
X311963Y336615D01*
G01X315099Y339850D02*
X318190Y342816D01*
G01X307018Y332097D02*
X312067Y336941D01*
G01X306803Y332118D02*
X312171Y337268D01*
G01X306588Y332140D02*
X312275Y337595D01*
G01X306374Y332162D02*
X311422Y337004D01*
G01X306180Y332202D02*
X310830Y336663D01*
G01X306005Y332262D02*
X310417Y336494D01*
G01X305830Y332320D02*
X310063Y336382D01*
G01X305653Y332380D02*
X309793Y336350D01*
G01X305480Y332438D02*
X309527Y336322D01*
G01X305331Y332522D02*
X309303Y336334D01*
G01X305189Y332615D02*
X309093Y336360D01*
G01X305047Y332707D02*
X308899Y336402D01*
G01X311651Y335633D02*
X311548Y335307D01*
G01X311755Y335960D02*
X311651Y335633D01*
G01X311548Y335307D02*
X311444Y334979D01*
G01X311859Y336287D02*
X311755Y335960D01*
G01X311444Y334979D02*
X311339Y334652D01*
G01X311963Y336615D02*
X311859Y336287D01*
G01X311339Y334652D02*
X311235Y334326D01*
G01D02*
X311132Y333999D01*
G01D02*
X311027Y333672D01*
G01X312067Y336941D02*
X311963Y336615D01*
G01X312171Y337268D02*
X312067Y336941D01*
G01X312275Y337595D02*
X312171Y337268D01*
G01X311027Y333672D02*
X310923Y333344D01*
G01X308393Y339097D02*
X308346Y338824D01*
G01D02*
X308297Y338551D01*
G01X308442Y339371D02*
X308489Y339645D01*
G01D02*
X308537Y339917D01*
G01X308442Y339371D02*
X308393Y339097D01*
G01X308537Y339917D02*
X308586Y340190D01*
G01X319556Y332083D02*
X329681Y341796D01*
G01X319328Y332091D02*
X329730Y342069D01*
G01X329777Y342342D02*
X319105Y332105D01*
G01X318894Y332129D02*
X323531Y336578D01*
G01X318684Y332155D02*
X322959Y336256D01*
G01X318482Y332187D02*
X322578Y336117D01*
G01X318286Y332227D02*
X322197Y335978D01*
G01X318091Y332267D02*
X321914Y335936D01*
G01X317905Y332318D02*
X321642Y335902D01*
G01X317725Y332371D02*
X321371Y335869D01*
G01X317544Y332425D02*
X321102Y335838D01*
G01X317375Y332490D02*
X320882Y335854D01*
G01X317208Y332558D02*
X320663Y335871D01*
G01X317041Y332625D02*
X320446Y335890D01*
G01X316885Y332702D02*
X320260Y335939D01*
G01X316732Y332783D02*
X320074Y335987D01*
G01X316580Y332864D02*
X319896Y336046D01*
G01X316435Y332952D02*
X319744Y336126D01*
G01X316298Y333046D02*
X319591Y336206D01*
G01X316158Y333141D02*
X319458Y336307D01*
G01X316025Y333241D02*
X319339Y336419D01*
G01X315902Y333348D02*
X319222Y336535D01*
G01X315777Y333456D02*
X319135Y336678D01*
G01X315655Y333567D02*
X319050Y336823D01*
G01X315545Y333689D02*
X318990Y336994D01*
G01X315437Y333811D02*
X318939Y337171D01*
G01X315327Y333934D02*
X318910Y337370D01*
G01X315232Y334069D02*
X318894Y337583D01*
G01X315137Y334206D02*
X318906Y337822D01*
G01X315043Y334343D02*
X318932Y338073D01*
G01X314960Y334491D02*
X319050Y338414D01*
G01X314883Y334644D02*
X319176Y338762D01*
G01X314806Y334797D02*
X319838Y339625D01*
G01X314735Y334957D02*
X323716Y343571D01*
G01X314676Y335127D02*
X323515Y343606D01*
G01X314616Y335297D02*
X323306Y343634D01*
G01X314562Y335472D02*
X323082Y343645D01*
G01X314521Y335660D02*
X322857Y343657D01*
G01X314482Y335848D02*
X322633Y343669D01*
G01X314444Y336039D02*
X322410Y343681D01*
G01X314425Y336249D02*
X322165Y343675D01*
G01X314406Y336458D02*
X321913Y343659D01*
G01X310430Y332872D02*
X310923Y333344D01*
G01X321659Y343644D02*
X314388Y336668D01*
G01X309946Y332634D02*
X311027Y333672D01*
G01X314394Y336901D02*
X321406Y343627D01*
G01X314399Y337133D02*
X321152Y343612D01*
G01X309560Y332491D02*
X311132Y333999D01*
G01X314406Y337367D02*
X320896Y343593D01*
G01X309188Y332361D02*
X311235Y334326D01*
G01X308880Y332292D02*
X311339Y334652D01*
G01X314438Y337626D02*
X320599Y343535D01*
G01X308571Y332224D02*
X311444Y334979D01*
G01X314472Y337885D02*
X320300Y343476D01*
G01X308263Y332156D02*
X311548Y335307D01*
G01X314516Y338155D02*
X320002Y343417D01*
G01X308005Y332135D02*
X311651Y335633D01*
G01X314602Y338465D02*
X319705Y343359D01*
G01X307747Y332116D02*
X311755Y335960D01*
G01X314689Y338775D02*
X319362Y343258D01*
G01X307490Y332097D02*
X311859Y336287D01*
G01X314777Y339086D02*
X318987Y343126D01*
G01X314864Y339397D02*
X318613Y342993D01*
G01X307232Y332075D02*
X311963Y336615D01*
G01X315099Y339850D02*
X318190Y342816D01*
G01X307018Y332097D02*
X312067Y336941D01*
G01X306803Y332118D02*
X312171Y337268D01*
G01X306588Y332140D02*
X312275Y337595D01*
G01X306374Y332162D02*
X311422Y337004D01*
G01X306180Y332202D02*
X310830Y336663D01*
G01X306005Y332262D02*
X310417Y336494D01*
G01X305830Y332320D02*
X310063Y336382D01*
G01X305653Y332380D02*
X309793Y336350D01*
G01X305480Y332438D02*
X309527Y336322D01*
G01X305331Y332522D02*
X309303Y336334D01*
G01X305189Y332615D02*
X309093Y336360D01*
G01X305047Y332707D02*
X308899Y336402D01*
G01X311651Y335633D02*
X311548Y335307D01*
G01X311755Y335960D02*
X311651Y335633D01*
G01X311548Y335307D02*
X311444Y334979D01*
G01X311859Y336287D02*
X311755Y335960D01*
G01X311444Y334979D02*
X311339Y334652D01*
G01X311963Y336615D02*
X311859Y336287D01*
G01X311339Y334652D02*
X311235Y334326D01*
G01D02*
X311132Y333999D01*
G01D02*
X311027Y333672D01*
G01X312067Y336941D02*
X311963Y336615D01*
G01X312171Y337268D02*
X312067Y336941D01*
G01X312275Y337595D02*
X312171Y337268D01*
G01X311027Y333672D02*
X310923Y333344D01*
G01X308393Y339097D02*
X308346Y338824D01*
G01D02*
X308297Y338551D01*
G01X308442Y339371D02*
X308489Y339645D01*
G01D02*
X308537Y339917D01*
G01X308442Y339371D02*
X308393Y339097D01*
G01X308537Y339917D02*
X308586Y340190D01*
G01X315338Y340305D02*
X317641Y342515D01*
G01X309258Y344017D02*
X309306Y344289D01*
G01X309210Y343743D02*
X309258Y344017D01*
G01X308970Y342376D02*
X309017Y342650D01*
G01X309113Y343197D02*
X309066Y342924D01*
G01D02*
X309017Y342650D01*
G01X308633Y340464D02*
X308682Y340738D01*
G01X309162Y343469D02*
X309210Y343743D01*
G01X308586Y340190D02*
X308633Y340464D01*
G01X309113Y343197D02*
X309162Y343469D01*
G01X308873Y341830D02*
X308922Y342104D01*
G01X308682Y340738D02*
X308729Y341010D01*
G01X308826Y341557D02*
X308873Y341830D01*
G01X308729Y341010D02*
X308777Y341283D01*
G01D02*
X308826Y341557D01*
G01X308922Y342104D02*
X308970Y342376D01*
G01X315338Y340305D02*
X317641Y342515D01*
G01X309258Y344017D02*
X309306Y344289D01*
G01X309210Y343743D02*
X309258Y344017D01*
G01X308970Y342376D02*
X309017Y342650D01*
G01X309113Y343197D02*
X309066Y342924D01*
G01D02*
X309017Y342650D01*
G01X308633Y340464D02*
X308682Y340738D01*
G01X309162Y343469D02*
X309210Y343743D01*
G01X308586Y340190D02*
X308633Y340464D01*
G01X309113Y343197D02*
X309162Y343469D01*
G01X308873Y341830D02*
X308922Y342104D01*
G01X308682Y340738D02*
X308729Y341010D01*
G01X308826Y341557D02*
X308873Y341830D01*
G01X308729Y341010D02*
X308777Y341283D01*
G01D02*
X308826Y341557D01*
G01X308922Y342104D02*
X308970Y342376D01*
G01X319789Y332080D02*
X329633Y341523D01*
G01X319877Y339662D02*
X323915Y343536D01*
G01X319789Y332080D02*
X329633Y341523D01*
G01X319877Y339662D02*
X323915Y343536D01*
G01X319534Y345240D02*
X324147Y349665D01*
G01X319085Y345037D02*
X323903Y349658D01*
G01X318726Y344919D02*
X323659Y349652D01*
G01X318662Y345086D02*
X323415Y349645D01*
G01X318600Y345252D02*
X323166Y349634D01*
G01X318537Y345420D02*
X322906Y349610D01*
G01X318473Y345587D02*
X322644Y349587D01*
G01X318411Y345754D02*
X322382Y349564D01*
G01X318349Y345920D02*
X322104Y349523D01*
G01X318285Y346087D02*
X321821Y349478D01*
G01X313507Y345138D02*
X313500Y345132D01*
G01X313554Y345412D02*
X313262Y345132D01*
G01X313601Y345684D02*
X313026Y345132D01*
G01X313650Y345957D02*
X312790Y345132D01*
G01X313698Y346230D02*
X312553Y345132D01*
G01X313745Y346504D02*
X312316Y345132D01*
G01X313793Y346777D02*
X312080Y345132D01*
G01X313842Y347050D02*
X311842Y345132D01*
G01X313889Y347323D02*
X311605Y345132D01*
G01X313936Y347597D02*
X311368Y345132D01*
G01X313984Y347869D02*
X311132Y345132D01*
G01X314033Y348142D02*
X310896Y345132D01*
G01X314080Y348415D02*
X310658Y345132D01*
G01X314128Y348689D02*
X310421Y345132D01*
G01X314177Y348961D02*
X310183Y345132D01*
G01X314224Y349234D02*
X309947Y345132D01*
G01X314069Y349314D02*
X309710Y345132D01*
G01X309450Y345110D02*
X309473Y345132D01*
G01X313832Y349314D02*
X309473Y345132D01*
G01X318662Y345086D02*
X318726Y344919D01*
G01X318600Y345252D02*
X318662Y345086D01*
G01X318285Y346087D02*
X318349Y345920D01*
G01D02*
X318411Y345754D01*
G01X318222Y346255D02*
X318285Y346087D01*
G01X318537Y345420D02*
X318600Y345252D01*
G01X318473Y345587D02*
X318537Y345420D01*
G01X318411Y345754D02*
X318473Y345587D01*
G01X309306Y344289D02*
X309353Y344563D01*
G01D02*
X309402Y344836D01*
G01X313507Y345138D02*
X313554Y345412D01*
G01X311605Y345132D02*
X311842D01*
G01X311368D02*
X311605D01*
G01X311132D02*
X310896D01*
G01X311132D02*
X311368D01*
G01X311842D02*
X312080D01*
G01X312553D02*
X312790D01*
G01X312080D02*
X312316D01*
G01D02*
X312553D01*
G01X310896D02*
X310658D01*
G01X313554Y345412D02*
X313601Y345684D01*
G01X310421Y345132D02*
X310183D01*
G01X313650Y345957D02*
X313698Y346230D01*
G01X310658Y345132D02*
X310421D01*
G01X310183D02*
X309947D01*
G01X309710D02*
X309473D01*
G01X313601Y345684D02*
X313650Y345957D01*
G01X309947Y345132D02*
X309710D01*
G01X313507Y345138D02*
X313505Y345132D01*
G01D02*
X313500D01*
G01X313262D02*
X313500D01*
G01X313026D02*
X313262D01*
G01X312790D02*
X313026D01*
G01X309402Y344836D02*
X309450Y345110D01*
G01D02*
X309454Y345132D01*
G01D02*
X309473D01*
G01X319534Y345240D02*
X324147Y349665D01*
G01X319085Y345037D02*
X323903Y349658D01*
G01X318726Y344919D02*
X323659Y349652D01*
G01X318662Y345086D02*
X323415Y349645D01*
G01X318600Y345252D02*
X323166Y349634D01*
G01X318537Y345420D02*
X322906Y349610D01*
G01X318473Y345587D02*
X322644Y349587D01*
G01X318411Y345754D02*
X322382Y349564D01*
G01X318349Y345920D02*
X322104Y349523D01*
G01X318285Y346087D02*
X321821Y349478D01*
G01X313507Y345138D02*
X313500Y345132D01*
G01X313554Y345412D02*
X313262Y345132D01*
G01X313601Y345684D02*
X313026Y345132D01*
G01X313650Y345957D02*
X312790Y345132D01*
G01X313698Y346230D02*
X312553Y345132D01*
G01X313745Y346504D02*
X312316Y345132D01*
G01X313793Y346777D02*
X312080Y345132D01*
G01X313842Y347050D02*
X311842Y345132D01*
G01X313889Y347323D02*
X311605Y345132D01*
G01X313936Y347597D02*
X311368Y345132D01*
G01X313984Y347869D02*
X311132Y345132D01*
G01X314033Y348142D02*
X310896Y345132D01*
G01X314080Y348415D02*
X310658Y345132D01*
G01X314128Y348689D02*
X310421Y345132D01*
G01X314177Y348961D02*
X310183Y345132D01*
G01X314224Y349234D02*
X309947Y345132D01*
G01X314069Y349314D02*
X309710Y345132D01*
G01X309450Y345110D02*
X309473Y345132D01*
G01X313832Y349314D02*
X309473Y345132D01*
G01X318662Y345086D02*
X318726Y344919D01*
G01X318600Y345252D02*
X318662Y345086D01*
G01X318285Y346087D02*
X318349Y345920D01*
G01D02*
X318411Y345754D01*
G01X318222Y346255D02*
X318285Y346087D01*
G01X318537Y345420D02*
X318600Y345252D01*
G01X318473Y345587D02*
X318537Y345420D01*
G01X318411Y345754D02*
X318473Y345587D01*
G01X309306Y344289D02*
X309353Y344563D01*
G01D02*
X309402Y344836D01*
G01X313507Y345138D02*
X313554Y345412D01*
G01X311605Y345132D02*
X311842D01*
G01X311368D02*
X311605D01*
G01X311132D02*
X310896D01*
G01X311132D02*
X311368D01*
G01X311842D02*
X312080D01*
G01X312553D02*
X312790D01*
G01X312080D02*
X312316D01*
G01D02*
X312553D01*
G01X310896D02*
X310658D01*
G01X313554Y345412D02*
X313601Y345684D01*
G01X310421Y345132D02*
X310183D01*
G01X313650Y345957D02*
X313698Y346230D01*
G01X310658Y345132D02*
X310421D01*
G01X310183D02*
X309947D01*
G01X309710D02*
X309473D01*
G01X313601Y345684D02*
X313650Y345957D01*
G01X309947Y345132D02*
X309710D01*
G01X313507Y345138D02*
X313505Y345132D01*
G01D02*
X313500D01*
G01X313262D02*
X313500D01*
G01X313026D02*
X313262D01*
G01X312790D02*
X313026D01*
G01X309402Y344836D02*
X309450Y345110D01*
G01D02*
X309454Y345132D01*
G01D02*
X309473D01*
G01X318222Y346255D02*
X321536Y349433D01*
G01X318160Y346421D02*
X321228Y349365D01*
G01X318096Y346588D02*
X320916Y349292D01*
G01X318034Y346755D02*
X320593Y349210D01*
G01X317972Y346922D02*
X320242Y349101D01*
G01X317908Y347089D02*
X319891Y348991D01*
G01X317845Y347256D02*
X319497Y348840D01*
G01X317783Y347423D02*
X319097Y348683D01*
G01X317719Y347590D02*
X318651Y348484D01*
G01X317657Y347757D02*
X318189Y348267D01*
G01X317595Y347923D02*
X317694Y348019D01*
G01X311126Y354670D02*
X305786Y349548D01*
G01X311174Y354943D02*
X305835Y349821D01*
G01X311222Y355217D02*
X305883Y350095D01*
G01X311270Y355489D02*
X305930Y350367D01*
G01X311319Y355763D02*
X305979Y350641D01*
G01X311068Y355750D02*
X306026Y350914D01*
G01X310613Y355542D02*
X306075Y351187D01*
G01X310160Y355333D02*
X306123Y351460D01*
G01X309705Y355124D02*
X306170Y351734D01*
G01X309249Y354915D02*
X306219Y352008D01*
G01X308795Y354706D02*
X306266Y352280D01*
G01X308342Y354497D02*
X306314Y352553D01*
G01X307886Y354288D02*
X306363Y352827D01*
G01X307430Y354079D02*
X306410Y353100D01*
G01X306977Y353871D02*
X306459Y353373D01*
G01X306523Y353662D02*
X306506Y353646D01*
G01X317908Y347089D02*
X317972Y346922D01*
G01X317845Y347256D02*
X317908Y347089D01*
G01X318096Y346588D02*
X318160Y346421D01*
G01X317972Y346922D02*
X318034Y346755D01*
G01X318160Y346421D02*
X318222Y346255D01*
G01X317783Y347423D02*
X317845Y347256D01*
G01X318034Y346755D02*
X318096Y346588D01*
G01X317719Y347590D02*
X317783Y347423D01*
G01X317595Y347923D02*
X317657Y347757D01*
G01D02*
X317719Y347590D01*
G01X305306Y349314D02*
X305069D01*
G01X305542D02*
X305306D01*
G01X313936Y347597D02*
X313984Y347869D01*
G01D02*
X314033Y348142D01*
G01X313842Y347050D02*
X313889Y347323D01*
G01X313793Y346777D02*
X313842Y347050D01*
G01X313889Y347323D02*
X313936Y347597D01*
G01X314128Y348689D02*
X314177Y348961D01*
G01X314080Y348415D02*
X314128Y348689D01*
G01X313745Y346504D02*
X313793Y346777D01*
G01X313698Y346230D02*
X313745Y346504D01*
G01X314177Y348961D02*
X314224Y349234D01*
G01X314033Y348142D02*
X314080Y348415D01*
G01X311464Y349314D02*
X311228D01*
G01X311701D02*
X311464D01*
G01X312175D02*
X311937D01*
G01D02*
X311701D01*
G01X312648D02*
X312412D01*
G01D02*
X312175D01*
G01X310753D02*
X310517D01*
G01X310310Y350024D02*
X310357Y350297D01*
G01D02*
X310406Y350571D01*
G01X312885Y349314D02*
X312648D01*
G01X311228D02*
X310990D01*
G01D02*
X310753D01*
G01X310213Y349478D02*
X310262Y349751D01*
G01D02*
X310310Y350024D01*
G01X310517Y349314D02*
X310280D01*
G01X314224Y349234D02*
X314238Y349314D01*
G01D02*
X314069D01*
G01X313596D02*
X313360D01*
G01X313123D02*
X312885D01*
G01X313360D02*
X313123D01*
G01X314069D02*
X313832D01*
G01D02*
X313596D01*
G01X310213Y349478D02*
X310185Y349314D01*
G01D02*
X310280D01*
G01X306363Y352827D02*
X306314Y352553D01*
G01X306363Y352827D02*
X306410Y353100D01*
G01X306219Y352008D02*
X306170Y351734D01*
G01X306314Y352553D02*
X306266Y352280D01*
G01X306170Y351734D02*
X306123Y351460D01*
G01X306410Y353100D02*
X306459Y353373D01*
G01X306266Y352280D02*
X306219Y352008D01*
G01X306523Y353662D02*
X306508Y353655D01*
G01D02*
X306506Y353646D01*
G01X306459Y353373D02*
X306506Y353646D01*
G01X306123Y351460D02*
X306075Y351187D01*
G01X305979Y350641D02*
X305930Y350367D01*
G01X306026Y350914D02*
X305979Y350641D01*
G01X306075Y351187D02*
X306026Y350914D01*
G01X305835Y349821D02*
X305786Y349548D01*
G01X305542Y349314D02*
X305746D01*
G01D02*
X305786Y349548D01*
G01X305883Y350095D02*
X305835Y349821D01*
G01X305930Y350367D02*
X305883Y350095D01*
G01X311068Y355750D02*
X310613Y355542D01*
G01X310886Y353303D02*
X310934Y353577D01*
G01X310613Y355542D02*
X310160Y355333D01*
G01X309705Y355124D02*
X309249Y354915D01*
G01X310160Y355333D02*
X309705Y355124D01*
G01X311319Y355763D02*
X311338Y355875D01*
G01D02*
X311068Y355750D01*
G01X310982Y353851D02*
X311030Y354124D01*
G01D02*
X311079Y354396D01*
G01X310934Y353577D02*
X310982Y353851D01*
G01X311222Y355217D02*
X311270Y355489D01*
G01X311174Y354943D02*
X311222Y355217D01*
G01X311079Y354396D02*
X311126Y354670D01*
G01D02*
X311174Y354943D01*
G01X311270Y355489D02*
X311319Y355763D01*
G01X307886Y354288D02*
X307430Y354079D01*
G01X309249Y354915D02*
X308795Y354706D01*
G01X306977Y353871D02*
X306523Y353662D01*
G01X307430Y354079D02*
X306977Y353871D01*
G01X308795Y354706D02*
X308342Y354497D01*
G01X310406Y350571D02*
X310453Y350844D01*
G01X308342Y354497D02*
X307886Y354288D01*
G01X310790Y352758D02*
X310837Y353030D01*
G01X310599Y351664D02*
X310646Y351937D01*
G01X310453Y350844D02*
X310502Y351117D01*
G01X310742Y352484D02*
X310790Y352758D01*
G01X310646Y351937D02*
X310693Y352210D01*
G01X310837Y353030D02*
X310886Y353303D01*
G01X310502Y351117D02*
X310550Y351391D01*
G01X310693Y352210D02*
X310742Y352484D01*
G01X310550Y351391D02*
X310599Y351664D01*
G01X318222Y346255D02*
X321536Y349433D01*
G01X318160Y346421D02*
X321228Y349365D01*
G01X318096Y346588D02*
X320916Y349292D01*
G01X318034Y346755D02*
X320593Y349210D01*
G01X317972Y346922D02*
X320242Y349101D01*
G01X317908Y347089D02*
X319891Y348991D01*
G01X317845Y347256D02*
X319497Y348840D01*
G01X317783Y347423D02*
X319097Y348683D01*
G01X317719Y347590D02*
X318651Y348484D01*
G01X317657Y347757D02*
X318189Y348267D01*
G01X317595Y347923D02*
X317694Y348019D01*
G01X311126Y354670D02*
X305786Y349548D01*
G01X311174Y354943D02*
X305835Y349821D01*
G01X311222Y355217D02*
X305883Y350095D01*
G01X311270Y355489D02*
X305930Y350367D01*
G01X311319Y355763D02*
X305979Y350641D01*
G01X311068Y355750D02*
X306026Y350914D01*
G01X310613Y355542D02*
X306075Y351187D01*
G01X310160Y355333D02*
X306123Y351460D01*
G01X309705Y355124D02*
X306170Y351734D01*
G01X309249Y354915D02*
X306219Y352008D01*
G01X308795Y354706D02*
X306266Y352280D01*
G01X308342Y354497D02*
X306314Y352553D01*
G01X307886Y354288D02*
X306363Y352827D01*
G01X307430Y354079D02*
X306410Y353100D01*
G01X306977Y353871D02*
X306459Y353373D01*
G01X306523Y353662D02*
X306506Y353646D01*
G01X317908Y347089D02*
X317972Y346922D01*
G01X317845Y347256D02*
X317908Y347089D01*
G01X318096Y346588D02*
X318160Y346421D01*
G01X317972Y346922D02*
X318034Y346755D01*
G01X318160Y346421D02*
X318222Y346255D01*
G01X317783Y347423D02*
X317845Y347256D01*
G01X318034Y346755D02*
X318096Y346588D01*
G01X317719Y347590D02*
X317783Y347423D01*
G01X317595Y347923D02*
X317657Y347757D01*
G01D02*
X317719Y347590D01*
G01X305306Y349314D02*
X305069D01*
G01X305542D02*
X305306D01*
G01X313936Y347597D02*
X313984Y347869D01*
G01D02*
X314033Y348142D01*
G01X313842Y347050D02*
X313889Y347323D01*
G01X313793Y346777D02*
X313842Y347050D01*
G01X313889Y347323D02*
X313936Y347597D01*
G01X314128Y348689D02*
X314177Y348961D01*
G01X314080Y348415D02*
X314128Y348689D01*
G01X313745Y346504D02*
X313793Y346777D01*
G01X313698Y346230D02*
X313745Y346504D01*
G01X314177Y348961D02*
X314224Y349234D01*
G01X314033Y348142D02*
X314080Y348415D01*
G01X311464Y349314D02*
X311228D01*
G01X311701D02*
X311464D01*
G01X312175D02*
X311937D01*
G01D02*
X311701D01*
G01X312648D02*
X312412D01*
G01D02*
X312175D01*
G01X310753D02*
X310517D01*
G01X310310Y350024D02*
X310357Y350297D01*
G01D02*
X310406Y350571D01*
G01X312885Y349314D02*
X312648D01*
G01X311228D02*
X310990D01*
G01D02*
X310753D01*
G01X310213Y349478D02*
X310262Y349751D01*
G01D02*
X310310Y350024D01*
G01X310517Y349314D02*
X310280D01*
G01X314224Y349234D02*
X314238Y349314D01*
G01D02*
X314069D01*
G01X313596D02*
X313360D01*
G01X313123D02*
X312885D01*
G01X313360D02*
X313123D01*
G01X314069D02*
X313832D01*
G01D02*
X313596D01*
G01X310213Y349478D02*
X310185Y349314D01*
G01D02*
X310280D01*
G01X306363Y352827D02*
X306314Y352553D01*
G01X306363Y352827D02*
X306410Y353100D01*
G01X306219Y352008D02*
X306170Y351734D01*
G01X306314Y352553D02*
X306266Y352280D01*
G01X306170Y351734D02*
X306123Y351460D01*
G01X306410Y353100D02*
X306459Y353373D01*
G01X306266Y352280D02*
X306219Y352008D01*
G01X306523Y353662D02*
X306508Y353655D01*
G01D02*
X306506Y353646D01*
G01X306459Y353373D02*
X306506Y353646D01*
G01X306123Y351460D02*
X306075Y351187D01*
G01X305979Y350641D02*
X305930Y350367D01*
G01X306026Y350914D02*
X305979Y350641D01*
G01X306075Y351187D02*
X306026Y350914D01*
G01X305835Y349821D02*
X305786Y349548D01*
G01X305542Y349314D02*
X305746D01*
G01D02*
X305786Y349548D01*
G01X305883Y350095D02*
X305835Y349821D01*
G01X305930Y350367D02*
X305883Y350095D01*
G01X311068Y355750D02*
X310613Y355542D01*
G01X310886Y353303D02*
X310934Y353577D01*
G01X310613Y355542D02*
X310160Y355333D01*
G01X309705Y355124D02*
X309249Y354915D01*
G01X310160Y355333D02*
X309705Y355124D01*
G01X311319Y355763D02*
X311338Y355875D01*
G01D02*
X311068Y355750D01*
G01X310982Y353851D02*
X311030Y354124D01*
G01D02*
X311079Y354396D01*
G01X310934Y353577D02*
X310982Y353851D01*
G01X311222Y355217D02*
X311270Y355489D01*
G01X311174Y354943D02*
X311222Y355217D01*
G01X311079Y354396D02*
X311126Y354670D01*
G01D02*
X311174Y354943D01*
G01X311270Y355489D02*
X311319Y355763D01*
G01X307886Y354288D02*
X307430Y354079D01*
G01X309249Y354915D02*
X308795Y354706D01*
G01X306977Y353871D02*
X306523Y353662D01*
G01X307430Y354079D02*
X306977Y353871D01*
G01X308795Y354706D02*
X308342Y354497D01*
G01X310406Y350571D02*
X310453Y350844D01*
G01X308342Y354497D02*
X307886Y354288D01*
G01X310790Y352758D02*
X310837Y353030D01*
G01X310599Y351664D02*
X310646Y351937D01*
G01X310453Y350844D02*
X310502Y351117D01*
G01X310742Y352484D02*
X310790Y352758D01*
G01X310646Y351937D02*
X310693Y352210D01*
G01X310837Y353030D02*
X310886Y353303D01*
G01X310502Y351117D02*
X310550Y351391D01*
G01X310693Y352210D02*
X310742Y352484D01*
G01X310550Y351391D02*
X310599Y351664D01*
G01X328071Y838543D02*
G02X312323I-7874J0D01*
G02X328071I7874J0D01*
G01Y1199961D02*
G02X312323I-7874J0D01*
G02X328071I7874J0D01*
G01X327970Y332429D02*
X328053Y332509D01*
G01X327733Y332429D02*
X328102Y332783D01*
G01X327496Y332429D02*
X328150Y333057D01*
G01X327260Y332429D02*
X328197Y333329D01*
G01X327022Y332429D02*
X328244Y333601D01*
G01X326785Y332429D02*
X328293Y333875D01*
G01X326548Y332429D02*
X328341Y334149D01*
G01X326312Y332429D02*
X328388Y334421D01*
G01X326076Y332429D02*
X328437Y334694D01*
G01X325838Y332429D02*
X328485Y334968D01*
G01X325601Y332429D02*
X328532Y335242D01*
G01X325364Y332429D02*
X328581Y335514D01*
G01X325128Y332429D02*
X328628Y335787D01*
G01X324890Y332429D02*
X328676Y336060D01*
G01X324653Y332429D02*
X328725Y336334D01*
G01X324417Y332429D02*
X328772Y336606D01*
G01X324181Y332429D02*
X328820Y336879D01*
G01X323944Y332429D02*
X328867Y337153D01*
G01X323706Y332429D02*
X328916Y337426D01*
G01X323629Y332581D02*
X328963Y337699D01*
G01X323676Y332855D02*
X329011Y337972D01*
G01X323725Y333128D02*
X329060Y338246D01*
G01X329107Y338519D02*
X323773Y333402D01*
G01X323389Y333261D02*
X329155Y338791D01*
G01X322715Y332841D02*
X329202Y339064D01*
G01X322241Y332614D02*
X329251Y339338D01*
G01X321836Y332452D02*
X329298Y339611D01*
G01X321499Y332357D02*
X329346Y339884D01*
G01X321163Y332261D02*
X329395Y340157D01*
G01X320844Y332183D02*
X329442Y340431D01*
G01X320580Y332156D02*
X329490Y340704D01*
G01X320317Y332132D02*
X329537Y340977D01*
G01X320054Y332105D02*
X329586Y341249D01*
G01X329825Y342616D02*
X324491Y337500D01*
G01X329873Y342889D02*
X324539Y337773D01*
G01X329921Y343162D02*
X324588Y338045D01*
G01X329968Y343434D02*
X324635Y338318D01*
G01X330016Y343708D02*
X324683Y338592D01*
G01X330042Y343959D02*
X324732Y338865D01*
G01X330061Y344205D02*
X324779Y339138D01*
G01X330081Y344451D02*
X324826Y339411D01*
G01X330101Y344698D02*
X324751Y339565D01*
G01X330122Y344946D02*
X324608Y339657D01*
G01X330123Y345174D02*
X324459Y339740D01*
G01X330096Y345374D02*
X324307Y339821D01*
G01X330069Y345576D02*
X324142Y339890D01*
G01X330040Y345777D02*
X323972Y339955D01*
G01X330013Y345977D02*
X323793Y340010D01*
G01X320342Y339881D02*
X324116Y343501D01*
G01X326785Y332429D02*
X327022D01*
G01X326312D02*
X326548D01*
G01D02*
X326785D01*
G01X325838D02*
X326076D01*
G01D02*
X326312D01*
G01X327733D02*
X327970D01*
G01D02*
X328040D01*
G01D02*
X328053Y332509D01*
G01X325601Y332429D02*
X325838D01*
G01X327022D02*
X327260D01*
G01X327496D02*
X327733D01*
G01X327260D02*
X327496D01*
G01X323706D02*
X323944D01*
G01X323725Y333128D02*
X323676Y332855D01*
G01X323629Y332581D02*
X323602Y332429D01*
G01D02*
X323706D01*
G01X323676Y332855D02*
X323629Y332581D01*
G01X325128Y332429D02*
X325364D01*
G01X324890D02*
X325128D01*
G01X325364D02*
X325601D01*
G01X324181D02*
X324417D01*
G01D02*
X324653D01*
G01D02*
X324890D01*
G01X329060Y338246D02*
X329107Y338519D01*
G01D02*
X329155Y338791D01*
G01D02*
X329202Y339064D01*
G01X328963Y337699D02*
X329011Y337972D01*
G01X328916Y337426D02*
X328963Y337699D01*
G01X329011Y337972D02*
X329060Y338246D01*
G01X328867Y337153D02*
X328916Y337426D01*
G01X329346Y339884D02*
X329395Y340157D01*
G01X328053Y332509D02*
X328102Y332783D01*
G01X329298Y339611D02*
X329346Y339884D01*
G01X329202Y339064D02*
X329251Y339338D01*
G01D02*
X329298Y339611D01*
G01X328244Y333601D02*
X328293Y333875D01*
G01X328820Y336879D02*
X328867Y337153D01*
G01X328341Y334149D02*
X328388Y334421D01*
G01X328293Y333875D02*
X328341Y334149D01*
G01X328197Y333329D02*
X328244Y333601D01*
G01X328102Y332783D02*
X328150Y333057D01*
G01D02*
X328197Y333329D01*
G01X328676Y336060D02*
X328725Y336334D01*
G01X328772Y336606D02*
X328820Y336879D01*
G01X328628Y335787D02*
X328676Y336060D01*
G01X328725Y336334D02*
X328772Y336606D01*
G01X328437Y334694D02*
X328485Y334968D01*
G01X328388Y334421D02*
X328437Y334694D01*
G01X328485Y334968D02*
X328532Y335242D01*
G01D02*
X328581Y335514D01*
G01D02*
X328628Y335787D01*
G01X323944Y332429D02*
X324181D01*
G01X324732Y338865D02*
X324683Y338592D01*
G01D02*
X324635Y338318D01*
G01X324826Y339411D02*
X324779Y339138D01*
G01D02*
X324732Y338865D01*
G01X324539Y337773D02*
X324491Y337500D01*
G01X324635Y338318D02*
X324588Y338045D01*
G01D02*
X324539Y337773D01*
G01X323773Y333402D02*
X323725Y333128D01*
G01X327970Y332429D02*
X328053Y332509D01*
G01X327733Y332429D02*
X328102Y332783D01*
G01X327496Y332429D02*
X328150Y333057D01*
G01X327260Y332429D02*
X328197Y333329D01*
G01X327022Y332429D02*
X328244Y333601D01*
G01X326785Y332429D02*
X328293Y333875D01*
G01X326548Y332429D02*
X328341Y334149D01*
G01X326312Y332429D02*
X328388Y334421D01*
G01X326076Y332429D02*
X328437Y334694D01*
G01X325838Y332429D02*
X328485Y334968D01*
G01X325601Y332429D02*
X328532Y335242D01*
G01X325364Y332429D02*
X328581Y335514D01*
G01X325128Y332429D02*
X328628Y335787D01*
G01X324890Y332429D02*
X328676Y336060D01*
G01X324653Y332429D02*
X328725Y336334D01*
G01X324417Y332429D02*
X328772Y336606D01*
G01X324181Y332429D02*
X328820Y336879D01*
G01X323944Y332429D02*
X328867Y337153D01*
G01X323706Y332429D02*
X328916Y337426D01*
G01X323629Y332581D02*
X328963Y337699D01*
G01X323676Y332855D02*
X329011Y337972D01*
G01X323725Y333128D02*
X329060Y338246D01*
G01X329107Y338519D02*
X323773Y333402D01*
G01X323389Y333261D02*
X329155Y338791D01*
G01X322715Y332841D02*
X329202Y339064D01*
G01X322241Y332614D02*
X329251Y339338D01*
G01X321836Y332452D02*
X329298Y339611D01*
G01X321499Y332357D02*
X329346Y339884D01*
G01X321163Y332261D02*
X329395Y340157D01*
G01X320844Y332183D02*
X329442Y340431D01*
G01X320580Y332156D02*
X329490Y340704D01*
G01X320317Y332132D02*
X329537Y340977D01*
G01X320054Y332105D02*
X329586Y341249D01*
G01X329825Y342616D02*
X324491Y337500D01*
G01X329873Y342889D02*
X324539Y337773D01*
G01X329921Y343162D02*
X324588Y338045D01*
G01X329968Y343434D02*
X324635Y338318D01*
G01X330016Y343708D02*
X324683Y338592D01*
G01X330042Y343959D02*
X324732Y338865D01*
G01X330061Y344205D02*
X324779Y339138D01*
G01X330081Y344451D02*
X324826Y339411D01*
G01X330101Y344698D02*
X324751Y339565D01*
G01X330122Y344946D02*
X324608Y339657D01*
G01X330123Y345174D02*
X324459Y339740D01*
G01X330096Y345374D02*
X324307Y339821D01*
G01X330069Y345576D02*
X324142Y339890D01*
G01X330040Y345777D02*
X323972Y339955D01*
G01X330013Y345977D02*
X323793Y340010D01*
G01X320342Y339881D02*
X324116Y343501D01*
G01X326785Y332429D02*
X327022D01*
G01X326312D02*
X326548D01*
G01D02*
X326785D01*
G01X325838D02*
X326076D01*
G01D02*
X326312D01*
G01X327733D02*
X327970D01*
G01D02*
X328040D01*
G01D02*
X328053Y332509D01*
G01X325601Y332429D02*
X325838D01*
G01X327022D02*
X327260D01*
G01X327496D02*
X327733D01*
G01X327260D02*
X327496D01*
G01X323706D02*
X323944D01*
G01X323725Y333128D02*
X323676Y332855D01*
G01X323629Y332581D02*
X323602Y332429D01*
G01D02*
X323706D01*
G01X323676Y332855D02*
X323629Y332581D01*
G01X325128Y332429D02*
X325364D01*
G01X324890D02*
X325128D01*
G01X325364D02*
X325601D01*
G01X324181D02*
X324417D01*
G01D02*
X324653D01*
G01D02*
X324890D01*
G01X329060Y338246D02*
X329107Y338519D01*
G01D02*
X329155Y338791D01*
G01D02*
X329202Y339064D01*
G01X328963Y337699D02*
X329011Y337972D01*
G01X328916Y337426D02*
X328963Y337699D01*
G01X329011Y337972D02*
X329060Y338246D01*
G01X328867Y337153D02*
X328916Y337426D01*
G01X329346Y339884D02*
X329395Y340157D01*
G01X328053Y332509D02*
X328102Y332783D01*
G01X329298Y339611D02*
X329346Y339884D01*
G01X329202Y339064D02*
X329251Y339338D01*
G01D02*
X329298Y339611D01*
G01X328244Y333601D02*
X328293Y333875D01*
G01X328820Y336879D02*
X328867Y337153D01*
G01X328341Y334149D02*
X328388Y334421D01*
G01X328293Y333875D02*
X328341Y334149D01*
G01X328197Y333329D02*
X328244Y333601D01*
G01X328102Y332783D02*
X328150Y333057D01*
G01D02*
X328197Y333329D01*
G01X328676Y336060D02*
X328725Y336334D01*
G01X328772Y336606D02*
X328820Y336879D01*
G01X328628Y335787D02*
X328676Y336060D01*
G01X328725Y336334D02*
X328772Y336606D01*
G01X328437Y334694D02*
X328485Y334968D01*
G01X328388Y334421D02*
X328437Y334694D01*
G01X328485Y334968D02*
X328532Y335242D01*
G01D02*
X328581Y335514D01*
G01D02*
X328628Y335787D01*
G01X323944Y332429D02*
X324181D01*
G01X324732Y338865D02*
X324683Y338592D01*
G01D02*
X324635Y338318D01*
G01X324826Y339411D02*
X324779Y339138D01*
G01D02*
X324732Y338865D01*
G01X324539Y337773D02*
X324491Y337500D01*
G01X324635Y338318D02*
X324588Y338045D01*
G01D02*
X324539Y337773D01*
G01X323773Y333402D02*
X323725Y333128D01*
G01X329986Y346178D02*
X323607Y340058D01*
G01X329939Y346360D02*
X323412Y340099D01*
G01X329871Y346523D02*
X323208Y340132D01*
G01X329804Y346685D02*
X323001Y340159D01*
G01X329738Y346848D02*
X322785Y340178D01*
G01X329671Y347012D02*
X322563Y340193D01*
G01X329604Y347175D02*
X325498Y343236D01*
G01X325326Y343072D02*
X322336Y340204D01*
G01X329526Y347328D02*
X325547Y343510D01*
G01X325167Y343147D02*
X322106Y340209D01*
G01X325008Y343221D02*
X321872Y340212D01*
G01X329426Y347458D02*
X325594Y343783D01*
G01X324841Y343288D02*
X321600Y340178D01*
G01X329324Y347588D02*
X325623Y344038D01*
G01X324662Y343345D02*
X321326Y340144D01*
G01X321055Y340110D02*
X324485Y343400D01*
G01X320782Y340076D02*
X324307Y343457D01*
G01X329633Y341523D02*
X329681Y341796D01*
G01X329968Y343434D02*
X330016Y343708D01*
G01X329921Y343162D02*
X329968Y343434D01*
G01X329873Y342889D02*
X329921Y343162D01*
G01X329825Y342616D02*
X329873Y342889D01*
G01X329730Y342069D02*
X329777Y342342D01*
G01X329681Y341796D02*
X329730Y342069D01*
G01X329777Y342342D02*
X329825Y342616D01*
G01X329395Y340157D02*
X329442Y340431D01*
G01X329490Y340704D02*
X329537Y340977D01*
G01D02*
X329586Y341249D01*
G01D02*
X329633Y341523D01*
G01X329442Y340431D02*
X329490Y340704D01*
G01X325594Y343783D02*
X325547Y343510D01*
G01D02*
X325498Y343236D01*
G01X329986Y346178D02*
X323607Y340058D01*
G01X329939Y346360D02*
X323412Y340099D01*
G01X329871Y346523D02*
X323208Y340132D01*
G01X329804Y346685D02*
X323001Y340159D01*
G01X329738Y346848D02*
X322785Y340178D01*
G01X329671Y347012D02*
X322563Y340193D01*
G01X329604Y347175D02*
X325498Y343236D01*
G01X325326Y343072D02*
X322336Y340204D01*
G01X329526Y347328D02*
X325547Y343510D01*
G01X325167Y343147D02*
X322106Y340209D01*
G01X325008Y343221D02*
X321872Y340212D01*
G01X329426Y347458D02*
X325594Y343783D01*
G01X324841Y343288D02*
X321600Y340178D01*
G01X329324Y347588D02*
X325623Y344038D01*
G01X324662Y343345D02*
X321326Y340144D01*
G01X321055Y340110D02*
X324485Y343400D01*
G01X320782Y340076D02*
X324307Y343457D01*
G01X329633Y341523D02*
X329681Y341796D01*
G01X329968Y343434D02*
X330016Y343708D01*
G01X329921Y343162D02*
X329968Y343434D01*
G01X329873Y342889D02*
X329921Y343162D01*
G01X329825Y342616D02*
X329873Y342889D01*
G01X329730Y342069D02*
X329777Y342342D01*
G01X329681Y341796D02*
X329730Y342069D01*
G01X329777Y342342D02*
X329825Y342616D01*
G01X329395Y340157D02*
X329442Y340431D01*
G01X329490Y340704D02*
X329537Y340977D01*
G01D02*
X329586Y341249D01*
G01D02*
X329633Y341523D01*
G01X329442Y340431D02*
X329490Y340704D01*
G01X325594Y343783D02*
X325547Y343510D01*
G01D02*
X325498Y343236D01*
G01X329222Y347719D02*
X325644Y344285D01*
G01X329122Y347848D02*
X325623Y344491D01*
G01X329020Y347978D02*
X325598Y344696D01*
G01X328919Y348109D02*
X325540Y344867D01*
G01X328792Y348214D02*
X325482Y345039D01*
G01X328660Y348314D02*
X325393Y345181D01*
G01X328528Y348414D02*
X325303Y345320D01*
G01X328395Y348514D02*
X325191Y345441D01*
G01X328262Y348615D02*
X325068Y345551D01*
G01X328131Y348714D02*
X324938Y345653D01*
G01X327992Y348809D02*
X324786Y345733D01*
G01X327829Y348881D02*
X324631Y345813D01*
G01X327667Y348953D02*
X324454Y345870D01*
G01X327505Y349024D02*
X324269Y345920D01*
G01X327344Y349096D02*
X324075Y345961D01*
G01X327181Y349168D02*
X323855Y345978D01*
G01X327020Y349240D02*
X323637Y345996D01*
G01X326842Y349298D02*
X323402Y345997D01*
G01X326652Y349341D02*
X323161Y345992D01*
G01X326461Y349385D02*
X322918Y345988D01*
G01X326268Y349429D02*
X322667Y345974D01*
G01X326078Y349473D02*
X322412Y345956D01*
G01X325887Y349517D02*
X322155Y345937D01*
G01X325696Y349561D02*
X321881Y345901D01*
G01X325479Y349580D02*
X321607Y345866D01*
G01X325258Y349595D02*
X321310Y345807D01*
G01X325038Y349610D02*
X321008Y345745D01*
G01X324816Y349626D02*
X320675Y345653D01*
G01X320325Y345544D02*
X324595Y349641D01*
G01X319950Y345412D02*
X324373Y349656D01*
G01X329222Y347719D02*
X325644Y344285D01*
G01X329122Y347848D02*
X325623Y344491D01*
G01X329020Y347978D02*
X325598Y344696D01*
G01X328919Y348109D02*
X325540Y344867D01*
G01X328792Y348214D02*
X325482Y345039D01*
G01X328660Y348314D02*
X325393Y345181D01*
G01X328528Y348414D02*
X325303Y345320D01*
G01X328395Y348514D02*
X325191Y345441D01*
G01X328262Y348615D02*
X325068Y345551D01*
G01X328131Y348714D02*
X324938Y345653D01*
G01X327992Y348809D02*
X324786Y345733D01*
G01X327829Y348881D02*
X324631Y345813D01*
G01X327667Y348953D02*
X324454Y345870D01*
G01X327505Y349024D02*
X324269Y345920D01*
G01X327344Y349096D02*
X324075Y345961D01*
G01X327181Y349168D02*
X323855Y345978D01*
G01X327020Y349240D02*
X323637Y345996D01*
G01X326842Y349298D02*
X323402Y345997D01*
G01X326652Y349341D02*
X323161Y345992D01*
G01X326461Y349385D02*
X322918Y345988D01*
G01X326268Y349429D02*
X322667Y345974D01*
G01X326078Y349473D02*
X322412Y345956D01*
G01X325887Y349517D02*
X322155Y345937D01*
G01X325696Y349561D02*
X321881Y345901D01*
G01X325479Y349580D02*
X321607Y345866D01*
G01X325258Y349595D02*
X321310Y345807D01*
G01X325038Y349610D02*
X321008Y345745D01*
G01X324816Y349626D02*
X320675Y345653D01*
G01X320325Y345544D02*
X324595Y349641D01*
G01X319950Y345412D02*
X324373Y349656D01*
G01X384646Y87795D02*
G02X362598I-11024J0D01*
G02X384646I11024J0D01*
G01X365287Y191535D02*
X371587D01*
G02Y178937I0J-6299D01*
G01X365287D01*
G02Y191535I0J6299D01*
G01X402689Y185236D02*
G02X387728I-7480J0D01*
G02X402689I7481J0D01*
G01X406694Y1714961D02*
G02X384647I-11023J0D01*
G02X406694I11023J0D01*
G01X411000Y-610138D02*
Y-635138D01*
G01X413633Y-612638D02*
Y-617638D01*
X416167D01*
G01X419240Y-612638D02*
X420760D01*
G01X420000D02*
Y-617638D01*
G01X419240D02*
X420760D01*
G01X425607Y-614971D02*
X425860Y-614721D01*
X426050Y-614305D01*
X426177Y-613721D01*
X426050Y-613221D01*
X425797Y-612888D01*
X425353Y-612638D01*
X423643D01*
Y-617638D01*
X425733D01*
X426177Y-617305D01*
X426430Y-616805D01*
X426557Y-616221D01*
X426430Y-615638D01*
X426050Y-615138D01*
X425607Y-614971D01*
X423643D01*
G01X430200Y-617805D02*
X430073Y-617721D01*
Y-617555D01*
X430200Y-617471D01*
X430327Y-617555D01*
Y-617721D01*
X430200Y-617805D01*
G01Y-615555D02*
X430073Y-615471D01*
Y-615305D01*
X430200Y-615221D01*
X430327Y-615305D01*
Y-615471D01*
X430200Y-615555D01*
G01X427484Y655965D02*
G02X412799I-7343J0D01*
G02X427484I7343J0D01*
G01X451106Y1339823D02*
G02X436421I-7343J0D01*
G02X451106I7343J0D01*
G01X434793Y1698268D02*
G02X447293I6250J0D01*
G02X434793I-6250J0D01*
G01X454000Y-610138D02*
Y-635138D01*
G01Y-585138D02*
Y-610138D01*
G01X459013Y-637305D02*
X459120Y-637180D01*
X459200Y-636971D01*
X459253Y-636680D01*
X459200Y-636430D01*
X459093Y-636263D01*
X458907Y-636138D01*
X458187D01*
Y-638638D01*
X459067D01*
X459253Y-638471D01*
X459360Y-638221D01*
X459413Y-637930D01*
X459360Y-637638D01*
X459200Y-637388D01*
X459013Y-637305D01*
X458187D01*
G01X461480Y-638638D02*
Y-636971D01*
G01Y-637263D02*
X461373Y-637096D01*
X461213Y-637013D01*
X461027Y-636971D01*
X460840Y-637055D01*
X460680Y-637221D01*
X460573Y-637471D01*
X460520Y-637805D01*
X460573Y-638138D01*
X460680Y-638388D01*
X460840Y-638555D01*
X461027Y-638638D01*
X461213Y-638596D01*
X461373Y-638471D01*
X461480Y-638305D01*
G01X462800Y-638346D02*
X462933Y-638513D01*
X463120Y-638638D01*
X463280D01*
X463440Y-638555D01*
X463547Y-638430D01*
X463600Y-638263D01*
X463573Y-638013D01*
X463467Y-637888D01*
X462987Y-637638D01*
X462880Y-637346D01*
X462933Y-637138D01*
X463040Y-637013D01*
X463200Y-636971D01*
X463360Y-637013D01*
X463520Y-637138D01*
G01X465000Y-637513D02*
X465853D01*
X465773Y-637221D01*
X465640Y-637055D01*
X465453Y-636971D01*
X465267Y-637013D01*
X465107Y-637138D01*
X465000Y-637430D01*
X464947Y-637680D01*
Y-637930D01*
X465000Y-638180D01*
X465133Y-638430D01*
X465293Y-638596D01*
X465480Y-638638D01*
X465667Y-638555D01*
X465853Y-638305D01*
G01X467120Y-638638D02*
Y-636138D01*
G01Y-637388D02*
X467253Y-637138D01*
X467413Y-637013D01*
X467573Y-636971D01*
X467813Y-637055D01*
X467973Y-637221D01*
X468080Y-637513D01*
Y-637846D01*
X468027Y-638180D01*
X467920Y-638430D01*
X467733Y-638596D01*
X467573Y-638638D01*
X467413Y-638596D01*
X467253Y-638471D01*
X467120Y-638263D01*
G01X469800Y-638638D02*
X469640Y-638596D01*
X469480Y-638430D01*
X469373Y-638138D01*
X469320Y-637805D01*
X469373Y-637471D01*
X469480Y-637180D01*
X469640Y-637013D01*
X469800Y-636971D01*
X469960Y-637013D01*
X470120Y-637180D01*
X470227Y-637471D01*
X470253Y-637805D01*
X470227Y-638138D01*
X470120Y-638430D01*
X469960Y-638596D01*
X469800Y-638638D01*
G01X472480D02*
Y-636971D01*
G01Y-637263D02*
X472373Y-637096D01*
X472213Y-637013D01*
X472027Y-636971D01*
X471840Y-637055D01*
X471680Y-637221D01*
X471573Y-637471D01*
X471520Y-637805D01*
X471573Y-638138D01*
X471680Y-638388D01*
X471840Y-638555D01*
X472027Y-638638D01*
X472213Y-638596D01*
X472373Y-638471D01*
X472480Y-638305D01*
G01X473827Y-638638D02*
Y-636971D01*
G01Y-637305D02*
X473960Y-637138D01*
X474093Y-637013D01*
X474280Y-636971D01*
X474413Y-637013D01*
X474573Y-637138D01*
G01X476880Y-636138D02*
Y-638638D01*
G01Y-638263D02*
X476773Y-638471D01*
X476613Y-638596D01*
X476427Y-638638D01*
X476213Y-638555D01*
X476053Y-638346D01*
X475947Y-638096D01*
X475920Y-637805D01*
X475947Y-637513D01*
X476053Y-637263D01*
X476213Y-637055D01*
X476427Y-636971D01*
X476613Y-637013D01*
X476747Y-637096D01*
X476880Y-637263D01*
G01X480267Y-638638D02*
Y-636138D01*
X480933D01*
X481147Y-636263D01*
X481280Y-636430D01*
X481333Y-636763D01*
X481280Y-637096D01*
X481120Y-637305D01*
X480933Y-637430D01*
X480267D01*
G01X480933D02*
X481333Y-638638D01*
G01X482600Y-637513D02*
X483453D01*
X483373Y-637221D01*
X483240Y-637055D01*
X483053Y-636971D01*
X482867Y-637013D01*
X482707Y-637138D01*
X482600Y-637430D01*
X482547Y-637680D01*
Y-637930D01*
X482600Y-638180D01*
X482733Y-638430D01*
X482893Y-638596D01*
X483080Y-638638D01*
X483267Y-638555D01*
X483453Y-638305D01*
G01X484720Y-636971D02*
X485200Y-638638D01*
X485680Y-636971D01*
G01X487400Y-638721D02*
X487347Y-638680D01*
Y-638596D01*
X487400Y-638555D01*
X487453Y-638596D01*
Y-638680D01*
X487400Y-638721D01*
G01X489147Y-638346D02*
X489333Y-638555D01*
X489547Y-638638D01*
X489760Y-638555D01*
X489947Y-638305D01*
X490080Y-637930D01*
X490133Y-637555D01*
Y-637096D01*
X490080Y-636721D01*
X489947Y-636388D01*
X489787Y-636221D01*
X489600Y-636138D01*
X489387Y-636221D01*
X489227Y-636388D01*
X489120Y-636638D01*
X489067Y-636971D01*
X489120Y-637263D01*
X489253Y-637555D01*
X489413Y-637721D01*
X489600Y-637763D01*
X489813Y-637680D01*
X489973Y-637471D01*
X490133Y-637096D01*
G01X492013Y-637305D02*
X492120Y-637180D01*
X492200Y-636971D01*
X492253Y-636680D01*
X492200Y-636430D01*
X492093Y-636263D01*
X491907Y-636138D01*
X491187D01*
Y-638638D01*
X492067D01*
X492253Y-638471D01*
X492360Y-638221D01*
X492413Y-637930D01*
X492360Y-637638D01*
X492200Y-637388D01*
X492013Y-637305D01*
X491187D01*
G01X457900Y-612638D02*
Y-617638D01*
G01X456443Y-612638D02*
X459357D01*
G01X463000Y-617638D02*
X462620Y-617555D01*
X462240Y-617221D01*
X461987Y-616638D01*
X461860Y-615971D01*
X461987Y-615305D01*
X462240Y-614721D01*
X462620Y-614388D01*
X463000Y-614305D01*
X463380Y-614388D01*
X463760Y-614721D01*
X464013Y-615305D01*
X464077Y-615971D01*
X464013Y-616638D01*
X463760Y-617221D01*
X463380Y-617555D01*
X463000Y-617638D01*
G01X468100D02*
X467720Y-617555D01*
X467340Y-617221D01*
X467087Y-616638D01*
X466960Y-615971D01*
X467087Y-615305D01*
X467340Y-614721D01*
X467720Y-614388D01*
X468100Y-614305D01*
X468480Y-614388D01*
X468860Y-614721D01*
X469113Y-615305D01*
X469177Y-615971D01*
X469113Y-616638D01*
X468860Y-617221D01*
X468480Y-617555D01*
X468100Y-617638D01*
G01X473200D02*
Y-612638D01*
G01X478300Y-617805D02*
X478173Y-617721D01*
Y-617555D01*
X478300Y-617471D01*
X478427Y-617555D01*
Y-617721D01*
X478300Y-617805D01*
G01Y-615555D02*
X478173Y-615471D01*
Y-615305D01*
X478300Y-615221D01*
X478427Y-615305D01*
Y-615471D01*
X478300Y-615555D01*
G01X456633Y-592638D02*
Y-587638D01*
X458217D01*
X458723Y-587888D01*
X459040Y-588221D01*
X459167Y-588888D01*
X459040Y-589555D01*
X458660Y-589971D01*
X458217Y-590221D01*
X456633D01*
G01X458217D02*
X459167Y-592638D01*
G01X464267D02*
X461733D01*
Y-587638D01*
X464267D01*
G01X463253Y-590055D02*
X461733D01*
G01X466517Y-587638D02*
X468100Y-592638D01*
X469683Y-587638D01*
G01X473200Y-592805D02*
X473073Y-592721D01*
Y-592555D01*
X473200Y-592471D01*
X473327Y-592555D01*
Y-592721D01*
X473200Y-592805D01*
G01Y-590555D02*
X473073Y-590471D01*
Y-590305D01*
X473200Y-590221D01*
X473327Y-590305D01*
Y-590471D01*
X473200Y-590555D01*
G01X530516Y578130D02*
G02X515831I-7343J0D01*
G02X530516I7342J0D01*
G01X569016Y838543D02*
G02X553268I-7874J0D01*
G02X569016I7874J0D01*
G01Y1199961D02*
G02X553268I-7874J0D01*
G02X569016I7874J0D01*
G01X614291Y1019252D02*
G02X598543I-7874J0D01*
G02X614291I7874J0D01*
G01X672047Y631890D02*
G02X650000I-11024J0D01*
G02X672047I11023J0D01*
G01X688783Y1385138D02*
G02X674098I-7343J0D01*
G02X688783I7343J0D01*
G01X682087Y1593661D02*
G02X664370I-8859J0D01*
G02X682087I8859J0D01*
G01X684500Y294362D02*
G02X723870I19685J0D01*
G01Y260110D01*
G02X684500I-19685J0D01*
G01Y294362D01*
G01X707677Y1482244D02*
G02X689961I-8858J0D01*
G02X707677I8858J0D01*
G01X718701Y1714961D02*
G02X696654I-11024J0D01*
G02X718701I11023J0D01*
G01X783287Y605413D02*
G02X743917I-19685J0D01*
G02X783287I19685J0D01*
G01X811811Y87795D02*
G02X789764I-11023J0D01*
G02X811811I11023J0D01*
G01X816535Y204724D02*
G02X794882I-10826J0D01*
G02X816535I10827J0D01*
G01X799020Y1385138D02*
G02X784335I-7343J0D01*
G02X799020I7342J0D01*
G01X849114Y1420331D02*
G02X833366I-7874J0D01*
G02X849114I7874J0D01*
G01X880965Y1145276D02*
G02X866280I-7342J0D01*
G02X880965I7343J0D01*
G01X895789Y1528196D02*
G02X879254I-8267J0D01*
G02X895789I8268J0D01*
G01X904134Y175177D02*
G02X896260I-3937J0D01*
G02X904134I3937J0D01*
G01X936673Y311614D02*
X920807D01*
G02X936673I7933J10039D01*
G01X942717Y757874D02*
G02X920669I-11024J0D01*
G02X942717I11024J0D01*
G01Y1072835D02*
G02X920669I-11024J0D01*
G02X942717I11024J0D01*
G01Y1387795D02*
G02X920669I-11024J0D01*
G02X942717I11024J0D01*
G01X948622Y155197D02*
G02X940748I-3937J0D01*
G02X948622I3937J0D01*
G01X991201Y1145276D02*
G02X976516I-7343J0D01*
G02X991201I7343J0D01*
G01X1024114Y1420331D02*
G02X1008366I-7874J0D01*
G02X1024114I7874J0D01*
G01X1056890Y87795D02*
G02X1034843I-11023J0D01*
G02X1056890I11024J0D01*
G01X1068504Y204724D02*
G02X1046850I-10827J0D01*
G02X1068504I10827J0D01*
G01X1060303Y1369350D02*
G02X1045618I-7343J0D01*
G02X1060303I7343J0D01*
G01X1113760Y605378D02*
G02X1074390I-19685J0D01*
G02X1113760I19685J0D01*
G01X1133870Y294335D02*
G02X1173240I19685J0D01*
G01Y260083D01*
G02X1133870I-19685J0D01*
G01Y294335D01*
G01X1154803Y1515236D02*
G02X1137087I-8858J0D01*
G02X1154803I8858J0D01*
G01X1166732Y1714961D02*
G02X1144685I-11024J0D01*
G02X1166732I11023J0D01*
G01X1180394Y1626654D02*
G02X1162677I-8859J0D01*
G02X1180394I8859J0D01*
G01X1258937Y1019252D02*
G02X1243189I-7874J0D01*
G02X1258937I7874J0D01*
G01X1257154Y1357539D02*
G02X1242469I-7343J0D01*
G02X1257154I7343J0D01*
G01X1282283Y631890D02*
G02X1260236I-11023J0D01*
G02X1282283I11023J0D01*
G01X1304213Y838543D02*
G02X1288465I-7874J0D01*
G02X1304213I7874J0D01*
G01Y1199961D02*
G02X1288465I-7874J0D01*
G02X1304213I7874J0D01*
G01X1377626Y582303D02*
G02X1362941I-7343J0D01*
G02X1377626I7342J0D01*
G01X1424476Y1339823D02*
G02X1409791I-7343J0D01*
G02X1424476I7342J0D01*
G01X1410187Y1698268D02*
G02X1422687I6250J0D01*
G02X1410187I-6250J0D01*
G01X1472829Y1714961D02*
G02X1450782I-11024J0D01*
G02X1472829I11023J0D01*
G01X1510630Y87795D02*
G02X1488583I-11023J0D01*
G02X1510630I11024J0D01*
G01X1540894Y682343D02*
G02X1526209I-7343J0D01*
G02X1540894I7342J0D01*
G01X1545157Y838543D02*
G02X1529409I-7874J0D01*
G02X1545157I7874J0D01*
G01Y1199961D02*
G02X1529409I-7874J0D01*
G02X1545157I7874J0D01*
G01X1590433Y1019252D02*
G02X1574685I-7874J0D01*
G02X1590433I7874J0D01*
G01X1637075Y1383524D02*
G02X1622390I-7343J0D01*
G02X1637075I7343J0D01*
G01X1660642Y294362D02*
G02X1700012I19685J0D01*
G01Y260110D01*
G02X1660642I-19685J0D01*
G01Y294362D01*
G01X1672232Y642972D02*
G02X1657547I-7343J0D01*
G02X1672232I7342J0D01*
G01X1689961Y1626654D02*
G02X1672244I-8859J0D01*
G02X1689961I8859J0D01*
G01X1715551Y1515236D02*
G02X1697835I-8858J0D01*
G02X1715551I8858J0D01*
G01X1759429Y605413D02*
G02X1720059I-19685J0D01*
G02X1759429I19685J0D01*
G01X1721673Y1570984D02*
G02X1706988I-7342J0D01*
G02X1721673I7343J0D01*
G01X1747311Y1383524D02*
G02X1732626I-7343J0D01*
G02X1747311I7343J0D01*
G01X1768917Y159134D02*
G02X1754232I-7342J0D01*
G02X1768917I7343J0D01*
G01X1773031Y1714961D02*
G02X1760827I-6102J0D01*
G02X1773031I6102J0D01*
G01X1817323D02*
G02X1795276I-11023J0D01*
G02X1817323I11024J0D01*
G01X1827795Y631890D02*
G02X1805748I-11023J0D01*
G02X1827795I11024J0D01*
G01Y1368898D02*
G02X1805748I-11023J0D01*
G02X1827795I11024J0D01*
G01X1840945Y87795D02*
G02X1818898I-11023J0D01*
G02X1840945I11023J0D01*
G01X1823819Y133465D02*
G02X1836024I6103J0D01*
G01Y127165D01*
G02X1823819I-6103J0D01*
G01Y133465D01*
G01X1831909Y1570984D02*
G02X1817224I-7342J0D01*
G02X1831909I7343J0D01*
G01X1845492Y201929D02*
G02X1830807I-7342J0D01*
G02X1845492I7343J0D01*
G01X-476840Y-884638D02*
Y2768362D01*
X5911000D01*
Y-884638D01*
X-476840D01*
G01X8820Y-607488D02*
X10387D01*
Y-609378D01*
X9917Y-610008D01*
X9368Y-610428D01*
X8585Y-610638D01*
X7802Y-610428D01*
X7253Y-610008D01*
X6783Y-609378D01*
X6470Y-608643D01*
X6313Y-607803D01*
Y-607068D01*
X6470Y-606438D01*
X6783Y-605703D01*
X7253Y-605073D01*
X7723Y-604653D01*
X8350Y-604338D01*
X8898D01*
X9525Y-604548D01*
X9995Y-604968D01*
G01X12927Y-604338D02*
Y-608853D01*
X13240Y-609798D01*
X13867Y-610428D01*
X14650Y-610638D01*
X15433Y-610428D01*
X16060Y-609798D01*
X16373Y-608853D01*
Y-604338D01*
G01X20010D02*
X21890D01*
G01X20950D02*
Y-610638D01*
G01X20010D02*
X21890D01*
G01X25605Y-609798D02*
X26232Y-610323D01*
X26937Y-610638D01*
X27563D01*
X28190Y-610323D01*
X28660Y-609798D01*
X28895Y-609063D01*
X28738Y-608328D01*
X28347Y-607698D01*
X27642Y-607278D01*
X26702Y-607068D01*
X26153Y-606648D01*
X25918Y-605913D01*
X26075Y-605178D01*
X26467Y-604653D01*
X27015Y-604338D01*
X27563D01*
X28112Y-604548D01*
X28582Y-605073D01*
G01X31905Y-610638D02*
Y-604338D01*
G01X35195D02*
Y-610638D01*
G01Y-607488D02*
X31905D01*
G01X37892Y-610638D02*
X39850Y-604338D01*
X41808Y-610638D01*
G01X41103Y-608433D02*
X38597D01*
G01X44348Y-610638D02*
Y-604338D01*
X47952Y-610638D01*
Y-604338D01*
G01X57027Y-610638D02*
Y-604338D01*
X58593D01*
X59220Y-604653D01*
X59690Y-605073D01*
X60082Y-605703D01*
X60395Y-606438D01*
X60473Y-607488D01*
X60395Y-608538D01*
X60082Y-609273D01*
X59690Y-609903D01*
X59220Y-610323D01*
X58593Y-610638D01*
X57027D01*
G01X64110Y-604338D02*
X65990D01*
G01X65050D02*
Y-610638D01*
G01X64110D02*
X65990D01*
G01X69705Y-609798D02*
X70332Y-610323D01*
X71037Y-610638D01*
X71663D01*
X72290Y-610323D01*
X72760Y-609798D01*
X72995Y-609063D01*
X72838Y-608328D01*
X72447Y-607698D01*
X71742Y-607278D01*
X70802Y-607068D01*
X70253Y-606648D01*
X70018Y-605913D01*
X70175Y-605178D01*
X70567Y-604653D01*
X71115Y-604338D01*
X71663D01*
X72212Y-604548D01*
X72682Y-605073D01*
G01X77650Y-604338D02*
Y-610638D01*
G01X75848Y-604338D02*
X79452D01*
G01X83950Y-610848D02*
X83793Y-610743D01*
Y-610533D01*
X83950Y-610428D01*
X84107Y-610533D01*
Y-610743D01*
X83950Y-610848D01*
G01X90093Y-611793D02*
X90407Y-610428D01*
G01X96550Y-604338D02*
Y-610638D01*
G01X94748Y-604338D02*
X98352D01*
G01X100892Y-610638D02*
X102850Y-604338D01*
X104808Y-610638D01*
G01X104103Y-608433D02*
X101597D01*
G01X109150Y-610638D02*
X108523Y-610533D01*
X107975Y-610113D01*
X107505Y-609483D01*
X107192Y-608748D01*
X107035Y-607908D01*
Y-607068D01*
X107192Y-606228D01*
X107505Y-605493D01*
X107975Y-604863D01*
X108523Y-604443D01*
X109150Y-604338D01*
X109777Y-604443D01*
X110325Y-604863D01*
X110795Y-605493D01*
X111108Y-606228D01*
X111265Y-607068D01*
Y-607908D01*
X111108Y-608748D01*
X110795Y-609483D01*
X110325Y-610113D01*
X109777Y-610533D01*
X109150Y-610638D01*
G01X115450D02*
Y-607803D01*
X113883Y-604338D01*
G01X117017D02*
X115450Y-607803D01*
G01X120027Y-604338D02*
Y-608853D01*
X120340Y-609798D01*
X120967Y-610428D01*
X121750Y-610638D01*
X122533Y-610428D01*
X123160Y-609798D01*
X123473Y-608853D01*
Y-604338D01*
G01X126092Y-610638D02*
X128050Y-604338D01*
X130008Y-610638D01*
G01X129303Y-608433D02*
X126797D01*
G01X132548Y-610638D02*
Y-604338D01*
X136152Y-610638D01*
Y-604338D01*
G01X10073Y-614863D02*
X9603Y-614548D01*
X9055Y-614338D01*
X8428D01*
X7723Y-614653D01*
X7175Y-615178D01*
X6783Y-615808D01*
X6470Y-616858D01*
X6392Y-617803D01*
X6548Y-618748D01*
X6783Y-619378D01*
X7253Y-620008D01*
X7802Y-620428D01*
X8350Y-620638D01*
X8898D01*
X9447Y-620428D01*
X9917Y-620113D01*
X10308Y-619693D01*
G01X13710Y-614338D02*
X15590D01*
G01X14650D02*
Y-620638D01*
G01X13710D02*
X15590D01*
G01X20950Y-614338D02*
Y-620638D01*
G01X19148Y-614338D02*
X22752D01*
G01X27250Y-620638D02*
Y-617803D01*
X25683Y-614338D01*
G01X28817D02*
X27250Y-617803D01*
G01X38127Y-619378D02*
X38597Y-620113D01*
X39223Y-620533D01*
X39928Y-620638D01*
X40555Y-620533D01*
X41182Y-620008D01*
X41573Y-619378D01*
X41652Y-618748D01*
X41495Y-618013D01*
X40947Y-617488D01*
X40398Y-617278D01*
X39693D01*
G01X40398D02*
X40868Y-616963D01*
X41260Y-616438D01*
X41417Y-615808D01*
X41260Y-615178D01*
X40868Y-614653D01*
X40163Y-614338D01*
X39458Y-614443D01*
X38753Y-614863D01*
G01X44427Y-619378D02*
X44897Y-620113D01*
X45523Y-620533D01*
X46228Y-620638D01*
X46855Y-620533D01*
X47482Y-620008D01*
X47873Y-619378D01*
X47952Y-618748D01*
X47795Y-618013D01*
X47247Y-617488D01*
X46698Y-617278D01*
X45993D01*
G01X46698D02*
X47168Y-616963D01*
X47560Y-616438D01*
X47717Y-615808D01*
X47560Y-615178D01*
X47168Y-614653D01*
X46463Y-614338D01*
X45758Y-614443D01*
X45053Y-614863D01*
G01X50727Y-619378D02*
X51197Y-620113D01*
X51823Y-620533D01*
X52528Y-620638D01*
X53155Y-620533D01*
X53782Y-620008D01*
X54173Y-619378D01*
X54252Y-618748D01*
X54095Y-618013D01*
X53547Y-617488D01*
X52998Y-617278D01*
X52293D01*
G01X52998D02*
X53468Y-616963D01*
X53860Y-616438D01*
X54017Y-615808D01*
X53860Y-615178D01*
X53468Y-614653D01*
X52763Y-614338D01*
X52058Y-614443D01*
X51353Y-614863D01*
G01X58593Y-620638D02*
X58750Y-619273D01*
X58985Y-618118D01*
X59298Y-617068D01*
X59690Y-615913D01*
X60317Y-614338D01*
X57183D01*
G01X64893Y-620638D02*
X65050Y-619273D01*
X65285Y-618118D01*
X65598Y-617068D01*
X65990Y-615913D01*
X66617Y-614338D01*
X63483D01*
G01X71193Y-621793D02*
X71507Y-620428D01*
G01X77650Y-614338D02*
Y-620638D01*
G01X75848Y-614338D02*
X79452D01*
G01X81992Y-620638D02*
X83950Y-614338D01*
X85908Y-620638D01*
G01X85203Y-618433D02*
X82697D01*
G01X89310Y-614338D02*
X91190D01*
G01X90250D02*
Y-620638D01*
G01X89310D02*
X91190D01*
G01X94200Y-614338D02*
X95297Y-620638D01*
X96550Y-614338D01*
X97803Y-620638D01*
X98900Y-614338D01*
G01X100892Y-620638D02*
X102850Y-614338D01*
X104808Y-620638D01*
G01X104103Y-618433D02*
X101597D01*
G01X107348Y-620638D02*
Y-614338D01*
X110952Y-620638D01*
Y-614338D01*
G01X121358Y-622738D02*
X120575Y-621688D01*
X120183Y-620638D01*
Y-616438D01*
X120575Y-615388D01*
X121358Y-614338D01*
G01X132783Y-620638D02*
Y-614338D01*
X134742D01*
X135368Y-614653D01*
X135760Y-615073D01*
X135917Y-615913D01*
X135760Y-616753D01*
X135290Y-617278D01*
X134742Y-617593D01*
X132783D01*
G01X134742D02*
X135917Y-620638D01*
G01X140650Y-620848D02*
X140493Y-620743D01*
Y-620533D01*
X140650Y-620428D01*
X140807Y-620533D01*
Y-620743D01*
X140650Y-620848D01*
G01X146950Y-620638D02*
X146323Y-620533D01*
X145775Y-620113D01*
X145305Y-619483D01*
X144992Y-618748D01*
X144835Y-617908D01*
Y-617068D01*
X144992Y-616228D01*
X145305Y-615493D01*
X145775Y-614863D01*
X146323Y-614443D01*
X146950Y-614338D01*
X147577Y-614443D01*
X148125Y-614863D01*
X148595Y-615493D01*
X148908Y-616228D01*
X149065Y-617068D01*
Y-617908D01*
X148908Y-618748D01*
X148595Y-619483D01*
X148125Y-620113D01*
X147577Y-620533D01*
X146950Y-620638D01*
G01X153250Y-620848D02*
X153093Y-620743D01*
Y-620533D01*
X153250Y-620428D01*
X153407Y-620533D01*
Y-620743D01*
X153250Y-620848D01*
G01X161273Y-614863D02*
X160803Y-614548D01*
X160255Y-614338D01*
X159628D01*
X158923Y-614653D01*
X158375Y-615178D01*
X157983Y-615808D01*
X157670Y-616858D01*
X157592Y-617803D01*
X157748Y-618748D01*
X157983Y-619378D01*
X158453Y-620008D01*
X159002Y-620428D01*
X159550Y-620638D01*
X160098D01*
X160647Y-620428D01*
X161117Y-620113D01*
X161508Y-619693D01*
G01X165850Y-620848D02*
X165693Y-620743D01*
Y-620533D01*
X165850Y-620428D01*
X166007Y-620533D01*
Y-620743D01*
X165850Y-620848D01*
G01X172542Y-622738D02*
X173325Y-621688D01*
X173717Y-620638D01*
Y-616438D01*
X173325Y-615388D01*
X172542Y-614338D01*
G01X6548Y-600638D02*
Y-594338D01*
X10152Y-600638D01*
Y-594338D01*
G01X14650Y-600638D02*
X14023Y-600533D01*
X13475Y-600113D01*
X13005Y-599483D01*
X12692Y-598748D01*
X12535Y-597908D01*
Y-597068D01*
X12692Y-596228D01*
X13005Y-595493D01*
X13475Y-594863D01*
X14023Y-594443D01*
X14650Y-594338D01*
X15277Y-594443D01*
X15825Y-594863D01*
X16295Y-595493D01*
X16608Y-596228D01*
X16765Y-597068D01*
Y-597908D01*
X16608Y-598748D01*
X16295Y-599483D01*
X15825Y-600113D01*
X15277Y-600533D01*
X14650Y-600638D01*
G01X20950Y-600848D02*
X20793Y-600743D01*
Y-600533D01*
X20950Y-600428D01*
X21107Y-600533D01*
Y-600743D01*
X20950Y-600848D01*
G01X25762Y-595388D02*
X26232Y-594758D01*
X26780Y-594443D01*
X27407Y-594338D01*
X28190Y-594548D01*
X28738Y-595073D01*
X28895Y-595703D01*
X28817Y-596333D01*
X28503Y-596858D01*
X26937Y-597908D01*
X26232Y-598643D01*
X25762Y-599693D01*
X25605Y-600638D01*
X28895D01*
G01X33550D02*
Y-594338D01*
X32610Y-595598D01*
G01Y-600638D02*
X34490D01*
G01X39850D02*
Y-594338D01*
X38910Y-595598D01*
G01Y-600638D02*
X40790D01*
G01X45993Y-601793D02*
X46307Y-600428D01*
G01X50100Y-594338D02*
X51197Y-600638D01*
X52450Y-594338D01*
X53703Y-600638D01*
X54800Y-594338D01*
G01X60317Y-600638D02*
X57183D01*
Y-594338D01*
X60317D01*
G01X59063Y-597383D02*
X57183D01*
G01X63248Y-600638D02*
Y-594338D01*
X66852Y-600638D01*
Y-594338D01*
G01X69705Y-600638D02*
Y-594338D01*
G01X72995D02*
Y-600638D01*
G01Y-597488D02*
X69705D01*
G01X75927Y-594338D02*
Y-598853D01*
X76240Y-599798D01*
X76867Y-600428D01*
X77650Y-600638D01*
X78433Y-600428D01*
X79060Y-599798D01*
X79373Y-598853D01*
Y-594338D01*
G01X81992Y-600638D02*
X83950Y-594338D01*
X85908Y-600638D01*
G01X85203Y-598433D02*
X82697D01*
G01X95062Y-595388D02*
X95532Y-594758D01*
X96080Y-594443D01*
X96707Y-594338D01*
X97490Y-594548D01*
X98038Y-595073D01*
X98195Y-595703D01*
X98117Y-596333D01*
X97803Y-596858D01*
X96237Y-597908D01*
X95532Y-598643D01*
X95062Y-599693D01*
X94905Y-600638D01*
X98195D01*
G01X101048D02*
Y-594338D01*
X104652Y-600638D01*
Y-594338D01*
G01X107427Y-600638D02*
Y-594338D01*
X108993D01*
X109620Y-594653D01*
X110090Y-595073D01*
X110482Y-595703D01*
X110795Y-596438D01*
X110873Y-597488D01*
X110795Y-598538D01*
X110482Y-599273D01*
X110090Y-599903D01*
X109620Y-600323D01*
X108993Y-600638D01*
X107427D01*
G01X120183D02*
Y-594338D01*
X122142D01*
X122768Y-594653D01*
X123160Y-595073D01*
X123317Y-595913D01*
X123160Y-596753D01*
X122690Y-597278D01*
X122142Y-597593D01*
X120183D01*
G01X122142D02*
X123317Y-600638D01*
G01X126327D02*
Y-594338D01*
X127893D01*
X128520Y-594653D01*
X128990Y-595073D01*
X129382Y-595703D01*
X129695Y-596438D01*
X129773Y-597488D01*
X129695Y-598538D01*
X129382Y-599273D01*
X128990Y-599903D01*
X128520Y-600323D01*
X127893Y-600638D01*
X126327D01*
G01X134350Y-600848D02*
X134193Y-600743D01*
Y-600533D01*
X134350Y-600428D01*
X134507Y-600533D01*
Y-600743D01*
X134350Y-600848D01*
G01X7468Y109174D02*
Y112274D01*
G01X9078D02*
Y109174D01*
G01Y110724D02*
X7468D01*
G01X10721Y109536D02*
X10990Y109277D01*
X11296Y109174D01*
X11603Y109277D01*
X11871Y109587D01*
X12063Y110052D01*
X12140Y110517D01*
Y111086D01*
X12063Y111551D01*
X11871Y111964D01*
X11641Y112171D01*
X11373Y112274D01*
X11066Y112171D01*
X10836Y111964D01*
X10683Y111654D01*
X10606Y111241D01*
X10683Y110879D01*
X10875Y110517D01*
X11105Y110311D01*
X11373Y110259D01*
X11680Y110362D01*
X11910Y110621D01*
X12140Y111086D01*
G01X14473Y109174D02*
Y112274D01*
X14013Y111654D01*
G01Y109174D02*
X14933D01*
G01X-3941Y1665676D02*
X-4096Y1665829D01*
X-4355Y1665944D01*
X-4716Y1666021D01*
X-5026Y1665944D01*
X-5233Y1665791D01*
X-5388Y1665522D01*
Y1664487D01*
X-2288D01*
Y1665752D01*
X-2495Y1666021D01*
X-2805Y1666174D01*
X-3166Y1666251D01*
X-3528Y1666174D01*
X-3838Y1665944D01*
X-3941Y1665676D01*
Y1664487D01*
G01X-5388Y1668009D02*
Y1668929D01*
G01Y1668469D02*
X-2288D01*
G01Y1668009D02*
Y1668929D01*
G01Y1671569D02*
X-2340Y1671262D01*
X-2546Y1670994D01*
X-2856Y1670764D01*
X-3218Y1670611D01*
X-3631Y1670534D01*
X-4045D01*
X-4458Y1670611D01*
X-4820Y1670764D01*
X-5130Y1670994D01*
X-5336Y1671262D01*
X-5388Y1671569D01*
X-5336Y1671876D01*
X-5130Y1672144D01*
X-4820Y1672374D01*
X-4458Y1672527D01*
X-4045Y1672604D01*
X-3631D01*
X-3218Y1672527D01*
X-2856Y1672374D01*
X-2546Y1672144D01*
X-2340Y1671876D01*
X-2288Y1671569D01*
G01X-2701Y1673864D02*
X-2443Y1674171D01*
X-2288Y1674516D01*
Y1674822D01*
X-2443Y1675129D01*
X-2701Y1675359D01*
X-3063Y1675474D01*
X-3425Y1675397D01*
X-3735Y1675206D01*
X-3941Y1674861D01*
X-4045Y1674401D01*
X-4251Y1674132D01*
X-4613Y1674017D01*
X-4975Y1674094D01*
X-5233Y1674286D01*
X-5388Y1674554D01*
Y1674822D01*
X-5285Y1675091D01*
X-5026Y1675321D01*
G01X-1255Y1676619D02*
Y1678919D01*
G01X-5388Y1680102D02*
X-2288D01*
Y1681636D01*
G01Y1683011D02*
X-5388Y1683969D01*
X-2288Y1684927D01*
G01X-3373Y1684582D02*
Y1683356D01*
G01X-3941Y1687376D02*
X-4096Y1687529D01*
X-4355Y1687644D01*
X-4716Y1687721D01*
X-5026Y1687644D01*
X-5233Y1687491D01*
X-5388Y1687222D01*
Y1686187D01*
X-2288D01*
Y1687452D01*
X-2495Y1687721D01*
X-2805Y1687874D01*
X-3166Y1687951D01*
X-3528Y1687874D01*
X-3838Y1687644D01*
X-3941Y1687376D01*
Y1686187D01*
G01X-2288Y1690936D02*
Y1689402D01*
X-5388D01*
Y1690936D01*
G01X-3890Y1690322D02*
Y1689402D01*
G01X-5388Y1692502D02*
X-2288D01*
Y1694036D01*
G01X30650Y-589938D02*
X28130Y-589521D01*
X25925Y-587855D01*
X24035Y-585355D01*
X22775Y-582438D01*
X22145Y-579105D01*
Y-575771D01*
X22775Y-572438D01*
X24035Y-569521D01*
X25925Y-567022D01*
X28130Y-565355D01*
X30650Y-564938D01*
X33170Y-565355D01*
X35375Y-567022D01*
X37265Y-569521D01*
X38525Y-572438D01*
X39155Y-575771D01*
Y-579105D01*
X38525Y-582438D01*
X37265Y-585355D01*
X35375Y-587855D01*
X33170Y-589521D01*
X30650Y-589938D01*
G01X33170Y-583271D02*
X36950Y-589938D01*
G01X50495Y-573272D02*
Y-584938D01*
X51755Y-587855D01*
X53645Y-589521D01*
X55850Y-589938D01*
X58055Y-589521D01*
X59945Y-587855D01*
X61205Y-584938D01*
G01Y-589938D02*
Y-573272D01*
G01X86720Y-589938D02*
Y-573272D01*
G01Y-576188D02*
X85460Y-574522D01*
X83570Y-573688D01*
X81365Y-573272D01*
X79160Y-574105D01*
X77270Y-575771D01*
X76010Y-578272D01*
X75380Y-581605D01*
X76010Y-584938D01*
X77270Y-587439D01*
X79160Y-589105D01*
X81365Y-589938D01*
X83570Y-589521D01*
X85460Y-588272D01*
X86720Y-586605D01*
G01X100895Y-589938D02*
Y-573272D01*
G01Y-577438D02*
X102155Y-575355D01*
X104045Y-573688D01*
X106565Y-573272D01*
X108770Y-573688D01*
X110660Y-575355D01*
X111605Y-578272D01*
Y-589938D01*
G01X131450Y-564938D02*
Y-589938D01*
G01X127040Y-573272D02*
X135860D01*
G01X162320Y-589938D02*
Y-573272D01*
G01Y-576188D02*
X161060Y-574522D01*
X159170Y-573688D01*
X156965Y-573272D01*
X154760Y-574105D01*
X152870Y-575771D01*
X151610Y-578272D01*
X150980Y-581605D01*
X151610Y-584938D01*
X152870Y-587439D01*
X154760Y-589105D01*
X156965Y-589938D01*
X159170Y-589521D01*
X161060Y-588272D01*
X162320Y-586605D01*
G01X10182Y170376D02*
Y176576D01*
G01D02*
X13382D01*
G01D02*
Y170376D01*
G01D02*
X10182D01*
G01X17091Y170548D02*
Y176748D01*
G01D02*
X20291D01*
G01D02*
Y170548D01*
G01D02*
X17091D01*
G01X18963Y234848D02*
Y228648D01*
G01D02*
X15763D01*
G01D02*
Y234848D01*
G01D02*
X18963D01*
G01X12143Y234892D02*
Y228692D01*
G01D02*
X8943D01*
G01D02*
Y234892D01*
G01D02*
X12143D01*
G01X21080Y296672D02*
X18078Y300274D01*
G01X16328D02*
Y288070D01*
G01D02*
X25832D01*
G01X24082Y300274D02*
X21080Y296672D01*
G01X11987Y304739D02*
Y302517D01*
X12140Y302052D01*
X12447Y301742D01*
X12830Y301639D01*
X13213Y301742D01*
X13520Y302052D01*
X13673Y302517D01*
Y304739D01*
G01X15202Y304222D02*
X15432Y304532D01*
X15700Y304687D01*
X16007Y304739D01*
X16390Y304636D01*
X16658Y304377D01*
X16735Y304067D01*
X16697Y303757D01*
X16543Y303499D01*
X15777Y302982D01*
X15432Y302621D01*
X15202Y302104D01*
X15125Y301639D01*
X16735D01*
G01X19490D02*
Y304739D01*
X18072Y302517D01*
X19988D01*
G01X22130Y301639D02*
Y304739D01*
X21670Y304119D01*
G01Y301639D02*
X22590D01*
G01X18078Y300274D02*
X16328D01*
G01X18091Y402962D02*
Y404357D01*
X17324Y406062D01*
G01X18858D02*
X18091Y404357D01*
G01X21191Y402962D02*
X21459Y403014D01*
X21766Y403169D01*
X21958Y403427D01*
X22034Y403789D01*
X21958Y404150D01*
X21728Y404460D01*
X21383Y404615D01*
X20999D01*
X20769Y404719D01*
X20578Y404977D01*
X20501Y405339D01*
X20616Y405700D01*
X20884Y405959D01*
X21191Y406062D01*
X21498Y405959D01*
X21766Y405700D01*
X21881Y405339D01*
X21804Y404977D01*
X21613Y404719D01*
X21383Y404615D01*
X20999D01*
X20654Y404460D01*
X20424Y404150D01*
X20348Y403789D01*
X20424Y403427D01*
X20616Y403169D01*
X20923Y403014D01*
X21191Y402962D01*
G01X24291Y406062D02*
X23984Y405959D01*
X23754Y405700D01*
X23601Y405390D01*
X23486Y404977D01*
X23448Y404512D01*
X23486Y404047D01*
X23601Y403634D01*
X23754Y403324D01*
X23984Y403065D01*
X24291Y402962D01*
X24598Y403065D01*
X24828Y403324D01*
X24981Y403634D01*
X25096Y404047D01*
X25134Y404512D01*
X25096Y404977D01*
X24981Y405390D01*
X24828Y405700D01*
X24598Y405959D01*
X24291Y406062D01*
G01X27391D02*
X27084Y405959D01*
X26854Y405700D01*
X26701Y405390D01*
X26586Y404977D01*
X26548Y404512D01*
X26586Y404047D01*
X26701Y403634D01*
X26854Y403324D01*
X27084Y403065D01*
X27391Y402962D01*
X27698Y403065D01*
X27928Y403324D01*
X28081Y403634D01*
X28196Y404047D01*
X28234Y404512D01*
X28196Y404977D01*
X28081Y405390D01*
X27928Y405700D01*
X27698Y405959D01*
X27391Y406062D01*
G01X30951Y402962D02*
Y406062D01*
X29533Y403840D01*
X31449D01*
G01X23432Y515351D02*
X17232D01*
G01Y518551D02*
X23432D01*
G01X17232Y515351D02*
Y518551D01*
G01X29787Y540724D02*
Y525324D01*
X17687D01*
Y540724D01*
X29787D01*
G01X18587Y544124D02*
Y545519D01*
X17820Y547224D01*
G01X19354D02*
X18587Y545519D01*
G01X21687Y544124D02*
X21955Y544176D01*
X22262Y544331D01*
X22454Y544589D01*
X22530Y544951D01*
X22454Y545312D01*
X22224Y545622D01*
X21879Y545777D01*
X21495D01*
X21265Y545881D01*
X21074Y546139D01*
X20997Y546501D01*
X21112Y546862D01*
X21380Y547121D01*
X21687Y547224D01*
X21994Y547121D01*
X22262Y546862D01*
X22377Y546501D01*
X22300Y546139D01*
X22109Y545881D01*
X21879Y545777D01*
X21495D01*
X21150Y545622D01*
X20920Y545312D01*
X20844Y544951D01*
X20920Y544589D01*
X21112Y544331D01*
X21419Y544176D01*
X21687Y544124D01*
G01X24787Y547224D02*
X24480Y547121D01*
X24250Y546862D01*
X24097Y546552D01*
X23982Y546139D01*
X23944Y545674D01*
X23982Y545209D01*
X24097Y544796D01*
X24250Y544486D01*
X24480Y544227D01*
X24787Y544124D01*
X25094Y544227D01*
X25324Y544486D01*
X25477Y544796D01*
X25592Y545209D01*
X25630Y545674D01*
X25592Y546139D01*
X25477Y546552D01*
X25324Y546862D01*
X25094Y547121D01*
X24787Y547224D01*
G01X27887D02*
X27580Y547121D01*
X27350Y546862D01*
X27197Y546552D01*
X27082Y546139D01*
X27044Y545674D01*
X27082Y545209D01*
X27197Y544796D01*
X27350Y544486D01*
X27580Y544227D01*
X27887Y544124D01*
X28194Y544227D01*
X28424Y544486D01*
X28577Y544796D01*
X28692Y545209D01*
X28730Y545674D01*
X28692Y546139D01*
X28577Y546552D01*
X28424Y546862D01*
X28194Y547121D01*
X27887Y547224D01*
G01X30144Y544744D02*
X30374Y544382D01*
X30680Y544176D01*
X31025Y544124D01*
X31332Y544176D01*
X31639Y544434D01*
X31830Y544744D01*
X31869Y545054D01*
X31792Y545416D01*
X31524Y545674D01*
X31255Y545777D01*
X30910D01*
G01X31255D02*
X31485Y545932D01*
X31677Y546191D01*
X31754Y546501D01*
X31677Y546811D01*
X31485Y547069D01*
X31140Y547224D01*
X30795Y547172D01*
X30450Y546966D01*
G01X17883Y1451500D02*
Y1454600D01*
X18803D01*
X19110Y1454445D01*
X19340Y1454083D01*
X19417Y1453670D01*
X19340Y1453257D01*
X19148Y1452947D01*
X18803Y1452792D01*
X17883D01*
G01X22593Y1454342D02*
X22363Y1454497D01*
X22095Y1454600D01*
X21788D01*
X21443Y1454445D01*
X21175Y1454187D01*
X20983Y1453877D01*
X20830Y1453360D01*
X20792Y1452895D01*
X20868Y1452430D01*
X20983Y1452120D01*
X21213Y1451810D01*
X21482Y1451603D01*
X21750Y1451500D01*
X22018D01*
X22287Y1451603D01*
X22517Y1451758D01*
X22708Y1451965D01*
G01X24122Y1452792D02*
X24390Y1453153D01*
X24620Y1453360D01*
X24927Y1453463D01*
X25195Y1453360D01*
X25387Y1453153D01*
X25540Y1452843D01*
X25578Y1452482D01*
X25540Y1452172D01*
X25387Y1451862D01*
X25157Y1451603D01*
X24888Y1451500D01*
X24582Y1451603D01*
X24313Y1451913D01*
X24160Y1452378D01*
X24122Y1452895D01*
X24198Y1453567D01*
X24313Y1453928D01*
X24505Y1454290D01*
X24773Y1454548D01*
X25042Y1454600D01*
X25310Y1454497D01*
X25502Y1454238D01*
G01X27222Y1452792D02*
X27490Y1453153D01*
X27720Y1453360D01*
X28027Y1453463D01*
X28295Y1453360D01*
X28487Y1453153D01*
X28640Y1452843D01*
X28678Y1452482D01*
X28640Y1452172D01*
X28487Y1451862D01*
X28257Y1451603D01*
X27988Y1451500D01*
X27682Y1451603D01*
X27413Y1451913D01*
X27260Y1452378D01*
X27222Y1452895D01*
X27298Y1453567D01*
X27413Y1453928D01*
X27605Y1454290D01*
X27873Y1454548D01*
X28142Y1454600D01*
X28410Y1454497D01*
X28602Y1454238D01*
G01X30207Y1452120D02*
X30437Y1451758D01*
X30743Y1451552D01*
X31088Y1451500D01*
X31395Y1451552D01*
X31702Y1451810D01*
X31893Y1452120D01*
X31932Y1452430D01*
X31855Y1452792D01*
X31587Y1453050D01*
X31318Y1453153D01*
X30973D01*
G01X31318D02*
X31548Y1453308D01*
X31740Y1453567D01*
X31817Y1453877D01*
X31740Y1454187D01*
X31548Y1454445D01*
X31203Y1454600D01*
X30858Y1454548D01*
X30513Y1454342D01*
G01X33422Y1454083D02*
X33652Y1454393D01*
X33920Y1454548D01*
X34227Y1454600D01*
X34610Y1454497D01*
X34878Y1454238D01*
X34955Y1453928D01*
X34917Y1453618D01*
X34763Y1453360D01*
X33997Y1452843D01*
X33652Y1452482D01*
X33422Y1451965D01*
X33345Y1451500D01*
X34955D01*
G01X15445Y1459448D02*
X22572D01*
G01X15445Y1478102D02*
Y1459448D01*
G01X18445Y1481102D02*
X15445Y1478102D01*
G01X22572Y1481102D02*
X18445D01*
G01X17493Y1545928D02*
Y1549028D01*
G01X19103D02*
Y1545928D01*
G01Y1547478D02*
X17493D01*
G01X20555Y1546548D02*
X20785Y1546186D01*
X21091Y1545980D01*
X21436Y1545928D01*
X21743Y1545980D01*
X22050Y1546238D01*
X22241Y1546548D01*
X22280Y1546858D01*
X22203Y1547220D01*
X21935Y1547478D01*
X21666Y1547581D01*
X21321D01*
G01X21666D02*
X21896Y1547736D01*
X22088Y1547995D01*
X22165Y1548305D01*
X22088Y1548615D01*
X21896Y1548873D01*
X21551Y1549028D01*
X21206Y1548976D01*
X20861Y1548770D01*
G01X35179Y9186D02*
X38279D01*
Y8266D01*
X38124Y7959D01*
X37762Y7729D01*
X37349Y7652D01*
X36936Y7729D01*
X36626Y7921D01*
X36471Y8266D01*
Y9186D01*
G01X35076Y6009D02*
X38279Y4629D01*
G01X35179Y3101D02*
X38279D01*
X35179Y1337D01*
X38279D01*
G01X35076Y-881D02*
X35127Y-804D01*
X35231D01*
X35282Y-881D01*
X35231Y-958D01*
X35127D01*
X35076Y-881D01*
G01X36471D02*
X36522Y-804D01*
X36626D01*
X36677Y-881D01*
X36626Y-958D01*
X36522D01*
X36471Y-881D01*
G01X35179Y-3138D02*
X38279D01*
Y-3904D01*
X38124Y-4211D01*
X37917Y-4441D01*
X37607Y-4633D01*
X37246Y-4786D01*
X36729Y-4824D01*
X36212Y-4786D01*
X35851Y-4633D01*
X35541Y-4441D01*
X35334Y-4211D01*
X35179Y-3904D01*
Y-3138D01*
G01Y-6123D02*
X38279Y-7081D01*
X35179Y-8039D01*
G01X36264Y-7694D02*
Y-6468D01*
G01X35179Y-9453D02*
X38279D01*
Y-10909D01*
G01X36781Y-10373D02*
Y-9453D01*
G01X38279Y-13281D02*
X38176Y-12974D01*
X37917Y-12744D01*
X37607Y-12591D01*
X37194Y-12476D01*
X36729Y-12438D01*
X36264Y-12476D01*
X35851Y-12591D01*
X35541Y-12744D01*
X35282Y-12974D01*
X35179Y-13281D01*
X35282Y-13588D01*
X35541Y-13818D01*
X35851Y-13971D01*
X36264Y-14086D01*
X36729Y-14124D01*
X37194Y-14086D01*
X37607Y-13971D01*
X37917Y-13818D01*
X38176Y-13588D01*
X38279Y-13281D01*
G01Y-16381D02*
X35179D01*
G01X38279Y-15499D02*
Y-17263D01*
G01X35179Y-18484D02*
X38279D01*
X35696Y-19481D01*
X38279Y-20478D01*
X35179D01*
G01X36832Y-22888D02*
X36987Y-23041D01*
X37246Y-23156D01*
X37607Y-23233D01*
X37917Y-23156D01*
X38124Y-23003D01*
X38279Y-22734D01*
Y-21699D01*
X35179D01*
Y-22964D01*
X35386Y-23233D01*
X35696Y-23386D01*
X36057Y-23463D01*
X36419Y-23386D01*
X36729Y-23156D01*
X36832Y-22888D01*
Y-21699D01*
G01X35799Y-24838D02*
X35437Y-25068D01*
X35231Y-25374D01*
X35179Y-25719D01*
X35231Y-26026D01*
X35489Y-26333D01*
X35799Y-26524D01*
X36109Y-26563D01*
X36471Y-26486D01*
X36729Y-26218D01*
X36832Y-25949D01*
Y-25604D01*
G01Y-25949D02*
X36987Y-26179D01*
X37246Y-26371D01*
X37556Y-26448D01*
X37866Y-26371D01*
X38124Y-26179D01*
X38279Y-25834D01*
X38227Y-25489D01*
X38021Y-25144D01*
G01X38279Y-28321D02*
Y-29241D01*
G01Y-28781D02*
X35179D01*
G01Y-28321D02*
Y-29241D01*
G01X38021Y-32724D02*
X38176Y-32494D01*
X38279Y-32226D01*
Y-31919D01*
X38124Y-31574D01*
X37866Y-31306D01*
X37556Y-31114D01*
X37039Y-30961D01*
X36574Y-30923D01*
X36109Y-30999D01*
X35799Y-31114D01*
X35489Y-31344D01*
X35282Y-31613D01*
X35179Y-31881D01*
Y-32149D01*
X35282Y-32418D01*
X35437Y-32648D01*
X35644Y-32839D01*
G01X38279Y-34981D02*
X38176Y-34674D01*
X37917Y-34444D01*
X37607Y-34291D01*
X37194Y-34176D01*
X36729Y-34138D01*
X36264Y-34176D01*
X35851Y-34291D01*
X35541Y-34444D01*
X35282Y-34674D01*
X35179Y-34981D01*
X35282Y-35288D01*
X35541Y-35518D01*
X35851Y-35671D01*
X36264Y-35786D01*
X36729Y-35824D01*
X37194Y-35786D01*
X37607Y-35671D01*
X37917Y-35518D01*
X38176Y-35288D01*
X38279Y-34981D01*
G01X53450Y154200D02*
G02I-9450J0D01*
G01X37795Y193937D02*
X24409D01*
G01D02*
Y195174D01*
G01Y209274D02*
Y210174D01*
G01Y204274D02*
Y205174D01*
G01Y199274D02*
Y200174D01*
G01X24785Y217711D02*
X24977Y217401D01*
X25207Y217194D01*
X25475Y217091D01*
X25782Y217194D01*
X26012Y217401D01*
X26242Y217711D01*
X26319Y218124D01*
Y220191D01*
G01X28575Y217091D02*
X28652Y217763D01*
X28767Y218331D01*
X28920Y218848D01*
X29112Y219416D01*
X29419Y220191D01*
X27885D01*
G01X24409Y215511D02*
X37795D01*
G01X24409Y214274D02*
Y215511D01*
G01X35265Y284516D02*
X41465D01*
G01Y281316D02*
X35265D01*
G01D02*
Y284516D01*
G01Y279398D02*
X41465D01*
G01Y276198D02*
X35265D01*
G01D02*
Y279398D01*
G01X31580Y296682D02*
Y302882D01*
G01X34780D02*
Y296682D01*
G01D02*
X31580D01*
G01X33400Y286900D02*
Y290100D01*
G01X39600Y286900D02*
X33400D01*
G01Y290100D02*
X39600D01*
G01X25832Y288070D02*
Y300274D01*
G01X31580Y302882D02*
X34780D01*
G01X35265Y314516D02*
X41465D01*
G01Y311316D02*
X35265D01*
G01D02*
Y314516D01*
G01Y309398D02*
X41465D01*
G01Y306198D02*
X35265D01*
G01D02*
Y309398D01*
G01X25832Y300274D02*
X24082D01*
G01X34995Y383452D02*
Y389652D01*
G01X38195Y383452D02*
X34995D01*
G01X33482Y385207D02*
Y397643D01*
G01X22614Y385207D02*
X33482D01*
G01X22614Y397643D02*
Y385207D01*
G01X34924Y396871D02*
X38124D01*
G01Y390671D02*
X34924D01*
G01D02*
Y396871D01*
G01X34995Y389652D02*
X38195D01*
G01X31385Y402600D02*
X37585D01*
G01X31385Y399400D02*
Y402600D01*
G01X37585Y399400D02*
X31385D01*
G01X33482Y397643D02*
X22614D01*
G01X23432Y518551D02*
Y515351D01*
G01X35912Y515425D02*
X29712D01*
G01D02*
Y518625D01*
G01X35912D02*
Y515425D01*
G01X29712Y518625D02*
X35912D01*
G01X34447Y532940D02*
X31247D01*
G01X34447Y539140D02*
Y532940D01*
G01X31247D02*
Y539140D01*
G01X34374Y530470D02*
Y524270D01*
G01D02*
X31174D01*
G01D02*
Y530470D01*
G01D02*
X34374D01*
G01X37972Y529695D02*
X34772D01*
G01D02*
Y535895D01*
G01D02*
X37972D01*
G01X31247Y539140D02*
X34447D01*
G01X22603Y652979D02*
Y656079D01*
G01X24213D02*
Y652979D01*
G01Y654529D02*
X22603D01*
G01X26508Y652979D02*
X26776Y653031D01*
X27083Y653186D01*
X27275Y653444D01*
X27351Y653806D01*
X27275Y654167D01*
X27045Y654477D01*
X26700Y654632D01*
X26316D01*
X26086Y654736D01*
X25895Y654994D01*
X25818Y655356D01*
X25933Y655717D01*
X26201Y655976D01*
X26508Y656079D01*
X26815Y655976D01*
X27083Y655717D01*
X27198Y655356D01*
X27121Y654994D01*
X26930Y654736D01*
X26700Y654632D01*
X26316D01*
X25971Y654477D01*
X25741Y654167D01*
X25665Y653806D01*
X25741Y653444D01*
X25933Y653186D01*
X26240Y653031D01*
X26508Y652979D01*
G01X29608D02*
X29876Y653031D01*
X30183Y653186D01*
X30375Y653444D01*
X30451Y653806D01*
X30375Y654167D01*
X30145Y654477D01*
X29800Y654632D01*
X29416D01*
X29186Y654736D01*
X28995Y654994D01*
X28918Y655356D01*
X29033Y655717D01*
X29301Y655976D01*
X29608Y656079D01*
X29915Y655976D01*
X30183Y655717D01*
X30298Y655356D01*
X30221Y654994D01*
X30030Y654736D01*
X29800Y654632D01*
X29416D01*
X29071Y654477D01*
X28841Y654167D01*
X28765Y653806D01*
X28841Y653444D01*
X29033Y653186D01*
X29340Y653031D01*
X29608Y652979D01*
G01X23116Y1391097D02*
Y1394197D01*
G01X24726D02*
Y1391097D01*
G01Y1392647D02*
X23116D01*
G01X27021Y1391097D02*
Y1394197D01*
X26561Y1393577D01*
G01Y1391097D02*
X27481D01*
G01X30121Y1394197D02*
X29814Y1394094D01*
X29584Y1393835D01*
X29431Y1393525D01*
X29316Y1393112D01*
X29278Y1392647D01*
X29316Y1392182D01*
X29431Y1391769D01*
X29584Y1391459D01*
X29814Y1391200D01*
X30121Y1391097D01*
X30428Y1391200D01*
X30658Y1391459D01*
X30811Y1391769D01*
X30926Y1392182D01*
X30964Y1392647D01*
X30926Y1393112D01*
X30811Y1393525D01*
X30658Y1393835D01*
X30428Y1394094D01*
X30121Y1394197D01*
G01X32493Y1393680D02*
X32723Y1393990D01*
X32991Y1394145D01*
X33298Y1394197D01*
X33681Y1394094D01*
X33949Y1393835D01*
X34026Y1393525D01*
X33988Y1393215D01*
X33834Y1392957D01*
X33068Y1392440D01*
X32723Y1392079D01*
X32493Y1391562D01*
X32416Y1391097D01*
X34026D01*
G01X41268Y1424257D02*
G02I-9450J0D01*
G01X29972Y1459448D02*
X37099D01*
G01X34099Y1481102D02*
X29972D01*
G01X37099Y1478102D02*
X34099Y1481102D01*
G01X29996Y1496314D02*
Y1499514D01*
G01X36196Y1496314D02*
X29996D01*
G01X36196Y1499514D02*
Y1496314D01*
G01X29996Y1499514D02*
X36196D01*
G01X29996Y1500614D02*
Y1503814D01*
G01X36196Y1500614D02*
X29996D01*
G01X36196Y1503814D02*
Y1500614D01*
G01X29996Y1503814D02*
X36196D01*
G01X36883Y1574000D02*
Y1577100D01*
X37803D01*
X38110Y1576945D01*
X38340Y1576583D01*
X38417Y1576170D01*
X38340Y1575757D01*
X38148Y1575447D01*
X37803Y1575292D01*
X36883D01*
G01X41593Y1576842D02*
X41363Y1576997D01*
X41095Y1577100D01*
X40788D01*
X40443Y1576945D01*
X40175Y1576687D01*
X39983Y1576377D01*
X39830Y1575860D01*
X39792Y1575395D01*
X39868Y1574930D01*
X39983Y1574620D01*
X40213Y1574310D01*
X40482Y1574103D01*
X40750Y1574000D01*
X41018D01*
X41287Y1574103D01*
X41517Y1574258D01*
X41708Y1574465D01*
G01X43122Y1575292D02*
X43390Y1575653D01*
X43620Y1575860D01*
X43927Y1575963D01*
X44195Y1575860D01*
X44387Y1575653D01*
X44540Y1575343D01*
X44578Y1574982D01*
X44540Y1574672D01*
X44387Y1574362D01*
X44157Y1574103D01*
X43888Y1574000D01*
X43582Y1574103D01*
X43313Y1574413D01*
X43160Y1574878D01*
X43122Y1575395D01*
X43198Y1576067D01*
X43313Y1576428D01*
X43505Y1576790D01*
X43773Y1577048D01*
X44042Y1577100D01*
X44310Y1576997D01*
X44502Y1576738D01*
G01X46222Y1575292D02*
X46490Y1575653D01*
X46720Y1575860D01*
X47027Y1575963D01*
X47295Y1575860D01*
X47487Y1575653D01*
X47640Y1575343D01*
X47678Y1574982D01*
X47640Y1574672D01*
X47487Y1574362D01*
X47257Y1574103D01*
X46988Y1574000D01*
X46682Y1574103D01*
X46413Y1574413D01*
X46260Y1574878D01*
X46222Y1575395D01*
X46298Y1576067D01*
X46413Y1576428D01*
X46605Y1576790D01*
X46873Y1577048D01*
X47142Y1577100D01*
X47410Y1576997D01*
X47602Y1576738D01*
G01X50050Y1574000D02*
Y1577100D01*
X49590Y1576480D01*
G01Y1574000D02*
X50510D01*
G01X52498Y1574362D02*
X52767Y1574103D01*
X53073Y1574000D01*
X53380Y1574103D01*
X53648Y1574413D01*
X53840Y1574878D01*
X53917Y1575343D01*
Y1575912D01*
X53840Y1576377D01*
X53648Y1576790D01*
X53418Y1576997D01*
X53150Y1577100D01*
X52843Y1576997D01*
X52613Y1576790D01*
X52460Y1576480D01*
X52383Y1576067D01*
X52460Y1575705D01*
X52652Y1575343D01*
X52882Y1575137D01*
X53150Y1575085D01*
X53457Y1575188D01*
X53687Y1575447D01*
X53917Y1575912D01*
G01X36533Y1595996D02*
X42733D01*
G01X36533Y1592796D02*
Y1595996D01*
G01X42733Y1592796D02*
X36533D01*
G01Y1609496D02*
X42733D01*
G01X36533Y1606296D02*
Y1609496D01*
G01X42733Y1606296D02*
X36533D01*
G01Y1600496D02*
X42733D01*
G01X36533Y1597296D02*
Y1600496D01*
G01X42733Y1597296D02*
X36533D01*
G01Y1604996D02*
X42733D01*
G01X36533Y1601796D02*
Y1604996D01*
G01X42733Y1601796D02*
X36533D01*
G01Y1611296D02*
Y1614496D01*
G01X42733Y1611296D02*
X36533D01*
G01X33457Y1603728D02*
X30357D01*
Y1604648D01*
X30512Y1604955D01*
X30874Y1605185D01*
X31287Y1605262D01*
X31700Y1605185D01*
X32010Y1604993D01*
X32165Y1604648D01*
Y1603728D01*
G01X30357Y1606752D02*
X32579D01*
X33044Y1606905D01*
X33354Y1607212D01*
X33457Y1607595D01*
X33354Y1607978D01*
X33044Y1608285D01*
X32579Y1608438D01*
X30357D01*
G01X32165Y1609967D02*
X31804Y1610235D01*
X31597Y1610465D01*
X31494Y1610772D01*
X31597Y1611040D01*
X31804Y1611232D01*
X32114Y1611385D01*
X32475Y1611423D01*
X32785Y1611385D01*
X33095Y1611232D01*
X33354Y1611002D01*
X33457Y1610733D01*
X33354Y1610427D01*
X33044Y1610158D01*
X32579Y1610005D01*
X32062Y1609967D01*
X31390Y1610043D01*
X31029Y1610158D01*
X30667Y1610350D01*
X30409Y1610618D01*
X30357Y1610887D01*
X30460Y1611155D01*
X30719Y1611347D01*
G01X32992Y1612952D02*
X33250Y1613182D01*
X33405Y1613450D01*
X33457Y1613795D01*
X33354Y1614140D01*
X33147Y1614408D01*
X32785Y1614600D01*
X32372Y1614638D01*
X31959Y1614562D01*
X31700Y1614370D01*
X31494Y1614102D01*
X31442Y1613833D01*
X31494Y1613565D01*
X31700Y1613220D01*
X30357Y1613335D01*
Y1614370D01*
G01X33457Y1616895D02*
X30357D01*
X30977Y1616435D01*
G01X33457D02*
Y1617355D01*
G01X30357Y1619995D02*
X30460Y1619688D01*
X30719Y1619458D01*
X31029Y1619305D01*
X31442Y1619190D01*
X31907Y1619152D01*
X32372Y1619190D01*
X32785Y1619305D01*
X33095Y1619458D01*
X33354Y1619688D01*
X33457Y1619995D01*
X33354Y1620302D01*
X33095Y1620532D01*
X32785Y1620685D01*
X32372Y1620800D01*
X31907Y1620838D01*
X31442Y1620800D01*
X31029Y1620685D01*
X30719Y1620532D01*
X30460Y1620302D01*
X30357Y1619995D01*
G01X36533Y1614496D02*
X42733D01*
G01X36533Y1618996D02*
X42733D01*
G01X36533Y1615796D02*
Y1618996D01*
G01X42733Y1615796D02*
X36533D01*
G01Y1621296D02*
Y1624496D01*
G01X42733Y1621296D02*
X36533D01*
G01Y1624496D02*
X42733D01*
G01X36533Y1625296D02*
Y1628496D01*
G01X42733Y1625296D02*
X36533D01*
G01Y1628496D02*
X42733D01*
G01X33827Y1666987D02*
Y1670187D01*
G01X40027Y1666987D02*
X33827D01*
G01Y1670187D02*
X40027D01*
G01X33827Y1661987D02*
Y1665187D01*
G01X40027Y1661987D02*
X33827D01*
G01Y1665187D02*
X40027D01*
G01X51346Y47500D02*
Y-2520D01*
G01D02*
X321898D01*
G01X48704Y57220D02*
Y63420D01*
G01X51904Y57220D02*
X48704D01*
G01Y63420D02*
X51904D01*
G01X39755Y172167D02*
Y175267D01*
G01X41365D02*
Y172167D01*
G01Y173717D02*
X39755D01*
G01X42932Y174750D02*
X43162Y175060D01*
X43430Y175215D01*
X43737Y175267D01*
X44120Y175164D01*
X44388Y174905D01*
X44465Y174595D01*
X44427Y174285D01*
X44273Y174027D01*
X43507Y173510D01*
X43162Y173149D01*
X42932Y172632D01*
X42855Y172167D01*
X44465D01*
G01X46760D02*
X47028Y172219D01*
X47335Y172374D01*
X47527Y172632D01*
X47603Y172994D01*
X47527Y173355D01*
X47297Y173665D01*
X46952Y173820D01*
X46568D01*
X46338Y173924D01*
X46147Y174182D01*
X46070Y174544D01*
X46185Y174905D01*
X46453Y175164D01*
X46760Y175267D01*
X47067Y175164D01*
X47335Y174905D01*
X47450Y174544D01*
X47373Y174182D01*
X47182Y173924D01*
X46952Y173820D01*
X46568D01*
X46223Y173665D01*
X45993Y173355D01*
X45917Y172994D01*
X45993Y172632D01*
X46185Y172374D01*
X46492Y172219D01*
X46760Y172167D01*
G01X37795Y195174D02*
Y193937D01*
G01Y210174D02*
Y209274D01*
G01Y205174D02*
Y204274D01*
G01Y200174D02*
Y199274D01*
G01Y215511D02*
Y214274D01*
G01X41465Y284516D02*
Y281316D01*
G01Y279398D02*
Y276198D01*
G01X46597Y274294D02*
Y272072D01*
X46750Y271607D01*
X47057Y271297D01*
X47440Y271194D01*
X47823Y271297D01*
X48130Y271607D01*
X48283Y272072D01*
Y274294D01*
G01X49697Y271659D02*
X49927Y271401D01*
X50195Y271246D01*
X50540Y271194D01*
X50885Y271297D01*
X51153Y271504D01*
X51345Y271866D01*
X51383Y272279D01*
X51307Y272692D01*
X51115Y272951D01*
X50847Y273157D01*
X50578Y273209D01*
X50310Y273157D01*
X49965Y272951D01*
X50080Y274294D01*
X51115D01*
G01X52988Y271556D02*
X53257Y271297D01*
X53563Y271194D01*
X53870Y271297D01*
X54138Y271607D01*
X54330Y272072D01*
X54407Y272537D01*
Y273106D01*
X54330Y273571D01*
X54138Y273984D01*
X53908Y274191D01*
X53640Y274294D01*
X53333Y274191D01*
X53103Y273984D01*
X52950Y273674D01*
X52873Y273261D01*
X52950Y272899D01*
X53142Y272537D01*
X53372Y272331D01*
X53640Y272279D01*
X53947Y272382D01*
X54177Y272641D01*
X54407Y273106D01*
G01X51040Y282357D02*
X48709Y284688D01*
G01D02*
X45600D01*
G01D02*
Y276026D01*
G01D02*
X56480D01*
G01X53371Y284688D02*
X51040Y282357D01*
G01X39600Y290100D02*
Y286900D01*
G01X51680Y296672D02*
X48678Y300274D01*
G01X46928D02*
Y288070D01*
G01D02*
X56432D01*
G01X54682Y300274D02*
X51680Y296672D01*
G01X49400Y301900D02*
Y305100D01*
G01X55600Y301900D02*
X49400D01*
G01Y305100D02*
X55600D01*
G01X41465Y314516D02*
Y311316D01*
G01Y309398D02*
Y306198D01*
G01X42400Y301900D02*
Y305100D01*
G01X48600Y301900D02*
X42400D01*
G01X48600Y305100D02*
Y301900D01*
G01X42400Y305100D02*
X48600D01*
G01X48678Y300274D02*
X46928D01*
G01X51000Y313100D02*
X48669Y315431D01*
G01X45560D02*
Y306769D01*
G01D02*
X56440D01*
G01X53331Y315431D02*
X51000Y313100D01*
G01X45507Y319767D02*
Y317545D01*
X45660Y317080D01*
X45967Y316770D01*
X46350Y316667D01*
X46733Y316770D01*
X47040Y317080D01*
X47193Y317545D01*
Y319767D01*
G01X48607Y317132D02*
X48837Y316874D01*
X49105Y316719D01*
X49450Y316667D01*
X49795Y316770D01*
X50063Y316977D01*
X50255Y317339D01*
X50293Y317752D01*
X50217Y318165D01*
X50025Y318424D01*
X49757Y318630D01*
X49488Y318682D01*
X49220Y318630D01*
X48875Y318424D01*
X48990Y319767D01*
X50025D01*
G01X52550Y316667D02*
X52818Y316719D01*
X53125Y316874D01*
X53317Y317132D01*
X53393Y317494D01*
X53317Y317855D01*
X53087Y318165D01*
X52742Y318320D01*
X52358D01*
X52128Y318424D01*
X51937Y318682D01*
X51860Y319044D01*
X51975Y319405D01*
X52243Y319664D01*
X52550Y319767D01*
X52857Y319664D01*
X53125Y319405D01*
X53240Y319044D01*
X53163Y318682D01*
X52972Y318424D01*
X52742Y318320D01*
X52358D01*
X52013Y318165D01*
X51783Y317855D01*
X51707Y317494D01*
X51783Y317132D01*
X51975Y316874D01*
X52282Y316719D01*
X52550Y316667D01*
G01X48669Y315431D02*
X45560D01*
G01X48434Y368012D02*
Y361812D01*
G01X45234Y368012D02*
X48434D01*
G01X45234Y361812D02*
Y368012D01*
G01X48434Y361812D02*
X45234D01*
G01X37408Y368012D02*
X40608D01*
G01Y361812D02*
X37408D01*
G01X40608Y368012D02*
Y361812D01*
G01X37408D02*
Y368012D01*
G01X49514D02*
X52714D01*
G01Y361812D02*
X49514D01*
G01D02*
Y368012D01*
G01X41209D02*
X44409D01*
G01Y361812D02*
X41209D01*
G01X44409Y368012D02*
Y361812D01*
G01X41209D02*
Y368012D01*
G01X38310Y373042D02*
Y375542D01*
X37990Y375042D01*
G01Y373042D02*
X38630D01*
G01X39923Y373417D02*
X40083Y373209D01*
X40270Y373084D01*
X40510Y373042D01*
X40750Y373125D01*
X40937Y373292D01*
X41070Y373584D01*
X41097Y373917D01*
X41043Y374250D01*
X40910Y374459D01*
X40723Y374625D01*
X40537Y374667D01*
X40350Y374625D01*
X40110Y374459D01*
X40190Y375542D01*
X40910D01*
G01X38195Y389652D02*
Y383452D01*
G01X41240Y384032D02*
Y386532D01*
X40920Y386032D01*
G01Y384032D02*
X41560D01*
G01X43760D02*
Y386532D01*
X42773Y384740D01*
X44107D01*
G01X45531Y380458D02*
Y383301D01*
G01X48374Y380458D02*
X45531D01*
G01X49374Y378801D02*
Y377301D01*
G01X38124Y396871D02*
Y390671D01*
G01X37585Y402600D02*
Y399400D01*
G01X43590Y397302D02*
X43777Y397344D01*
X43990Y397469D01*
X44123Y397677D01*
X44177Y397969D01*
X44123Y398260D01*
X43963Y398510D01*
X43723Y398635D01*
X43457D01*
X43297Y398719D01*
X43163Y398927D01*
X43110Y399219D01*
X43190Y399510D01*
X43377Y399719D01*
X43590Y399802D01*
X43803Y399719D01*
X43990Y399510D01*
X44070Y399219D01*
X44017Y398927D01*
X43883Y398719D01*
X43723Y398635D01*
X43457D01*
X43217Y398510D01*
X43057Y398260D01*
X43003Y397969D01*
X43057Y397677D01*
X43190Y397469D01*
X43403Y397344D01*
X43590Y397302D01*
G01X48221Y401568D02*
X48274Y402110D01*
X48354Y402568D01*
X48461Y402985D01*
X48594Y403443D01*
X48807Y404068D01*
X47741D01*
G01X45531Y400144D02*
X48374D01*
G01X45531Y397301D02*
Y400144D01*
G01X43874Y392301D02*
X40874D01*
G01X46567Y421535D02*
Y415335D01*
X43367D01*
Y421535D01*
X46567D01*
G01X43367Y412185D02*
Y418385D01*
X46567D01*
Y412185D01*
X43367D01*
G01X48739Y412270D02*
Y418470D01*
X51939D01*
Y412270D01*
X48739D01*
G01X51939Y421620D02*
Y415420D01*
X48739D01*
Y421620D01*
X51939D01*
G01X51302Y502985D02*
Y509185D01*
G01X54502Y502985D02*
X51302D01*
G01X46902Y503172D02*
Y509372D01*
G01X50102D02*
Y503172D01*
G01D02*
X46902D01*
G01X51302Y509185D02*
X54502D01*
G01X46902Y509372D02*
X50102D01*
G01X45262Y519642D02*
X47362D01*
G01X45262Y521742D02*
Y519642D01*
G01X37972Y535895D02*
Y529695D01*
G01X42840Y541280D02*
Y539058D01*
X42993Y538593D01*
X43300Y538283D01*
X43683Y538180D01*
X44066Y538283D01*
X44373Y538593D01*
X44526Y539058D01*
Y541280D01*
G01X46055Y540763D02*
X46285Y541073D01*
X46553Y541228D01*
X46860Y541280D01*
X47243Y541177D01*
X47511Y540918D01*
X47588Y540608D01*
X47550Y540298D01*
X47396Y540040D01*
X46630Y539523D01*
X46285Y539162D01*
X46055Y538645D01*
X45978Y538180D01*
X47588D01*
G01X50343D02*
Y541280D01*
X48925Y539058D01*
X50841D01*
G01X52906Y538180D02*
X52983Y538852D01*
X53098Y539420D01*
X53251Y539937D01*
X53443Y540505D01*
X53750Y541280D01*
X52216D01*
G01X47362Y535784D02*
X45262D01*
G01D02*
Y533684D01*
G01X50226Y545160D02*
X47026D01*
G01X50226Y551360D02*
Y545160D01*
G01X47026Y551360D02*
X50226D01*
G01X47026Y545160D02*
Y551360D01*
G01X54899Y545195D02*
X51699D01*
G01Y551395D02*
X54899D01*
G01X51699Y545195D02*
Y551395D01*
G01X43873Y749325D02*
Y781125D01*
G01X57673Y749325D02*
X43873D01*
G01X47860Y782458D02*
X44760D01*
Y783417D01*
X44915Y783723D01*
X45122Y783915D01*
X45535Y783992D01*
X45948Y783915D01*
X46207Y783685D01*
X46362Y783417D01*
Y782458D01*
G01Y783417D02*
X47860Y783992D01*
G01Y786325D02*
X44760D01*
X45380Y785865D01*
G01X47860D02*
Y786785D01*
G01Y789425D02*
X47808Y789693D01*
X47653Y790000D01*
X47395Y790192D01*
X47033Y790268D01*
X46672Y790192D01*
X46362Y789962D01*
X46207Y789617D01*
Y789233D01*
X46103Y789003D01*
X45845Y788812D01*
X45483Y788735D01*
X45122Y788850D01*
X44863Y789118D01*
X44760Y789425D01*
X44863Y789732D01*
X45122Y790000D01*
X45483Y790115D01*
X45845Y790038D01*
X46103Y789847D01*
X46207Y789617D01*
Y789233D01*
X46362Y788888D01*
X46672Y788658D01*
X47033Y788582D01*
X47395Y788658D01*
X47653Y788850D01*
X47808Y789157D01*
X47860Y789425D01*
G01X47240Y791682D02*
X47602Y791912D01*
X47808Y792218D01*
X47860Y792563D01*
X47808Y792870D01*
X47550Y793177D01*
X47240Y793368D01*
X46930Y793407D01*
X46568Y793330D01*
X46310Y793062D01*
X46207Y792793D01*
Y792448D01*
G01Y792793D02*
X46052Y793023D01*
X45793Y793215D01*
X45483Y793292D01*
X45173Y793215D01*
X44915Y793023D01*
X44760Y792678D01*
X44812Y792333D01*
X45018Y791988D01*
G01X47860Y795548D02*
X47188Y795625D01*
X46620Y795740D01*
X46103Y795893D01*
X45535Y796085D01*
X44760Y796392D01*
Y794858D01*
G01X43873Y781125D02*
X57673D01*
G01X52790Y1317264D02*
Y1314164D01*
G01X51908Y1317264D02*
X53672D01*
G01X55123Y1314164D02*
Y1317264D01*
X56043D01*
X56350Y1317109D01*
X56580Y1316747D01*
X56657Y1316334D01*
X56580Y1315921D01*
X56388Y1315611D01*
X56043Y1315456D01*
X55123D01*
G01X58990Y1314164D02*
Y1317264D01*
X58530Y1316644D01*
G01Y1314164D02*
X59450D01*
G01X61362Y1316747D02*
X61592Y1317057D01*
X61860Y1317212D01*
X62167Y1317264D01*
X62550Y1317161D01*
X62818Y1316902D01*
X62895Y1316592D01*
X62857Y1316282D01*
X62703Y1316024D01*
X61937Y1315507D01*
X61592Y1315146D01*
X61362Y1314629D01*
X61285Y1314164D01*
X62895D01*
G01X52790Y1312844D02*
Y1309744D01*
G01X51908Y1312844D02*
X53672D01*
G01X55123Y1309744D02*
Y1312844D01*
X56043D01*
X56350Y1312689D01*
X56580Y1312327D01*
X56657Y1311914D01*
X56580Y1311501D01*
X56388Y1311191D01*
X56043Y1311036D01*
X55123D01*
G01X58990Y1309744D02*
Y1312844D01*
X58530Y1312224D01*
G01Y1309744D02*
X59450D01*
G01X61247Y1310209D02*
X61477Y1309951D01*
X61745Y1309796D01*
X62090Y1309744D01*
X62435Y1309847D01*
X62703Y1310054D01*
X62895Y1310416D01*
X62933Y1310829D01*
X62857Y1311242D01*
X62665Y1311501D01*
X62397Y1311707D01*
X62128Y1311759D01*
X61860Y1311707D01*
X61515Y1311501D01*
X61630Y1312844D01*
X62665D01*
G01X41263Y1415224D02*
Y1418324D01*
G01X42873D02*
Y1415224D01*
G01Y1416774D02*
X41263D01*
G01X44325Y1415844D02*
X44555Y1415482D01*
X44861Y1415276D01*
X45206Y1415224D01*
X45513Y1415276D01*
X45820Y1415534D01*
X46011Y1415844D01*
X46050Y1416154D01*
X45973Y1416516D01*
X45705Y1416774D01*
X45436Y1416877D01*
X45091D01*
G01X45436D02*
X45666Y1417032D01*
X45858Y1417291D01*
X45935Y1417601D01*
X45858Y1417911D01*
X45666Y1418169D01*
X45321Y1418324D01*
X44976Y1418272D01*
X44631Y1418066D01*
G01X48268Y1418324D02*
X47961Y1418221D01*
X47731Y1417962D01*
X47578Y1417652D01*
X47463Y1417239D01*
X47425Y1416774D01*
X47463Y1416309D01*
X47578Y1415896D01*
X47731Y1415586D01*
X47961Y1415327D01*
X48268Y1415224D01*
X48575Y1415327D01*
X48805Y1415586D01*
X48958Y1415896D01*
X49073Y1416309D01*
X49111Y1416774D01*
X49073Y1417239D01*
X48958Y1417652D01*
X48805Y1417962D01*
X48575Y1418221D01*
X48268Y1418324D01*
G01X41383Y1451500D02*
Y1454600D01*
X42303D01*
X42610Y1454445D01*
X42840Y1454083D01*
X42917Y1453670D01*
X42840Y1453257D01*
X42648Y1452947D01*
X42303Y1452792D01*
X41383D01*
G01X46093Y1454342D02*
X45863Y1454497D01*
X45595Y1454600D01*
X45288D01*
X44943Y1454445D01*
X44675Y1454187D01*
X44483Y1453877D01*
X44330Y1453360D01*
X44292Y1452895D01*
X44368Y1452430D01*
X44483Y1452120D01*
X44713Y1451810D01*
X44982Y1451603D01*
X45250Y1451500D01*
X45518D01*
X45787Y1451603D01*
X46017Y1451758D01*
X46208Y1451965D01*
G01X47622Y1452792D02*
X47890Y1453153D01*
X48120Y1453360D01*
X48427Y1453463D01*
X48695Y1453360D01*
X48887Y1453153D01*
X49040Y1452843D01*
X49078Y1452482D01*
X49040Y1452172D01*
X48887Y1451862D01*
X48657Y1451603D01*
X48388Y1451500D01*
X48082Y1451603D01*
X47813Y1451913D01*
X47660Y1452378D01*
X47622Y1452895D01*
X47698Y1453567D01*
X47813Y1453928D01*
X48005Y1454290D01*
X48273Y1454548D01*
X48542Y1454600D01*
X48810Y1454497D01*
X49002Y1454238D01*
G01X50722Y1452792D02*
X50990Y1453153D01*
X51220Y1453360D01*
X51527Y1453463D01*
X51795Y1453360D01*
X51987Y1453153D01*
X52140Y1452843D01*
X52178Y1452482D01*
X52140Y1452172D01*
X51987Y1451862D01*
X51757Y1451603D01*
X51488Y1451500D01*
X51182Y1451603D01*
X50913Y1451913D01*
X50760Y1452378D01*
X50722Y1452895D01*
X50798Y1453567D01*
X50913Y1453928D01*
X51105Y1454290D01*
X51373Y1454548D01*
X51642Y1454600D01*
X51910Y1454497D01*
X52102Y1454238D01*
G01X53822Y1454083D02*
X54052Y1454393D01*
X54320Y1454548D01*
X54627Y1454600D01*
X55010Y1454497D01*
X55278Y1454238D01*
X55355Y1453928D01*
X55317Y1453618D01*
X55163Y1453360D01*
X54397Y1452843D01*
X54052Y1452482D01*
X53822Y1451965D01*
X53745Y1451500D01*
X55355D01*
G01X56998Y1451862D02*
X57267Y1451603D01*
X57573Y1451500D01*
X57880Y1451603D01*
X58148Y1451913D01*
X58340Y1452378D01*
X58417Y1452843D01*
Y1453412D01*
X58340Y1453877D01*
X58148Y1454290D01*
X57918Y1454497D01*
X57650Y1454600D01*
X57343Y1454497D01*
X57113Y1454290D01*
X56960Y1453980D01*
X56883Y1453567D01*
X56960Y1453205D01*
X57152Y1452843D01*
X57382Y1452637D01*
X57650Y1452585D01*
X57957Y1452688D01*
X58187Y1452947D01*
X58417Y1453412D01*
G01X39445Y1459448D02*
X46572D01*
G01X39445Y1478102D02*
Y1459448D01*
G01X37099D02*
Y1478102D01*
G01X42445Y1481102D02*
X39445Y1478102D01*
G01X46572Y1481102D02*
X42445D01*
G01X53640Y1497697D02*
X50440D01*
G01Y1503897D02*
X53640D01*
G01X50440Y1497697D02*
Y1503897D01*
G01X47062Y1520935D02*
X53262D01*
G01X47062Y1517735D02*
Y1520935D01*
G01X53262Y1517735D02*
X47062D01*
G01X50262Y1521735D02*
X47062D01*
G01X50262Y1527935D02*
Y1521735D01*
G01X47062D02*
Y1527935D01*
G01X49031Y1534771D02*
X52231D01*
G01X49031Y1528571D02*
Y1534771D01*
G01X52231Y1528571D02*
X49031D01*
G01X52231Y1535571D02*
X49031D01*
G01D02*
Y1541771D01*
G01X47062Y1527935D02*
X50262D01*
G01X49031Y1541771D02*
X49900D01*
G01X53596Y1549842D02*
X50396D01*
G01D02*
Y1556042D01*
G01X40550Y1548980D02*
Y1555180D01*
G01X43750Y1548980D02*
X40550D01*
G01X43750Y1555180D02*
Y1548980D01*
G01X44550D02*
Y1555180D01*
G01X47750Y1548980D02*
X44550D01*
G01X47750Y1555180D02*
Y1548980D01*
G01X49096Y1548969D02*
X52296D01*
G01X49096Y1542769D02*
Y1548969D01*
G01X49900Y1542769D02*
X49096D01*
G01X50396Y1556042D02*
X53596D01*
G01X40550Y1555180D02*
X43750D01*
G01X44550D02*
X47750D01*
G01X42508Y1561750D02*
Y1564850D01*
X43428D01*
X43735Y1564695D01*
X43965Y1564333D01*
X44042Y1563920D01*
X43965Y1563507D01*
X43773Y1563197D01*
X43428Y1563042D01*
X42508D01*
G01X45532Y1564850D02*
Y1562628D01*
X45685Y1562163D01*
X45992Y1561853D01*
X46375Y1561750D01*
X46758Y1561853D01*
X47065Y1562163D01*
X47218Y1562628D01*
Y1564850D01*
G01X48747Y1563042D02*
X49015Y1563403D01*
X49245Y1563610D01*
X49552Y1563713D01*
X49820Y1563610D01*
X50012Y1563403D01*
X50165Y1563093D01*
X50203Y1562732D01*
X50165Y1562422D01*
X50012Y1562112D01*
X49782Y1561853D01*
X49513Y1561750D01*
X49207Y1561853D01*
X48938Y1562163D01*
X48785Y1562628D01*
X48747Y1563145D01*
X48823Y1563817D01*
X48938Y1564178D01*
X49130Y1564540D01*
X49398Y1564798D01*
X49667Y1564850D01*
X49935Y1564747D01*
X50127Y1564488D01*
G01X51732Y1562215D02*
X51962Y1561957D01*
X52230Y1561802D01*
X52575Y1561750D01*
X52920Y1561853D01*
X53188Y1562060D01*
X53380Y1562422D01*
X53418Y1562835D01*
X53342Y1563248D01*
X53150Y1563507D01*
X52882Y1563713D01*
X52613Y1563765D01*
X52345Y1563713D01*
X52000Y1563507D01*
X52115Y1564850D01*
X53150D01*
G01X55675Y1561750D02*
Y1564850D01*
X55215Y1564230D01*
G01Y1561750D02*
X56135D01*
G01X58775D02*
Y1564850D01*
X58315Y1564230D01*
G01Y1561750D02*
X59235D01*
G01X44033Y1593796D02*
Y1599996D01*
G01X47233Y1593796D02*
X44033D01*
G01X47233Y1599996D02*
Y1593796D01*
G01X48533D02*
Y1599996D01*
G01X51733Y1593796D02*
X48533D01*
G01X51733Y1599996D02*
Y1593796D01*
G01X42733Y1595996D02*
Y1592796D01*
G01Y1609496D02*
Y1606296D01*
G01Y1600496D02*
Y1597296D01*
G01Y1604996D02*
Y1601796D01*
G01Y1614496D02*
Y1611296D01*
G01X44033Y1599996D02*
X47233D01*
G01X48533D02*
X51733D01*
G01X45889Y1609811D02*
X43389D01*
X45181Y1608824D01*
Y1610158D01*
G01X43389Y1611691D02*
X43472Y1611478D01*
X43681Y1611318D01*
X43931Y1611211D01*
X44264Y1611131D01*
X44639Y1611104D01*
X45014Y1611131D01*
X45347Y1611211D01*
X45597Y1611318D01*
X45806Y1611478D01*
X45889Y1611691D01*
X45806Y1611904D01*
X45597Y1612064D01*
X45347Y1612171D01*
X45014Y1612251D01*
X44639Y1612278D01*
X44264Y1612251D01*
X43931Y1612171D01*
X43681Y1612064D01*
X43472Y1611904D01*
X43389Y1611691D01*
G01X51830Y1605562D02*
X49924D01*
G01X48467Y1608305D02*
X45467D01*
G01X49924Y1605562D02*
Y1607468D01*
G01X42733Y1618996D02*
Y1615796D01*
G01Y1624496D02*
Y1621296D01*
G01Y1628496D02*
Y1625296D01*
G01X45698Y1620713D02*
X45990Y1620873D01*
X46156Y1621087D01*
X46198Y1621327D01*
X46156Y1621540D01*
X45948Y1621753D01*
X45698Y1621887D01*
X45448Y1621913D01*
X45156Y1621860D01*
X44948Y1621673D01*
X44865Y1621487D01*
Y1621247D01*
G01Y1621487D02*
X44740Y1621647D01*
X44531Y1621780D01*
X44281Y1621833D01*
X44031Y1621780D01*
X43823Y1621647D01*
X43698Y1621407D01*
X43740Y1621167D01*
X43906Y1620927D01*
G01X46198Y1623500D02*
X43698D01*
X44198Y1623180D01*
G01X46198D02*
Y1623820D01*
G01X49924Y1625248D02*
X51830D01*
G01X49924Y1623342D02*
Y1625248D01*
G01X47017Y1616105D02*
X48517D01*
G01X47733Y1631796D02*
X44533D01*
G01X47733Y1637996D02*
Y1631796D01*
G01X44533Y1637996D02*
X47733D01*
G01X44533Y1631796D02*
Y1637996D01*
G01X52733Y1631796D02*
X49533D01*
G01Y1637996D02*
X52733D01*
G01X49533Y1631796D02*
Y1637996D01*
G01X48122Y1628725D02*
X48282Y1628433D01*
X48496Y1628267D01*
X48736Y1628225D01*
X48949Y1628267D01*
X49162Y1628475D01*
X49296Y1628725D01*
X49322Y1628975D01*
X49269Y1629267D01*
X49082Y1629475D01*
X48896Y1629558D01*
X48656D01*
G01X48896D02*
X49056Y1629683D01*
X49189Y1629892D01*
X49242Y1630142D01*
X49189Y1630392D01*
X49056Y1630600D01*
X48816Y1630725D01*
X48576Y1630683D01*
X48336Y1630517D01*
G01X50909Y1630725D02*
X50696Y1630642D01*
X50536Y1630433D01*
X50429Y1630183D01*
X50349Y1629850D01*
X50322Y1629475D01*
X50349Y1629100D01*
X50429Y1628767D01*
X50536Y1628517D01*
X50696Y1628308D01*
X50909Y1628225D01*
X51122Y1628308D01*
X51282Y1628517D01*
X51389Y1628767D01*
X51469Y1629100D01*
X51496Y1629475D01*
X51469Y1629850D01*
X51389Y1630183D01*
X51282Y1630433D01*
X51122Y1630642D01*
X50909Y1630725D01*
G01X42827Y1666987D02*
Y1670187D01*
G01X49027D02*
Y1666987D01*
G01X42827Y1670187D02*
X49027D01*
G01Y1666987D02*
X42827D01*
G01Y1661987D02*
Y1665187D01*
G01X49027D02*
Y1661987D01*
G01X42827Y1665187D02*
X49027D01*
G01Y1661987D02*
X42827D01*
G01X40027Y1670187D02*
Y1666987D01*
G01Y1665187D02*
Y1661987D01*
G01X50527Y1679889D02*
Y1683089D01*
G01X56727Y1679889D02*
X50527D01*
G01Y1683089D02*
X56727D01*
G01X43527Y1680045D02*
Y1683245D01*
G01X49727D02*
Y1680045D01*
G01X43527Y1683245D02*
X49727D01*
G01Y1680045D02*
X43527D01*
G01X50040Y1690358D02*
Y1688136D01*
X50193Y1687671D01*
X50500Y1687361D01*
X50883Y1687258D01*
X51266Y1687361D01*
X51573Y1687671D01*
X51726Y1688136D01*
Y1690358D01*
G01X53255Y1688550D02*
X53523Y1688911D01*
X53753Y1689118D01*
X54060Y1689221D01*
X54328Y1689118D01*
X54520Y1688911D01*
X54673Y1688601D01*
X54711Y1688240D01*
X54673Y1687930D01*
X54520Y1687620D01*
X54290Y1687361D01*
X54021Y1687258D01*
X53715Y1687361D01*
X53446Y1687671D01*
X53293Y1688136D01*
X53255Y1688653D01*
X53331Y1689325D01*
X53446Y1689686D01*
X53638Y1690048D01*
X53906Y1690306D01*
X54175Y1690358D01*
X54443Y1690255D01*
X54635Y1689996D01*
G01X57083Y1690358D02*
X56776Y1690255D01*
X56546Y1689996D01*
X56393Y1689686D01*
X56278Y1689273D01*
X56240Y1688808D01*
X56278Y1688343D01*
X56393Y1687930D01*
X56546Y1687620D01*
X56776Y1687361D01*
X57083Y1687258D01*
X57390Y1687361D01*
X57620Y1687620D01*
X57773Y1687930D01*
X57888Y1688343D01*
X57926Y1688808D01*
X57888Y1689273D01*
X57773Y1689686D01*
X57620Y1689996D01*
X57390Y1690255D01*
X57083Y1690358D01*
G01X60183D02*
X59876Y1690255D01*
X59646Y1689996D01*
X59493Y1689686D01*
X59378Y1689273D01*
X59340Y1688808D01*
X59378Y1688343D01*
X59493Y1687930D01*
X59646Y1687620D01*
X59876Y1687361D01*
X60183Y1687258D01*
X60490Y1687361D01*
X60720Y1687620D01*
X60873Y1687930D01*
X60988Y1688343D01*
X61026Y1688808D01*
X60988Y1689273D01*
X60873Y1689686D01*
X60720Y1689996D01*
X60490Y1690255D01*
X60183Y1690358D01*
G01X63283D02*
X62976Y1690255D01*
X62746Y1689996D01*
X62593Y1689686D01*
X62478Y1689273D01*
X62440Y1688808D01*
X62478Y1688343D01*
X62593Y1687930D01*
X62746Y1687620D01*
X62976Y1687361D01*
X63283Y1687258D01*
X63590Y1687361D01*
X63820Y1687620D01*
X63973Y1687930D01*
X64088Y1688343D01*
X64126Y1688808D01*
X64088Y1689273D01*
X63973Y1689686D01*
X63820Y1689996D01*
X63590Y1690255D01*
X63283Y1690358D01*
G01X53472Y43779D02*
Y79D01*
G01D02*
X319772D01*
G01X64662Y43779D02*
X53472D01*
G01X51904Y63420D02*
Y57220D01*
G01X53016D02*
Y63420D01*
G01X56216D02*
Y57220D01*
G01D02*
X53016D01*
G01X70500Y51142D02*
X55500D01*
G01X53016Y63420D02*
X56216D01*
G01X65125Y269823D02*
X71325D01*
G01X65125Y266623D02*
Y269823D01*
G01X71325Y266623D02*
X65125D01*
G01X58125D02*
Y269823D01*
G01X64325Y266623D02*
X58125D01*
G01X64325Y269823D02*
Y266623D01*
G01X58125Y269823D02*
X64325D01*
G01X58255Y281957D02*
X64455D01*
G01D02*
Y278757D01*
G01D02*
X58255D01*
G01D02*
Y281957D01*
G01Y277957D02*
X64455D01*
G01D02*
Y274757D01*
G01D02*
X58255D01*
G01D02*
Y277957D01*
G01Y273957D02*
X64455D01*
G01D02*
Y270757D01*
G01D02*
X58255D01*
G01D02*
Y273957D01*
G01X58401Y286944D02*
Y284722D01*
X58554Y284257D01*
X58861Y283947D01*
X59244Y283844D01*
X59627Y283947D01*
X59934Y284257D01*
X60087Y284722D01*
Y286944D01*
G01X61616Y286427D02*
X61846Y286737D01*
X62114Y286892D01*
X62421Y286944D01*
X62804Y286841D01*
X63072Y286582D01*
X63149Y286272D01*
X63111Y285962D01*
X62957Y285704D01*
X62191Y285187D01*
X61846Y284826D01*
X61616Y284309D01*
X61539Y283844D01*
X63149D01*
G01X65904D02*
Y286944D01*
X64486Y284722D01*
X66402D01*
G01X67816Y286427D02*
X68046Y286737D01*
X68314Y286892D01*
X68621Y286944D01*
X69004Y286841D01*
X69272Y286582D01*
X69349Y286272D01*
X69311Y285962D01*
X69157Y285704D01*
X68391Y285187D01*
X68046Y284826D01*
X67816Y284309D01*
X67739Y283844D01*
X69349D01*
G01X56480Y276026D02*
Y284688D01*
G01D02*
X53371D01*
G01X62180Y296682D02*
Y302882D01*
G01X65380D02*
Y296682D01*
G01D02*
X62180D01*
G01X62900Y288400D02*
Y291600D01*
G01X69100Y288400D02*
X62900D01*
G01Y291600D02*
X69100D01*
G01X56432Y288070D02*
Y300274D01*
G01X58255Y311957D02*
X64455D01*
G01D02*
Y308757D01*
G01D02*
X58255D01*
G01D02*
Y311957D01*
G01X62180Y302882D02*
X65380D01*
G01X55600Y305100D02*
Y301900D01*
G01X56432Y300274D02*
X54682D01*
G01X56440Y306769D02*
Y315431D01*
G01D02*
X53331D01*
G01X53590Y368012D02*
X56790D01*
G01X53590Y361812D02*
Y368012D01*
G01X56790Y361812D02*
X53590D01*
G01X56790Y368012D02*
Y361812D01*
G01X66081Y368012D02*
X69281D01*
G01Y361812D02*
X66081D01*
G01D02*
Y368012D01*
G01X52714D02*
Y361812D01*
G01X57722Y368012D02*
X60922D01*
G01Y361812D02*
X57722D01*
G01X60922Y368012D02*
Y361812D01*
G01X57722D02*
Y368012D01*
G01X61829D02*
X65029D01*
G01Y361812D02*
X61829D01*
G01X65029Y368012D02*
Y361812D01*
G01X61829D02*
Y368012D01*
G01X65217Y380458D02*
X62374D01*
G01X65217Y383301D02*
Y380458D01*
G01X59374Y378801D02*
Y375801D01*
G01X62374Y400144D02*
X65217D01*
G01D02*
Y397301D01*
G01X53374Y401801D02*
Y403301D01*
G01X54563Y418603D02*
X57763D01*
G01Y412403D02*
X54563D01*
G01X57763Y418603D02*
Y412403D01*
G01X54563D02*
Y418603D01*
G01X58589Y412395D02*
Y418595D01*
X61789D01*
Y412395D01*
X58589D01*
G01X63933Y409365D02*
Y415565D01*
X67133D01*
Y409365D01*
X63933D01*
G01Y412515D02*
Y418715D01*
X67133D01*
Y412515D01*
X63933D01*
G01X58589Y409245D02*
Y415445D01*
X61789D01*
Y409245D01*
X58589D01*
G01X64008Y422146D02*
Y425346D01*
G01X70208Y422146D02*
X64008D01*
G01Y425346D02*
X70208D01*
G01X61707D02*
Y422146D01*
G01X55507Y425346D02*
X61707D01*
G01X55507Y422146D02*
Y425346D01*
G01X61707Y422146D02*
X55507D01*
G01X54502Y509185D02*
Y502985D01*
G01X66042Y509065D02*
Y502865D01*
G01D02*
X62842D01*
G01D02*
Y509065D01*
G01X60002Y502985D02*
X56802D01*
G01X60002Y509185D02*
Y502985D01*
G01X56802D02*
Y509185D01*
G01X62842Y509065D02*
X66042D01*
G01X56802Y509185D02*
X60002D01*
G01X61404Y519642D02*
Y521742D01*
G01X59304Y519642D02*
X61404D01*
G01Y533684D02*
Y535784D01*
G01D02*
X59304D01*
G01X54899Y551395D02*
Y545195D01*
G01X64748Y545160D02*
X61548D01*
G01Y551360D02*
X64748D01*
G01X61548Y545160D02*
Y551360D01*
G01X64748D02*
Y545160D01*
G01X59965D02*
X56765D01*
G01Y551360D02*
X59965D01*
G01X56765Y545160D02*
Y551360D01*
G01X59965D02*
Y545160D01*
G01X64599Y687245D02*
Y1303000D01*
G01X90189Y687245D02*
X64599D01*
G01X90189Y720710D02*
X64599D01*
G01X57673Y781125D02*
Y749325D01*
G01X90189Y1291576D02*
X64599D01*
G01X68707Y1335909D02*
X65607D01*
Y1336829D01*
X65762Y1337136D01*
X66124Y1337366D01*
X66537Y1337443D01*
X66950Y1337366D01*
X67260Y1337174D01*
X67415Y1336829D01*
Y1335909D01*
G01X65607Y1339009D02*
X68707D01*
Y1340543D01*
G01Y1343336D02*
X65607D01*
X67829Y1341918D01*
Y1343834D01*
G01X67415Y1345248D02*
X67054Y1345516D01*
X66847Y1345746D01*
X66744Y1346053D01*
X66847Y1346321D01*
X67054Y1346513D01*
X67364Y1346666D01*
X67725Y1346704D01*
X68035Y1346666D01*
X68345Y1346513D01*
X68604Y1346283D01*
X68707Y1346014D01*
X68604Y1345708D01*
X68294Y1345439D01*
X67829Y1345286D01*
X67312Y1345248D01*
X66640Y1345324D01*
X66279Y1345439D01*
X65917Y1345631D01*
X65659Y1345899D01*
X65607Y1346168D01*
X65710Y1346436D01*
X65969Y1346628D01*
G01X65864Y1417508D02*
X62764D01*
Y1418428D01*
X62919Y1418735D01*
X63281Y1418965D01*
X63694Y1419042D01*
X64107Y1418965D01*
X64417Y1418773D01*
X64572Y1418428D01*
Y1417508D01*
G01X65864Y1421375D02*
X65812Y1421068D01*
X65606Y1420800D01*
X65296Y1420570D01*
X64934Y1420417D01*
X64521Y1420340D01*
X64107D01*
X63694Y1420417D01*
X63332Y1420570D01*
X63022Y1420800D01*
X62816Y1421068D01*
X62764Y1421375D01*
X62816Y1421682D01*
X63022Y1421950D01*
X63332Y1422180D01*
X63694Y1422333D01*
X64107Y1422410D01*
X64521D01*
X64934Y1422333D01*
X65296Y1422180D01*
X65606Y1421950D01*
X65812Y1421682D01*
X65864Y1421375D01*
G01X65037Y1421682D02*
X65864Y1422142D01*
G01Y1424475D02*
X62764D01*
X63384Y1424015D01*
G01X65864D02*
Y1424935D01*
G01X64572Y1426847D02*
X64211Y1427115D01*
X64004Y1427345D01*
X63901Y1427652D01*
X64004Y1427920D01*
X64211Y1428112D01*
X64521Y1428265D01*
X64882Y1428303D01*
X65192Y1428265D01*
X65502Y1428112D01*
X65761Y1427882D01*
X65864Y1427613D01*
X65761Y1427307D01*
X65451Y1427038D01*
X64986Y1426885D01*
X64469Y1426847D01*
X63797Y1426923D01*
X63436Y1427038D01*
X63074Y1427230D01*
X62816Y1427498D01*
X62764Y1427767D01*
X62867Y1428035D01*
X63126Y1428227D01*
G01X66285Y1438116D02*
X63185D01*
Y1439036D01*
X63340Y1439343D01*
X63702Y1439573D01*
X64115Y1439650D01*
X64528Y1439573D01*
X64838Y1439381D01*
X64993Y1439036D01*
Y1438116D01*
G01X66285Y1441983D02*
X66233Y1441676D01*
X66027Y1441408D01*
X65717Y1441178D01*
X65355Y1441025D01*
X64942Y1440948D01*
X64528D01*
X64115Y1441025D01*
X63753Y1441178D01*
X63443Y1441408D01*
X63237Y1441676D01*
X63185Y1441983D01*
X63237Y1442290D01*
X63443Y1442558D01*
X63753Y1442788D01*
X64115Y1442941D01*
X64528Y1443018D01*
X64942D01*
X65355Y1442941D01*
X65717Y1442788D01*
X66027Y1442558D01*
X66233Y1442290D01*
X66285Y1441983D01*
G01X65458Y1442290D02*
X66285Y1442750D01*
G01Y1445083D02*
X63185D01*
X63805Y1444623D01*
G01X66285D02*
Y1445543D01*
G01X63702Y1447455D02*
X63392Y1447685D01*
X63237Y1447953D01*
X63185Y1448260D01*
X63288Y1448643D01*
X63547Y1448911D01*
X63857Y1448988D01*
X64167Y1448950D01*
X64425Y1448796D01*
X64942Y1448030D01*
X65303Y1447685D01*
X65820Y1447455D01*
X66285Y1447378D01*
Y1448988D01*
G01X65883Y1451500D02*
Y1454600D01*
X66803D01*
X67110Y1454445D01*
X67340Y1454083D01*
X67417Y1453670D01*
X67340Y1453257D01*
X67148Y1452947D01*
X66803Y1452792D01*
X65883D01*
G01X70593Y1454342D02*
X70363Y1454497D01*
X70095Y1454600D01*
X69788D01*
X69443Y1454445D01*
X69175Y1454187D01*
X68983Y1453877D01*
X68830Y1453360D01*
X68792Y1452895D01*
X68868Y1452430D01*
X68983Y1452120D01*
X69213Y1451810D01*
X69482Y1451603D01*
X69750Y1451500D01*
X70018D01*
X70287Y1451603D01*
X70517Y1451758D01*
X70708Y1451965D01*
G01X72122Y1452792D02*
X72390Y1453153D01*
X72620Y1453360D01*
X72927Y1453463D01*
X73195Y1453360D01*
X73387Y1453153D01*
X73540Y1452843D01*
X73578Y1452482D01*
X73540Y1452172D01*
X73387Y1451862D01*
X73157Y1451603D01*
X72888Y1451500D01*
X72582Y1451603D01*
X72313Y1451913D01*
X72160Y1452378D01*
X72122Y1452895D01*
X72198Y1453567D01*
X72313Y1453928D01*
X72505Y1454290D01*
X72773Y1454548D01*
X73042Y1454600D01*
X73310Y1454497D01*
X73502Y1454238D01*
G01X75222Y1452792D02*
X75490Y1453153D01*
X75720Y1453360D01*
X76027Y1453463D01*
X76295Y1453360D01*
X76487Y1453153D01*
X76640Y1452843D01*
X76678Y1452482D01*
X76640Y1452172D01*
X76487Y1451862D01*
X76257Y1451603D01*
X75988Y1451500D01*
X75682Y1451603D01*
X75413Y1451913D01*
X75260Y1452378D01*
X75222Y1452895D01*
X75298Y1453567D01*
X75413Y1453928D01*
X75605Y1454290D01*
X75873Y1454548D01*
X76142Y1454600D01*
X76410Y1454497D01*
X76602Y1454238D01*
G01X78207Y1452120D02*
X78437Y1451758D01*
X78743Y1451552D01*
X79088Y1451500D01*
X79395Y1451552D01*
X79702Y1451810D01*
X79893Y1452120D01*
X79932Y1452430D01*
X79855Y1452792D01*
X79587Y1453050D01*
X79318Y1453153D01*
X78973D01*
G01X79318D02*
X79548Y1453308D01*
X79740Y1453567D01*
X79817Y1453877D01*
X79740Y1454187D01*
X79548Y1454445D01*
X79203Y1454600D01*
X78858Y1454548D01*
X78513Y1454342D01*
G01X82150Y1454600D02*
X81843Y1454497D01*
X81613Y1454238D01*
X81460Y1453928D01*
X81345Y1453515D01*
X81307Y1453050D01*
X81345Y1452585D01*
X81460Y1452172D01*
X81613Y1451862D01*
X81843Y1451603D01*
X82150Y1451500D01*
X82457Y1451603D01*
X82687Y1451862D01*
X82840Y1452172D01*
X82955Y1452585D01*
X82993Y1453050D01*
X82955Y1453515D01*
X82840Y1453928D01*
X82687Y1454238D01*
X82457Y1454497D01*
X82150Y1454600D01*
G01X63445Y1459448D02*
X70572D01*
G01X63445Y1478102D02*
Y1459448D01*
G01X61099D02*
Y1478102D01*
G01X53972Y1459448D02*
X61099D01*
G01X57500Y1489883D02*
X54400D01*
Y1490803D01*
X54555Y1491110D01*
X54917Y1491340D01*
X55330Y1491417D01*
X55743Y1491340D01*
X56053Y1491148D01*
X56208Y1490803D01*
Y1489883D01*
G01X54400Y1492983D02*
X57500D01*
Y1494517D01*
G01X56208Y1496122D02*
X55847Y1496390D01*
X55640Y1496620D01*
X55537Y1496927D01*
X55640Y1497195D01*
X55847Y1497387D01*
X56157Y1497540D01*
X56518Y1497578D01*
X56828Y1497540D01*
X57138Y1497387D01*
X57397Y1497157D01*
X57500Y1496888D01*
X57397Y1496582D01*
X57087Y1496313D01*
X56622Y1496160D01*
X56105Y1496122D01*
X55433Y1496198D01*
X55072Y1496313D01*
X54710Y1496505D01*
X54452Y1496773D01*
X54400Y1497042D01*
X54503Y1497310D01*
X54762Y1497502D01*
G01X57035Y1499107D02*
X57293Y1499337D01*
X57448Y1499605D01*
X57500Y1499950D01*
X57397Y1500295D01*
X57190Y1500563D01*
X56828Y1500755D01*
X56415Y1500793D01*
X56002Y1500717D01*
X55743Y1500525D01*
X55537Y1500257D01*
X55485Y1499988D01*
X55537Y1499720D01*
X55743Y1499375D01*
X54400Y1499490D01*
Y1500525D01*
G01X57500Y1503050D02*
X54400D01*
X55020Y1502590D01*
G01X57500D02*
Y1503510D01*
G01Y1506150D02*
X54400D01*
X55020Y1505690D01*
G01X57500D02*
Y1506610D01*
G01X58326Y1489905D02*
Y1515495D01*
G01X62321Y1489905D02*
X58326D01*
G01X66445Y1481102D02*
X63445Y1478102D01*
G01X70572Y1481102D02*
X66445D01*
G01X58099D02*
X53972D01*
G01X61099Y1478102D02*
X58099Y1481102D01*
G01X53640Y1503897D02*
Y1497697D01*
G01X53262Y1520935D02*
Y1517735D01*
G01X58326Y1515495D02*
X62321D01*
G01X55362Y1519111D02*
Y1521711D01*
G01X56155Y1519111D02*
X55362D01*
G01X52231Y1534771D02*
Y1528571D01*
G01Y1540800D02*
Y1535571D01*
G01X55362Y1528322D02*
Y1530020D01*
G01X53596Y1556042D02*
Y1549842D01*
G01X52296Y1548969D02*
Y1544800D01*
G01X60096Y1551269D02*
Y1554469D01*
G01X66296Y1551269D02*
X60096D01*
G01X66296Y1554469D02*
Y1551269D01*
G01X55362Y1542733D02*
X56370D01*
G01X55362Y1540879D02*
Y1542733D01*
G01X60096Y1554469D02*
X66296D01*
G01X60665Y1571494D02*
Y1564367D01*
X79319D01*
X82319Y1567367D01*
Y1571494D01*
G01X77168Y1556357D02*
X65168D01*
G01Y1562357D02*
X77168D01*
G01X65168Y1556357D02*
Y1562357D01*
G01X79319Y1586021D02*
X60665D01*
Y1578894D01*
G01X60233Y1588796D02*
X57033D01*
G01X60233Y1594996D02*
Y1588796D01*
G01X57033Y1594996D02*
X60233D01*
G01X57033Y1588796D02*
Y1594996D01*
G01X65233Y1588796D02*
X62033D01*
G01X65233Y1594996D02*
Y1588796D01*
G01X62033Y1594996D02*
X65233D01*
G01X62033Y1588796D02*
Y1594996D01*
G01X69733Y1588796D02*
X66533D01*
G01Y1594996D02*
X69733D01*
G01X66533Y1588796D02*
Y1594996D01*
G01X59067Y1602555D02*
Y1604055D01*
G01X65533Y1631996D02*
X71733D01*
G01X65533Y1628796D02*
Y1631996D01*
G01X71733Y1628796D02*
X65533D01*
G01X52733Y1637996D02*
Y1631796D01*
G01X57733Y1634896D02*
X54533D01*
G01X57733Y1641096D02*
Y1634896D01*
G01X54533Y1641096D02*
X57733D01*
G01X54533Y1634896D02*
Y1641096D01*
G01X62733Y1634896D02*
X59533D01*
G01X62733Y1641096D02*
Y1634896D01*
G01X59533Y1641096D02*
X62733D01*
G01X59533Y1634896D02*
Y1641096D01*
G01X52767Y1626705D02*
Y1629705D01*
G01X60567Y1626755D02*
Y1628255D01*
G01X57827Y1651487D02*
X61027D01*
G01X57827Y1645287D02*
Y1651487D01*
G01X61027Y1645287D02*
X57827D01*
G01X61027Y1651487D02*
Y1645287D01*
G01X62827Y1651487D02*
X66027D01*
G01Y1645287D02*
X62827D01*
G01X66027Y1651487D02*
Y1645287D01*
G01X62827D02*
Y1651487D01*
G01X53827D02*
X57027D01*
G01Y1645287D02*
X53827D01*
G01X57027Y1651487D02*
Y1645287D01*
G01X53827D02*
Y1651487D01*
G01X57375Y1657809D02*
Y1659880D01*
G01X59446Y1657809D02*
X57375D01*
G01X63727Y1683616D02*
Y1680416D01*
G01X57527Y1683616D02*
X63727D01*
G01X57527Y1680416D02*
Y1683616D01*
G01X63727Y1680416D02*
X57527D01*
G01X64527Y1680287D02*
Y1686487D01*
G01X67727Y1680287D02*
X64527D01*
G01X56727Y1683089D02*
Y1679889D01*
G01X57375Y1673951D02*
X59446D01*
G01X57375Y1671880D02*
Y1673951D01*
G01X64527Y1686487D02*
X67727D01*
G01X80000Y51142D02*
X77500D01*
G01X79296Y81657D02*
X78549Y81782D01*
X77896Y82282D01*
X77336Y83032D01*
X76963Y83907D01*
X76776Y84907D01*
Y85907D01*
X76963Y86907D01*
X77336Y87782D01*
X77896Y88532D01*
X78549Y89032D01*
X79296Y89157D01*
X80043Y89032D01*
X80696Y88532D01*
X81256Y87782D01*
X81629Y86907D01*
X81816Y85907D01*
Y84907D01*
X81629Y83907D01*
X81256Y83032D01*
X80696Y82282D01*
X80043Y81782D01*
X79296Y81657D01*
G01X88849Y88532D02*
X88289Y88907D01*
X87636Y89157D01*
X86889D01*
X86049Y88782D01*
X85396Y88157D01*
X84929Y87407D01*
X84556Y86157D01*
X84463Y85032D01*
X84649Y83907D01*
X84929Y83157D01*
X85489Y82407D01*
X86143Y81907D01*
X86796Y81657D01*
X87449D01*
X88103Y81907D01*
X88663Y82282D01*
X89129Y82782D01*
G01X92429Y81657D02*
Y89157D01*
X94669D01*
X95416Y88782D01*
X95976Y87907D01*
X96163Y86907D01*
X95976Y85907D01*
X95509Y85157D01*
X94669Y84782D01*
X92429D01*
G01X107149Y81657D02*
Y89157D01*
X111443Y81657D01*
Y89157D01*
G01X115676D02*
X117916D01*
G01X116796D02*
Y81657D01*
G01X115676D02*
X117916D01*
G01X126349Y88532D02*
X125789Y88907D01*
X125136Y89157D01*
X124389D01*
X123549Y88782D01*
X122896Y88157D01*
X122429Y87407D01*
X122056Y86157D01*
X121963Y85032D01*
X122149Y83907D01*
X122429Y83157D01*
X122989Y82407D01*
X123643Y81907D01*
X124296Y81657D01*
X124949D01*
X125603Y81907D01*
X126163Y82282D01*
X126629Y82782D01*
G01X139296Y81657D02*
Y89157D01*
X138176Y87657D01*
G01Y81657D02*
X140416D01*
G01X78851Y146791D02*
Y143591D01*
G01X72651Y146791D02*
X78851D01*
G01X72651Y143591D02*
Y146791D01*
G01X78851Y143591D02*
X72651D01*
G01X80501Y139350D02*
Y142550D01*
G01X86701Y139350D02*
X80501D01*
G01Y142550D02*
X86701D01*
G01X78854Y150791D02*
Y147591D01*
G01X72654D02*
Y150791D01*
G01X78854Y147591D02*
X72654D01*
G01Y155591D02*
Y158791D01*
G01X78854Y155591D02*
X72654D01*
G01X78854Y158791D02*
Y155591D01*
G01X72654Y158791D02*
X78854D01*
G01X72654Y159591D02*
Y162791D01*
G01X78854Y159591D02*
X72654D01*
G01X78854Y162791D02*
Y159591D01*
G01X72654Y162791D02*
X78854D01*
G01X72654Y163591D02*
Y166791D01*
G01X78854Y163591D02*
X72654D01*
G01X78854Y166791D02*
Y163591D01*
G01X72654Y150791D02*
X78854D01*
G01Y151591D02*
X72654D01*
Y154791D01*
X78854D01*
Y151591D01*
G01X72654Y166791D02*
X78854D01*
G01X81338Y174472D02*
Y172250D01*
X81491Y171785D01*
X81798Y171475D01*
X82181Y171372D01*
X82564Y171475D01*
X82871Y171785D01*
X83024Y172250D01*
Y174472D01*
G01X84438Y171837D02*
X84668Y171579D01*
X84936Y171424D01*
X85281Y171372D01*
X85626Y171475D01*
X85894Y171682D01*
X86086Y172044D01*
X86124Y172457D01*
X86048Y172870D01*
X85856Y173129D01*
X85588Y173335D01*
X85319Y173387D01*
X85051Y173335D01*
X84706Y173129D01*
X84821Y174472D01*
X85856D01*
G01X87653Y172664D02*
X87921Y173025D01*
X88151Y173232D01*
X88458Y173335D01*
X88726Y173232D01*
X88918Y173025D01*
X89071Y172715D01*
X89109Y172354D01*
X89071Y172044D01*
X88918Y171734D01*
X88688Y171475D01*
X88419Y171372D01*
X88113Y171475D01*
X87844Y171785D01*
X87691Y172250D01*
X87653Y172767D01*
X87729Y173439D01*
X87844Y173800D01*
X88036Y174162D01*
X88304Y174420D01*
X88573Y174472D01*
X88841Y174369D01*
X89033Y174110D01*
G01X73918Y264140D02*
X74148Y264450D01*
X74416Y264605D01*
X74723Y264657D01*
X75106Y264554D01*
X75374Y264295D01*
X75451Y263985D01*
X75413Y263675D01*
X75259Y263417D01*
X74493Y262900D01*
X74148Y262539D01*
X73918Y262022D01*
X73841Y261557D01*
X75451D01*
G01X77248Y262590D02*
X78244D01*
G01X80003Y262177D02*
X80233Y261815D01*
X80539Y261609D01*
X80884Y261557D01*
X81191Y261609D01*
X81498Y261867D01*
X81689Y262177D01*
X81728Y262487D01*
X81651Y262849D01*
X81383Y263107D01*
X81114Y263210D01*
X80769D01*
G01X81114D02*
X81344Y263365D01*
X81536Y263624D01*
X81613Y263934D01*
X81536Y264244D01*
X81344Y264502D01*
X80999Y264657D01*
X80654Y264605D01*
X80309Y264399D01*
G01X87813Y261557D02*
X86279D01*
Y264657D01*
X87813D01*
G01X87199Y263159D02*
X86279D01*
G01X89264Y261557D02*
Y264657D01*
X91028Y261557D01*
Y264657D01*
G01X92288Y261557D02*
X93246Y264657D01*
X94204Y261557D01*
G01X93859Y262642D02*
X92633D01*
G01X96653Y263210D02*
X96806Y263365D01*
X96921Y263624D01*
X96998Y263985D01*
X96921Y264295D01*
X96768Y264502D01*
X96499Y264657D01*
X95464D01*
Y261557D01*
X96729D01*
X96998Y261764D01*
X97151Y262074D01*
X97228Y262435D01*
X97151Y262797D01*
X96921Y263107D01*
X96653Y263210D01*
X95464D01*
G01X98679Y264657D02*
Y261557D01*
X100213D01*
G01X103313D02*
X101779D01*
Y264657D01*
X103313D01*
G01X102699Y263159D02*
X101779D01*
G01X105454Y260524D02*
X105071Y261040D01*
X104879Y261557D01*
Y263624D01*
X105071Y264140D01*
X105454Y264657D01*
G01X107903Y261557D02*
Y264657D01*
X108669D01*
X108976Y264502D01*
X109206Y264295D01*
X109398Y263985D01*
X109551Y263624D01*
X109589Y263107D01*
X109551Y262590D01*
X109398Y262229D01*
X109206Y261919D01*
X108976Y261712D01*
X108669Y261557D01*
X107903D01*
G01X112613D02*
X111079D01*
Y264657D01*
X112613D01*
G01X111999Y263159D02*
X111079D01*
G01X114218Y261557D02*
Y264657D01*
X115674D01*
G01X115138Y263159D02*
X114218D01*
G01X117088Y261557D02*
X118046Y264657D01*
X119004Y261557D01*
G01X118659Y262642D02*
X117433D01*
G01X120303Y264657D02*
Y262435D01*
X120456Y261970D01*
X120763Y261660D01*
X121146Y261557D01*
X121529Y261660D01*
X121836Y261970D01*
X121989Y262435D01*
Y264657D01*
G01X123479D02*
Y261557D01*
X125013D01*
G01X127346Y264657D02*
Y261557D01*
G01X126464Y264657D02*
X128228D01*
G01X130638Y260524D02*
X131021Y261040D01*
X131213Y261557D01*
Y263624D01*
X131021Y264140D01*
X130638Y264657D01*
G01X74646Y267157D02*
Y270257D01*
X74186Y269637D01*
G01Y267157D02*
X75106D01*
G01X77248Y268190D02*
X78244D01*
G01X80118Y269740D02*
X80348Y270050D01*
X80616Y270205D01*
X80923Y270257D01*
X81306Y270154D01*
X81574Y269895D01*
X81651Y269585D01*
X81613Y269275D01*
X81459Y269017D01*
X80693Y268500D01*
X80348Y268139D01*
X80118Y267622D01*
X80041Y267157D01*
X81651D01*
G01X86203D02*
Y270257D01*
X86969D01*
X87276Y270102D01*
X87506Y269895D01*
X87698Y269585D01*
X87851Y269224D01*
X87889Y268707D01*
X87851Y268190D01*
X87698Y267829D01*
X87506Y267519D01*
X87276Y267312D01*
X86969Y267157D01*
X86203D01*
G01X89686Y270257D02*
X90606D01*
G01X90146D02*
Y267157D01*
G01X89686D02*
X90606D01*
G01X92441Y267570D02*
X92748Y267312D01*
X93093Y267157D01*
X93399D01*
X93706Y267312D01*
X93936Y267570D01*
X94051Y267932D01*
X93974Y268294D01*
X93783Y268604D01*
X93438Y268810D01*
X92978Y268914D01*
X92709Y269120D01*
X92594Y269482D01*
X92671Y269844D01*
X92863Y270102D01*
X93131Y270257D01*
X93399D01*
X93668Y270154D01*
X93898Y269895D01*
G01X95388Y267157D02*
X96346Y270257D01*
X97304Y267157D01*
G01X96959Y268242D02*
X95733D01*
G01X99753Y268810D02*
X99906Y268965D01*
X100021Y269224D01*
X100098Y269585D01*
X100021Y269895D01*
X99868Y270102D01*
X99599Y270257D01*
X98564D01*
Y267157D01*
X99829D01*
X100098Y267364D01*
X100251Y267674D01*
X100328Y268035D01*
X100251Y268397D01*
X100021Y268707D01*
X99753Y268810D01*
X98564D01*
G01X101779Y270257D02*
Y267157D01*
X103313D01*
G01X106413D02*
X104879D01*
Y270257D01*
X106413D01*
G01X105799Y268759D02*
X104879D01*
G01X71325Y269823D02*
Y266623D01*
G01X73879Y273377D02*
X74071Y273067D01*
X74301Y272860D01*
X74569Y272757D01*
X74876Y272860D01*
X75106Y273067D01*
X75336Y273377D01*
X75413Y273790D01*
Y275857D01*
G01X77746D02*
Y272757D01*
G01X76864Y275857D02*
X78628D01*
G01X79888Y272757D02*
X80846Y275857D01*
X81804Y272757D01*
G01X81459Y273842D02*
X80233D01*
G01X84176Y274307D02*
X84943D01*
Y273377D01*
X84713Y273067D01*
X84444Y272860D01*
X84061Y272757D01*
X83678Y272860D01*
X83409Y273067D01*
X83179Y273377D01*
X83026Y273739D01*
X82949Y274152D01*
Y274514D01*
X83026Y274824D01*
X83179Y275185D01*
X83409Y275495D01*
X83639Y275702D01*
X83946Y275857D01*
X84214D01*
X84521Y275754D01*
X84751Y275547D01*
G01X90913Y272757D02*
X89379D01*
Y275857D01*
X90913D01*
G01X90299Y274359D02*
X89379D01*
G01X92364Y272757D02*
Y275857D01*
X94128Y272757D01*
Y275857D01*
G01X95388Y272757D02*
X96346Y275857D01*
X97304Y272757D01*
G01X96959Y273842D02*
X95733D01*
G01X99753Y274410D02*
X99906Y274565D01*
X100021Y274824D01*
X100098Y275185D01*
X100021Y275495D01*
X99868Y275702D01*
X99599Y275857D01*
X98564D01*
Y272757D01*
X99829D01*
X100098Y272964D01*
X100251Y273274D01*
X100328Y273635D01*
X100251Y273997D01*
X100021Y274307D01*
X99753Y274410D01*
X98564D01*
G01X101779Y275857D02*
Y272757D01*
X103313D01*
G01X106413D02*
X104879D01*
Y275857D01*
X106413D01*
G01X105799Y274359D02*
X104879D01*
G01X111079Y273377D02*
X111271Y273067D01*
X111501Y272860D01*
X111769Y272757D01*
X112076Y272860D01*
X112306Y273067D01*
X112536Y273377D01*
X112613Y273790D01*
Y275857D01*
G01X114103D02*
Y273635D01*
X114256Y273170D01*
X114563Y272860D01*
X114946Y272757D01*
X115329Y272860D01*
X115636Y273170D01*
X115789Y273635D01*
Y275857D01*
G01X117049Y272757D02*
Y275857D01*
X118046Y273274D01*
X119043Y275857D01*
Y272757D01*
G01X120379D02*
Y275857D01*
X121299D01*
X121606Y275702D01*
X121836Y275340D01*
X121913Y274927D01*
X121836Y274514D01*
X121644Y274204D01*
X121299Y274049D01*
X120379D01*
G01X125013Y272757D02*
X123479D01*
Y275857D01*
X125013D01*
G01X124399Y274359D02*
X123479D01*
G01X126579Y272757D02*
Y275857D01*
X127538D01*
X127844Y275702D01*
X128036Y275495D01*
X128113Y275082D01*
X128036Y274669D01*
X127806Y274410D01*
X127538Y274255D01*
X126579D01*
G01X127538D02*
X128113Y272757D01*
G01X74411Y279396D02*
X74603Y279086D01*
X74833Y278879D01*
X75101Y278776D01*
X75408Y278879D01*
X75638Y279086D01*
X75868Y279396D01*
X75945Y279809D01*
Y281876D01*
G01X77511Y278776D02*
Y281876D01*
X78431D01*
X78738Y281721D01*
X78968Y281359D01*
X79045Y280946D01*
X78968Y280533D01*
X78776Y280223D01*
X78431Y280068D01*
X77511D01*
G01X80650D02*
X80918Y280429D01*
X81148Y280636D01*
X81455Y280739D01*
X81723Y280636D01*
X81915Y280429D01*
X82068Y280119D01*
X82106Y279758D01*
X82068Y279448D01*
X81915Y279138D01*
X81685Y278879D01*
X81416Y278776D01*
X81110Y278879D01*
X80841Y279189D01*
X80688Y279654D01*
X80650Y280171D01*
X80726Y280843D01*
X80841Y281204D01*
X81033Y281566D01*
X81301Y281824D01*
X81570Y281876D01*
X81838Y281773D01*
X82030Y281514D01*
G01X84478Y281876D02*
X84171Y281773D01*
X83941Y281514D01*
X83788Y281204D01*
X83673Y280791D01*
X83635Y280326D01*
X83673Y279861D01*
X83788Y279448D01*
X83941Y279138D01*
X84171Y278879D01*
X84478Y278776D01*
X84785Y278879D01*
X85015Y279138D01*
X85168Y279448D01*
X85283Y279861D01*
X85321Y280326D01*
X85283Y280791D01*
X85168Y281204D01*
X85015Y281514D01*
X84785Y281773D01*
X84478Y281876D01*
G01X87578D02*
X87271Y281773D01*
X87041Y281514D01*
X86888Y281204D01*
X86773Y280791D01*
X86735Y280326D01*
X86773Y279861D01*
X86888Y279448D01*
X87041Y279138D01*
X87271Y278879D01*
X87578Y278776D01*
X87885Y278879D01*
X88115Y279138D01*
X88268Y279448D01*
X88383Y279861D01*
X88421Y280326D01*
X88383Y280791D01*
X88268Y281204D01*
X88115Y281514D01*
X87885Y281773D01*
X87578Y281876D01*
G01X90678D02*
X90371Y281773D01*
X90141Y281514D01*
X89988Y281204D01*
X89873Y280791D01*
X89835Y280326D01*
X89873Y279861D01*
X89988Y279448D01*
X90141Y279138D01*
X90371Y278879D01*
X90678Y278776D01*
X90985Y278879D01*
X91215Y279138D01*
X91368Y279448D01*
X91483Y279861D01*
X91521Y280326D01*
X91483Y280791D01*
X91368Y281204D01*
X91215Y281514D01*
X90985Y281773D01*
X90678Y281876D01*
G01X69100Y291600D02*
Y288400D01*
G01X78749Y297665D02*
X78387Y297435D01*
X78181Y297129D01*
X78129Y296784D01*
X78181Y296477D01*
X78439Y296170D01*
X78749Y295979D01*
X79059Y295940D01*
X79421Y296017D01*
X79679Y296285D01*
X79782Y296554D01*
Y296899D01*
G01Y296554D02*
X79937Y296324D01*
X80196Y296132D01*
X80506Y296055D01*
X80816Y296132D01*
X81074Y296324D01*
X81229Y296669D01*
X81177Y297014D01*
X80971Y297359D01*
G01X74532Y294743D02*
X104926D01*
G01X74532Y284901D02*
Y294743D01*
G01X104926Y284901D02*
X74532D01*
G01Y305335D02*
Y315177D01*
G01X104926Y305335D02*
X74532D01*
G01X75153Y332810D02*
X75383Y333120D01*
X75651Y333275D01*
X75958Y333327D01*
X76341Y333224D01*
X76609Y332965D01*
X76686Y332655D01*
X76648Y332345D01*
X76494Y332087D01*
X75728Y331570D01*
X75383Y331209D01*
X75153Y330692D01*
X75076Y330227D01*
X76686D01*
G01X78483Y331260D02*
X79479D01*
G01X81238Y330847D02*
X81468Y330485D01*
X81774Y330279D01*
X82119Y330227D01*
X82426Y330279D01*
X82733Y330537D01*
X82924Y330847D01*
X82963Y331157D01*
X82886Y331519D01*
X82618Y331777D01*
X82349Y331880D01*
X82004D01*
G01X82349D02*
X82579Y332035D01*
X82771Y332294D01*
X82848Y332604D01*
X82771Y332914D01*
X82579Y333172D01*
X82234Y333327D01*
X81889Y333275D01*
X81544Y333069D01*
G01X89048Y330227D02*
X87514D01*
Y333327D01*
X89048D01*
G01X88434Y331829D02*
X87514D01*
G01X90499Y330227D02*
Y333327D01*
X92263Y330227D01*
Y333327D01*
G01X93523Y330227D02*
X94481Y333327D01*
X95439Y330227D01*
G01X95094Y331312D02*
X93868D01*
G01X97888Y331880D02*
X98041Y332035D01*
X98156Y332294D01*
X98233Y332655D01*
X98156Y332965D01*
X98003Y333172D01*
X97734Y333327D01*
X96699D01*
Y330227D01*
X97964D01*
X98233Y330434D01*
X98386Y330744D01*
X98463Y331105D01*
X98386Y331467D01*
X98156Y331777D01*
X97888Y331880D01*
X96699D01*
G01X99914Y333327D02*
Y330227D01*
X101448D01*
G01X104548D02*
X103014D01*
Y333327D01*
X104548D01*
G01X103934Y331829D02*
X103014D01*
G01X106689Y329194D02*
X106306Y329710D01*
X106114Y330227D01*
Y332294D01*
X106306Y332810D01*
X106689Y333327D01*
G01X109138Y330227D02*
Y333327D01*
X109904D01*
X110211Y333172D01*
X110441Y332965D01*
X110633Y332655D01*
X110786Y332294D01*
X110824Y331777D01*
X110786Y331260D01*
X110633Y330899D01*
X110441Y330589D01*
X110211Y330382D01*
X109904Y330227D01*
X109138D01*
G01X113848D02*
X112314D01*
Y333327D01*
X113848D01*
G01X113234Y331829D02*
X112314D01*
G01X115453Y330227D02*
Y333327D01*
X116909D01*
G01X116373Y331829D02*
X115453D01*
G01X118323Y330227D02*
X119281Y333327D01*
X120239Y330227D01*
G01X119894Y331312D02*
X118668D01*
G01X121538Y333327D02*
Y331105D01*
X121691Y330640D01*
X121998Y330330D01*
X122381Y330227D01*
X122764Y330330D01*
X123071Y330640D01*
X123224Y331105D01*
Y333327D01*
G01X124714D02*
Y330227D01*
X126248D01*
G01X128581Y333327D02*
Y330227D01*
G01X127699Y333327D02*
X129463D01*
G01X131873Y329194D02*
X132256Y329710D01*
X132448Y330227D01*
Y332294D01*
X132256Y332810D01*
X131873Y333327D01*
G01X78749Y318099D02*
X78387Y317869D01*
X78181Y317563D01*
X78129Y317218D01*
X78181Y316911D01*
X78439Y316604D01*
X78749Y316413D01*
X79059Y316374D01*
X79421Y316451D01*
X79679Y316719D01*
X79782Y316988D01*
Y317333D01*
G01Y316988D02*
X79937Y316758D01*
X80196Y316566D01*
X80506Y316489D01*
X80816Y316566D01*
X81074Y316758D01*
X81229Y317103D01*
X81177Y317448D01*
X80971Y317793D01*
G01X73626Y321824D02*
X73818Y321514D01*
X74048Y321307D01*
X74316Y321204D01*
X74623Y321307D01*
X74853Y321514D01*
X75083Y321824D01*
X75160Y322237D01*
Y324304D01*
G01X76726Y321204D02*
Y324304D01*
X77646D01*
X77953Y324149D01*
X78183Y323787D01*
X78260Y323374D01*
X78183Y322961D01*
X77991Y322651D01*
X77646Y322496D01*
X76726D01*
G01X79865D02*
X80133Y322857D01*
X80363Y323064D01*
X80670Y323167D01*
X80938Y323064D01*
X81130Y322857D01*
X81283Y322547D01*
X81321Y322186D01*
X81283Y321876D01*
X81130Y321566D01*
X80900Y321307D01*
X80631Y321204D01*
X80325Y321307D01*
X80056Y321617D01*
X79903Y322082D01*
X79865Y322599D01*
X79941Y323271D01*
X80056Y323632D01*
X80248Y323994D01*
X80516Y324252D01*
X80785Y324304D01*
X81053Y324201D01*
X81245Y323942D01*
G01X83693Y324304D02*
X83386Y324201D01*
X83156Y323942D01*
X83003Y323632D01*
X82888Y323219D01*
X82850Y322754D01*
X82888Y322289D01*
X83003Y321876D01*
X83156Y321566D01*
X83386Y321307D01*
X83693Y321204D01*
X84000Y321307D01*
X84230Y321566D01*
X84383Y321876D01*
X84498Y322289D01*
X84536Y322754D01*
X84498Y323219D01*
X84383Y323632D01*
X84230Y323942D01*
X84000Y324201D01*
X83693Y324304D01*
G01X86793D02*
X86486Y324201D01*
X86256Y323942D01*
X86103Y323632D01*
X85988Y323219D01*
X85950Y322754D01*
X85988Y322289D01*
X86103Y321876D01*
X86256Y321566D01*
X86486Y321307D01*
X86793Y321204D01*
X87100Y321307D01*
X87330Y321566D01*
X87483Y321876D01*
X87598Y322289D01*
X87636Y322754D01*
X87598Y323219D01*
X87483Y323632D01*
X87330Y323942D01*
X87100Y324201D01*
X86793Y324304D01*
G01X89893Y321204D02*
Y324304D01*
X89433Y323684D01*
G01Y321204D02*
X90353D01*
G01X74532Y315177D02*
X104926D01*
G01X75881Y334827D02*
Y337927D01*
X75421Y337307D01*
G01Y334827D02*
X76341D01*
G01X78483Y335860D02*
X79479D01*
G01X81353Y337410D02*
X81583Y337720D01*
X81851Y337875D01*
X82158Y337927D01*
X82541Y337824D01*
X82809Y337565D01*
X82886Y337255D01*
X82848Y336945D01*
X82694Y336687D01*
X81928Y336170D01*
X81583Y335809D01*
X81353Y335292D01*
X81276Y334827D01*
X82886D01*
G01X87438D02*
Y337927D01*
X88204D01*
X88511Y337772D01*
X88741Y337565D01*
X88933Y337255D01*
X89086Y336894D01*
X89124Y336377D01*
X89086Y335860D01*
X88933Y335499D01*
X88741Y335189D01*
X88511Y334982D01*
X88204Y334827D01*
X87438D01*
G01X90921Y337927D02*
X91841D01*
G01X91381D02*
Y334827D01*
G01X90921D02*
X91841D01*
G01X93676Y335240D02*
X93983Y334982D01*
X94328Y334827D01*
X94634D01*
X94941Y334982D01*
X95171Y335240D01*
X95286Y335602D01*
X95209Y335964D01*
X95018Y336274D01*
X94673Y336480D01*
X94213Y336584D01*
X93944Y336790D01*
X93829Y337152D01*
X93906Y337514D01*
X94098Y337772D01*
X94366Y337927D01*
X94634D01*
X94903Y337824D01*
X95133Y337565D01*
G01X96623Y334827D02*
X97581Y337927D01*
X98539Y334827D01*
G01X98194Y335912D02*
X96968D01*
G01X100988Y336480D02*
X101141Y336635D01*
X101256Y336894D01*
X101333Y337255D01*
X101256Y337565D01*
X101103Y337772D01*
X100834Y337927D01*
X99799D01*
Y334827D01*
X101064D01*
X101333Y335034D01*
X101486Y335344D01*
X101563Y335705D01*
X101486Y336067D01*
X101256Y336377D01*
X100988Y336480D01*
X99799D01*
G01X103014Y337927D02*
Y334827D01*
X104548D01*
G01X107648D02*
X106114D01*
Y337927D01*
X107648D01*
G01X107034Y336429D02*
X106114D01*
G01X75114Y340047D02*
X75306Y339737D01*
X75536Y339530D01*
X75804Y339427D01*
X76111Y339530D01*
X76341Y339737D01*
X76571Y340047D01*
X76648Y340460D01*
Y342527D01*
G01X78981D02*
Y339427D01*
G01X78099Y342527D02*
X79863D01*
G01X81123Y339427D02*
X82081Y342527D01*
X83039Y339427D01*
G01X82694Y340512D02*
X81468D01*
G01X85411Y340977D02*
X86178D01*
Y340047D01*
X85948Y339737D01*
X85679Y339530D01*
X85296Y339427D01*
X84913Y339530D01*
X84644Y339737D01*
X84414Y340047D01*
X84261Y340409D01*
X84184Y340822D01*
Y341184D01*
X84261Y341494D01*
X84414Y341855D01*
X84644Y342165D01*
X84874Y342372D01*
X85181Y342527D01*
X85449D01*
X85756Y342424D01*
X85986Y342217D01*
G01X92148Y339427D02*
X90614D01*
Y342527D01*
X92148D01*
G01X91534Y341029D02*
X90614D01*
G01X93599Y339427D02*
Y342527D01*
X95363Y339427D01*
Y342527D01*
G01X96623Y339427D02*
X97581Y342527D01*
X98539Y339427D01*
G01X98194Y340512D02*
X96968D01*
G01X100988Y341080D02*
X101141Y341235D01*
X101256Y341494D01*
X101333Y341855D01*
X101256Y342165D01*
X101103Y342372D01*
X100834Y342527D01*
X99799D01*
Y339427D01*
X101064D01*
X101333Y339634D01*
X101486Y339944D01*
X101563Y340305D01*
X101486Y340667D01*
X101256Y340977D01*
X100988Y341080D01*
X99799D01*
G01X103014Y342527D02*
Y339427D01*
X104548D01*
G01X107648D02*
X106114D01*
Y342527D01*
X107648D01*
G01X107034Y341029D02*
X106114D01*
G01X112314Y340047D02*
X112506Y339737D01*
X112736Y339530D01*
X113004Y339427D01*
X113311Y339530D01*
X113541Y339737D01*
X113771Y340047D01*
X113848Y340460D01*
Y342527D01*
G01X115338D02*
Y340305D01*
X115491Y339840D01*
X115798Y339530D01*
X116181Y339427D01*
X116564Y339530D01*
X116871Y339840D01*
X117024Y340305D01*
Y342527D01*
G01X118284Y339427D02*
Y342527D01*
X119281Y339944D01*
X120278Y342527D01*
Y339427D01*
G01X121614D02*
Y342527D01*
X122534D01*
X122841Y342372D01*
X123071Y342010D01*
X123148Y341597D01*
X123071Y341184D01*
X122879Y340874D01*
X122534Y340719D01*
X121614D01*
G01X126248Y339427D02*
X124714D01*
Y342527D01*
X126248D01*
G01X125634Y341029D02*
X124714D01*
G01X127814Y339427D02*
Y342527D01*
X128773D01*
X129079Y342372D01*
X129271Y342165D01*
X129348Y341752D01*
X129271Y341339D01*
X129041Y341080D01*
X128773Y340925D01*
X127814D01*
G01X128773D02*
X129348Y339427D01*
G01X69281Y368012D02*
Y361812D01*
G01X69413Y373315D02*
X69573Y373565D01*
X69760Y373690D01*
X69973Y373732D01*
X70240Y373649D01*
X70427Y373440D01*
X70480Y373190D01*
X70453Y372940D01*
X70347Y372732D01*
X69813Y372315D01*
X69573Y372024D01*
X69413Y371607D01*
X69360Y371232D01*
X70480D01*
G01X72120D02*
Y373732D01*
X71800Y373232D01*
G01Y371232D02*
X72440D01*
G01X80274Y383819D02*
X86474D01*
G01X80274Y380619D02*
Y383819D01*
G01X86474Y380619D02*
X80274D01*
G01Y384902D02*
Y388102D01*
G01X86474Y384902D02*
X80274D01*
G01Y388102D02*
X86474D01*
G01X80291Y374426D02*
Y377626D01*
G01X86491Y374426D02*
X80291D01*
G01Y377626D02*
X86491D01*
G01X71843Y378205D02*
X72003Y378455D01*
X72190Y378580D01*
X72403Y378622D01*
X72670Y378539D01*
X72857Y378330D01*
X72910Y378080D01*
X72883Y377830D01*
X72777Y377622D01*
X72243Y377205D01*
X72003Y376914D01*
X71843Y376497D01*
X71790Y376122D01*
X72910D01*
G01X74043Y378205D02*
X74203Y378455D01*
X74390Y378580D01*
X74603Y378622D01*
X74870Y378539D01*
X75057Y378330D01*
X75110Y378080D01*
X75083Y377830D01*
X74977Y377622D01*
X74443Y377205D01*
X74203Y376914D01*
X74043Y376497D01*
X73990Y376122D01*
X75110D01*
G01X80274Y392991D02*
X86474D01*
G01X80274Y389791D02*
Y392991D01*
G01X86474Y389791D02*
X80274D01*
G01Y397465D02*
X86474D01*
G01X80274Y394265D02*
Y397465D01*
G01X86474Y394265D02*
X80274D01*
G01X69717Y396605D02*
X69877Y396855D01*
X70064Y396980D01*
X70277Y397022D01*
X70544Y396939D01*
X70731Y396730D01*
X70784Y396480D01*
X70757Y396230D01*
X70651Y396022D01*
X70117Y395605D01*
X69877Y395314D01*
X69717Y394897D01*
X69664Y394522D01*
X70784D01*
G01X72424D02*
X72611Y394564D01*
X72824Y394689D01*
X72957Y394897D01*
X73011Y395189D01*
X72957Y395480D01*
X72797Y395730D01*
X72557Y395855D01*
X72291D01*
X72131Y395939D01*
X71997Y396147D01*
X71944Y396439D01*
X72024Y396730D01*
X72211Y396939D01*
X72424Y397022D01*
X72637Y396939D01*
X72824Y396730D01*
X72904Y396439D01*
X72851Y396147D01*
X72717Y395939D01*
X72557Y395855D01*
X72291D01*
X72051Y395730D01*
X71891Y395480D01*
X71837Y395189D01*
X71891Y394897D01*
X72024Y394689D01*
X72237Y394564D01*
X72424Y394522D01*
G01X71263Y405582D02*
Y403360D01*
X71416Y402895D01*
X71723Y402585D01*
X72106Y402482D01*
X72489Y402585D01*
X72796Y402895D01*
X72949Y403360D01*
Y405582D01*
G01X74478Y405065D02*
X74708Y405375D01*
X74976Y405530D01*
X75283Y405582D01*
X75666Y405479D01*
X75934Y405220D01*
X76011Y404910D01*
X75973Y404600D01*
X75819Y404342D01*
X75053Y403825D01*
X74708Y403464D01*
X74478Y402947D01*
X74401Y402482D01*
X76011D01*
G01X77578Y403774D02*
X77846Y404135D01*
X78076Y404342D01*
X78383Y404445D01*
X78651Y404342D01*
X78843Y404135D01*
X78996Y403825D01*
X79034Y403464D01*
X78996Y403154D01*
X78843Y402844D01*
X78613Y402585D01*
X78344Y402482D01*
X78038Y402585D01*
X77769Y402895D01*
X77616Y403360D01*
X77578Y403877D01*
X77654Y404549D01*
X77769Y404910D01*
X77961Y405272D01*
X78229Y405530D01*
X78498Y405582D01*
X78766Y405479D01*
X78958Y405220D01*
G01X81406Y402482D02*
X81674Y402534D01*
X81981Y402689D01*
X82173Y402947D01*
X82249Y403309D01*
X82173Y403670D01*
X81943Y403980D01*
X81598Y404135D01*
X81214D01*
X80984Y404239D01*
X80793Y404497D01*
X80716Y404859D01*
X80831Y405220D01*
X81099Y405479D01*
X81406Y405582D01*
X81713Y405479D01*
X81981Y405220D01*
X82096Y404859D01*
X82019Y404497D01*
X81828Y404239D01*
X81598Y404135D01*
X81214D01*
X80869Y403980D01*
X80639Y403670D01*
X80563Y403309D01*
X80639Y402947D01*
X80831Y402689D01*
X81138Y402534D01*
X81406Y402482D01*
G01X66874Y390301D02*
X68374D01*
G01X67923Y418603D02*
X71123D01*
G01Y412403D02*
X67923D01*
G01X71123Y418603D02*
Y412403D01*
G01X67923D02*
Y418603D01*
G01X70208Y425346D02*
Y422146D01*
G01X70533Y520013D02*
Y523213D01*
G01X76733Y520013D02*
X70533D01*
G01X76733Y523213D02*
Y520013D01*
G01X70533Y523213D02*
X76733D01*
G01X70533Y523913D02*
Y527113D01*
G01X76733Y523913D02*
X70533D01*
G01X76733Y527113D02*
Y523913D01*
G01X70533Y527113D02*
X76733D01*
G01X70533Y537713D02*
Y540913D01*
G01X76733Y537713D02*
X70533D01*
G01X76733Y540913D02*
Y537713D01*
G01X70533Y541613D02*
Y544813D01*
G01X76733Y541613D02*
X70533D01*
G01X76733Y544813D02*
Y541613D01*
G01X70533Y544813D02*
X76733D01*
G01X70533Y540913D02*
X76733D01*
G01X78487Y682219D02*
X78679Y681909D01*
X78909Y681702D01*
X79177Y681599D01*
X79484Y681702D01*
X79714Y681909D01*
X79944Y682219D01*
X80021Y682632D01*
Y684699D01*
G01X81511Y682219D02*
X81741Y681857D01*
X82047Y681651D01*
X82392Y681599D01*
X82699Y681651D01*
X83006Y681909D01*
X83197Y682219D01*
X83236Y682529D01*
X83159Y682891D01*
X82891Y683149D01*
X82622Y683252D01*
X82277D01*
G01X82622D02*
X82852Y683407D01*
X83044Y683666D01*
X83121Y683976D01*
X83044Y684286D01*
X82852Y684544D01*
X82507Y684699D01*
X82162Y684647D01*
X81817Y684441D01*
G01X84611Y682219D02*
X84841Y681857D01*
X85147Y681651D01*
X85492Y681599D01*
X85799Y681651D01*
X86106Y681909D01*
X86297Y682219D01*
X86336Y682529D01*
X86259Y682891D01*
X85991Y683149D01*
X85722Y683252D01*
X85377D01*
G01X85722D02*
X85952Y683407D01*
X86144Y683666D01*
X86221Y683976D01*
X86144Y684286D01*
X85952Y684544D01*
X85607Y684699D01*
X85262Y684647D01*
X84917Y684441D01*
G01X70179Y1322731D02*
Y1348321D01*
G01X74174Y1322731D02*
X70179D01*
G01Y1348321D02*
X74174D01*
G01X77978Y1413755D02*
Y1407555D01*
G01D02*
X74778D01*
G01D02*
Y1413755D01*
G01D02*
X77978D01*
G01X78778Y1407555D02*
Y1413755D01*
G01D02*
X81978D01*
G01Y1407555D02*
X78778D01*
G01X73978Y1413755D02*
Y1407555D01*
G01D02*
X70778D01*
G01D02*
Y1413755D01*
G01D02*
X73978D01*
G01X82339Y1415323D02*
X69661D01*
G01D02*
Y1430677D01*
G01X78100Y1435600D02*
Y1432400D01*
G01D02*
X71900D01*
G01D02*
Y1435600D01*
G01X69858Y1430677D02*
X82339D01*
G01X71900Y1435600D02*
X78100D01*
G01X82906Y1437188D02*
X71094D01*
G01D02*
Y1449812D01*
G01D02*
X82906D01*
G01X77972Y1459448D02*
X85099D01*
G01X83916Y1489905D02*
X79921D01*
G01X82099Y1481102D02*
X77972D01*
G01X79921Y1515495D02*
X83916D01*
G01X75048Y1519111D02*
X74255D01*
G01X75048Y1521711D02*
Y1519111D01*
G01X77723Y1534627D02*
X80923D01*
G01X77723Y1528427D02*
Y1534627D01*
G01X80923Y1528427D02*
X77723D01*
G01X80923Y1534627D02*
Y1528427D01*
G01X77096Y1547769D02*
Y1550969D01*
G01X83296Y1547769D02*
X77096D01*
G01Y1550969D02*
X83296D01*
G01X71168Y1551896D02*
X74368D01*
G01X71168Y1545696D02*
Y1551896D01*
G01X74368Y1545696D02*
X71168D01*
G01X74368Y1551896D02*
Y1545696D01*
G01X70368D02*
X67168D01*
G01X70368Y1551896D02*
Y1545696D01*
G01X67168Y1551896D02*
X70368D01*
G01X67168Y1545696D02*
Y1551896D01*
G01X81596Y1546469D02*
X87796D01*
G01X81596Y1543269D02*
Y1546469D01*
G01X86100Y1543269D02*
X81596D01*
G01X75048Y1542733D02*
Y1540542D01*
G01X74315Y1542733D02*
X75048D01*
G01X77168Y1562357D02*
Y1556357D01*
G01X75206Y1594807D02*
Y1601007D01*
G01X78406Y1594807D02*
X75206D01*
G01X78406Y1601007D02*
Y1594807D01*
G01X82606D02*
X79406D01*
G01D02*
Y1601007D01*
G01X69733Y1594996D02*
Y1588796D01*
G01X74260D02*
X71060D01*
G01X74260Y1594996D02*
Y1588796D01*
G01X71060Y1594996D02*
X74260D01*
G01X71060Y1588796D02*
Y1594996D01*
G01X82319Y1578894D02*
Y1583021D01*
X79319Y1586021D01*
G01X75206Y1601007D02*
X78406D01*
G01X79406D02*
X82606D01*
G01X76806Y1609307D02*
X80006D01*
G01X76806Y1603107D02*
Y1609307D01*
G01X80006Y1603107D02*
X76806D01*
G01X80006Y1609307D02*
Y1603107D01*
G01X84206D02*
X81006D01*
G01Y1609307D02*
X84206D01*
G01X81006Y1603107D02*
Y1609307D01*
G01X77533Y1610296D02*
Y1613496D01*
G01X83733Y1610296D02*
X77533D01*
G01X75890Y1603000D02*
X73390D01*
X73890Y1602680D01*
G01X75890D02*
Y1603320D01*
G01Y1605200D02*
X73390D01*
X73890Y1604880D01*
G01X75890D02*
Y1605520D01*
G01X68144Y1602628D02*
Y1605128D01*
X67824Y1604628D01*
G01Y1602628D02*
X68464D01*
G01X70344Y1605128D02*
X70131Y1605045D01*
X69971Y1604836D01*
X69864Y1604586D01*
X69784Y1604253D01*
X69757Y1603878D01*
X69784Y1603503D01*
X69864Y1603170D01*
X69971Y1602920D01*
X70131Y1602711D01*
X70344Y1602628D01*
X70557Y1602711D01*
X70717Y1602920D01*
X70824Y1603170D01*
X70904Y1603503D01*
X70931Y1603878D01*
X70904Y1604253D01*
X70824Y1604586D01*
X70717Y1604836D01*
X70557Y1605045D01*
X70344Y1605128D01*
G01X69610Y1605562D02*
X67714D01*
G01X69610Y1607468D02*
Y1605562D01*
G01X66867Y1601005D02*
Y1604005D01*
G01X77533Y1623796D02*
Y1626996D01*
G01X83733Y1623796D02*
X77533D01*
G01Y1622496D02*
X83733D01*
G01X77533Y1619296D02*
Y1622496D01*
G01X83733Y1619296D02*
X77533D01*
G01Y1613496D02*
X83733D01*
G01X77533Y1617996D02*
X83733D01*
G01X77533Y1614796D02*
Y1617996D01*
G01X83733Y1614796D02*
X77533D01*
G01X68908Y1627970D02*
X69068Y1628220D01*
X69255Y1628345D01*
X69468Y1628387D01*
X69735Y1628304D01*
X69922Y1628095D01*
X69975Y1627845D01*
X69948Y1627595D01*
X69842Y1627387D01*
X69308Y1626970D01*
X69068Y1626679D01*
X68908Y1626262D01*
X68855Y1625887D01*
X69975D01*
G01X71615D02*
Y1628387D01*
X71295Y1627887D01*
G01Y1625887D02*
X71935D01*
G01X72832Y1622987D02*
X72582Y1623147D01*
X72457Y1623334D01*
X72415Y1623547D01*
X72498Y1623814D01*
X72707Y1624001D01*
X72957Y1624054D01*
X73207Y1624027D01*
X73415Y1623921D01*
X73832Y1623387D01*
X74123Y1623147D01*
X74540Y1622987D01*
X74915Y1622934D01*
Y1624054D01*
G01X72415Y1625694D02*
X72498Y1625481D01*
X72707Y1625321D01*
X72957Y1625214D01*
X73290Y1625134D01*
X73665Y1625107D01*
X74040Y1625134D01*
X74373Y1625214D01*
X74623Y1625321D01*
X74832Y1625481D01*
X74915Y1625694D01*
X74832Y1625907D01*
X74623Y1626067D01*
X74373Y1626174D01*
X74040Y1626254D01*
X73665Y1626281D01*
X73290Y1626254D01*
X72957Y1626174D01*
X72707Y1626067D01*
X72498Y1625907D01*
X72415Y1625694D01*
G01X69610Y1625248D02*
Y1623342D01*
G01X67704Y1625248D02*
X69610D01*
G01X74067Y1622405D02*
X71067D01*
G01X71117Y1614605D02*
X72617D01*
G01X71733Y1631996D02*
Y1628796D01*
G01X75267Y1636505D02*
Y1633305D01*
G01X69067Y1636505D02*
X75267D01*
G01X69067Y1633305D02*
Y1636505D01*
G01X75267Y1633305D02*
X69067D01*
G01X77533Y1626996D02*
X83733D01*
G01X71827Y1645287D02*
Y1651487D01*
G01X75027D02*
Y1645287D01*
G01X71827Y1651487D02*
X75027D01*
G01Y1645287D02*
X71827D01*
G01X66827Y1651487D02*
X70027D01*
G01X66827Y1645287D02*
Y1651487D01*
G01X70027Y1645287D02*
X66827D01*
G01X70027Y1651487D02*
Y1645287D01*
G01X75827Y1651487D02*
X79027D01*
G01Y1645287D02*
X75827D01*
G01X79027Y1651487D02*
Y1645287D01*
G01X75827D02*
Y1651487D01*
G01X73517Y1659880D02*
Y1657809D01*
G01D02*
X71446D01*
G01X80527Y1680287D02*
Y1686487D01*
G01X83727Y1680287D02*
X80527D01*
G01X67727Y1686487D02*
Y1680287D01*
G01X79727D02*
X76527D01*
G01X79727Y1686487D02*
Y1680287D01*
G01X76527D02*
Y1686487D01*
G01X71727Y1680287D02*
X68527D01*
G01X71727Y1686487D02*
Y1680287D01*
G01X68527D02*
Y1686487D01*
G01X75727Y1680287D02*
X72527D01*
G01X75727Y1686487D02*
Y1680287D01*
G01X72527D02*
Y1686487D01*
G01X71446Y1673951D02*
X73517D01*
G01D02*
Y1671880D01*
G01X80527Y1686487D02*
X83727D01*
G01X76527D02*
X79727D01*
G01X68527D02*
X71727D01*
G01X72527D02*
X75727D01*
G01X70911Y1729977D02*
Y1733077D01*
G01X72521D02*
Y1729977D01*
G01Y1731527D02*
X70911D01*
G01X74164Y1730339D02*
X74433Y1730080D01*
X74739Y1729977D01*
X75046Y1730080D01*
X75314Y1730390D01*
X75506Y1730855D01*
X75583Y1731320D01*
Y1731889D01*
X75506Y1732354D01*
X75314Y1732767D01*
X75084Y1732974D01*
X74816Y1733077D01*
X74509Y1732974D01*
X74279Y1732767D01*
X74126Y1732457D01*
X74049Y1732044D01*
X74126Y1731682D01*
X74318Y1731320D01*
X74548Y1731114D01*
X74816Y1731062D01*
X75123Y1731165D01*
X75353Y1731424D01*
X75583Y1731889D01*
G01X77839Y1729977D02*
X77916Y1730649D01*
X78031Y1731217D01*
X78184Y1731734D01*
X78376Y1732302D01*
X78683Y1733077D01*
X77149D01*
G01X95500Y51142D02*
X92000D01*
G01X88000D02*
X85000D01*
G01X93601Y142550D02*
Y139350D01*
G01X87401Y142550D02*
X93601D01*
G01X87401Y139350D02*
Y142550D01*
G01X93601Y139350D02*
X87401D01*
G01X86701Y142550D02*
Y139350D01*
G01X85548Y162697D02*
X87501D01*
G01X95407D02*
X97360D01*
G01X85548Y160744D02*
Y162697D01*
G01Y150885D02*
Y152838D01*
G01X87501Y150885D02*
X85548D01*
G01X97360D02*
X95407D01*
G01X86474Y383819D02*
Y380619D01*
G01Y388102D02*
Y384902D01*
G01X86491Y377626D02*
Y374426D01*
G01X86474Y392991D02*
Y389791D01*
G01Y397465D02*
Y394265D01*
G01X140833Y605376D02*
G02I-22900J0D01*
G01X96138Y682634D02*
X96330Y682324D01*
X96560Y682117D01*
X96828Y682014D01*
X97135Y682117D01*
X97365Y682324D01*
X97595Y682634D01*
X97672Y683047D01*
Y685114D01*
G01X99162Y682634D02*
X99392Y682272D01*
X99698Y682066D01*
X100043Y682014D01*
X100350Y682066D01*
X100657Y682324D01*
X100848Y682634D01*
X100887Y682944D01*
X100810Y683306D01*
X100542Y683564D01*
X100273Y683667D01*
X99928D01*
G01X100273D02*
X100503Y683822D01*
X100695Y684081D01*
X100772Y684391D01*
X100695Y684701D01*
X100503Y684959D01*
X100158Y685114D01*
X99813Y685062D01*
X99468Y684856D01*
G01X102377Y684597D02*
X102607Y684907D01*
X102875Y685062D01*
X103182Y685114D01*
X103565Y685011D01*
X103833Y684752D01*
X103910Y684442D01*
X103872Y684132D01*
X103718Y683874D01*
X102952Y683357D01*
X102607Y682996D01*
X102377Y682479D01*
X102300Y682014D01*
X103910D01*
G01X94300Y687245D02*
Y1303000D01*
G01X119890Y687245D02*
X94300D01*
G01X90189Y1303000D02*
Y687245D01*
G01X119890Y720710D02*
X94300D01*
G01X119890Y1291576D02*
X94300D01*
G01X95758Y1306501D02*
X92558D01*
G01X95758Y1312701D02*
Y1306501D01*
G01X92558Y1312701D02*
X95758D01*
G01X92558Y1306501D02*
Y1312701D01*
G01X85455Y1305899D02*
Y1309099D01*
G01X91655Y1305899D02*
X85455D01*
G01X91655Y1309099D02*
Y1305899D01*
G01X85455Y1309099D02*
X91655D01*
G01X85475Y1310019D02*
Y1313219D01*
G01X91675Y1310019D02*
X85475D01*
G01X91675Y1313219D02*
Y1310019D01*
G01X85475Y1313219D02*
X91675D01*
G01X95769Y1322731D02*
X91774D01*
G01X95769Y1348321D02*
Y1322731D01*
G01X94958Y1354816D02*
X101158D01*
G01X94958Y1351616D02*
Y1354816D01*
G01X101158Y1351616D02*
X94958D01*
G01X99724Y1355116D02*
X96524D01*
G01D02*
Y1361316D01*
G01X91774Y1348321D02*
X95769D01*
G01X83535Y1352550D02*
Y1355650D01*
G01X85145D02*
Y1352550D01*
G01Y1354100D02*
X83535D01*
G01X87440Y1352550D02*
Y1355650D01*
X86980Y1355030D01*
G01Y1352550D02*
X87900D01*
G01X90540D02*
Y1355650D01*
X90080Y1355030D01*
G01Y1352550D02*
X91000D01*
G01X99701Y1372437D02*
X96501D01*
G01D02*
Y1378637D01*
G01Y1368137D02*
X99701D01*
G01X96501Y1361937D02*
Y1368137D01*
G01X99701Y1361937D02*
X96501D01*
G01X96524Y1361316D02*
X99724D01*
G01X96501Y1378637D02*
X99701D01*
G01X92201Y1381189D02*
X89001D01*
G01X92201Y1387389D02*
Y1381189D01*
G01X89001Y1387389D02*
X92201D01*
G01X89001Y1381189D02*
Y1387389D01*
G01X96313Y1381237D02*
X93113D01*
G01X96313Y1387437D02*
Y1381237D01*
G01X93113Y1387437D02*
X96313D01*
G01X93113Y1381237D02*
Y1387437D01*
G01X91600Y1415400D02*
X85400D01*
G01X91600Y1418600D02*
Y1415400D01*
G01X85400D02*
Y1418600D01*
G01X91600Y1410900D02*
X85400D01*
G01Y1414100D02*
X91600D01*
G01D02*
Y1410900D01*
G01X85400D02*
Y1414100D01*
G01X94400D02*
X100600D01*
G01Y1410900D02*
X94400D01*
G01D02*
Y1414100D01*
G01Y1409600D02*
X100600D01*
G01Y1406400D02*
X94400D01*
G01D02*
Y1409600D01*
G01X91600Y1406400D02*
X85400D01*
G01Y1409600D02*
X91600D01*
G01D02*
Y1406400D01*
G01X85400D02*
Y1409600D01*
G01X81978Y1413755D02*
Y1407555D01*
G01X94400Y1415400D02*
Y1418600D01*
G01X100600Y1415400D02*
X94400D01*
G01X82339Y1430677D02*
Y1415323D01*
G01X91600Y1419900D02*
X85400D01*
G01Y1423100D02*
X91600D01*
G01D02*
Y1419900D01*
G01X85400D02*
Y1423100D01*
G01Y1418600D02*
X91600D01*
G01X100600Y1424400D02*
X94400D01*
G01D02*
Y1427600D01*
G01D02*
X100600D01*
G01Y1428900D02*
X94400D01*
G01D02*
Y1432100D01*
G01D02*
X100600D01*
G01X94400Y1418600D02*
X100600D01*
G01X94400Y1419900D02*
Y1423100D01*
G01X100600Y1419900D02*
X94400D01*
G01Y1423100D02*
X100600D01*
G01Y1438400D02*
X94400D01*
G01D02*
Y1441600D01*
G01D02*
X100600D01*
G01Y1433900D02*
X94400D01*
G01D02*
Y1437100D01*
G01D02*
X100600D01*
G01X91600Y1433900D02*
X85400D01*
G01D02*
Y1437100D01*
G01D02*
X91600D01*
G01D02*
Y1433900D01*
G01X100600Y1446900D02*
X94400D01*
G01D02*
Y1450100D01*
G01Y1446100D02*
X100600D01*
G01Y1442900D02*
X94400D01*
G01D02*
Y1446100D01*
G01X91600Y1446900D02*
X85400D01*
G01D02*
Y1450100D01*
G01X91600D02*
Y1446900D01*
G01Y1441600D02*
Y1438400D01*
G01D02*
X85400D01*
G01D02*
Y1441600D01*
G01D02*
X91600D01*
G01Y1446100D02*
Y1442900D01*
G01D02*
X85400D01*
G01Y1446100D02*
X91600D01*
G01X85400Y1442900D02*
Y1446100D01*
G01X82906Y1449812D02*
Y1437188D01*
G01X94400Y1450100D02*
X100600D01*
G01X85400D02*
X91600D01*
G01X89883Y1451000D02*
Y1454100D01*
X90803D01*
X91110Y1453945D01*
X91340Y1453583D01*
X91417Y1453170D01*
X91340Y1452757D01*
X91148Y1452447D01*
X90803Y1452292D01*
X89883D01*
G01X94593Y1453842D02*
X94363Y1453997D01*
X94095Y1454100D01*
X93788D01*
X93443Y1453945D01*
X93175Y1453687D01*
X92983Y1453377D01*
X92830Y1452860D01*
X92792Y1452395D01*
X92868Y1451930D01*
X92983Y1451620D01*
X93213Y1451310D01*
X93482Y1451103D01*
X93750Y1451000D01*
X94018D01*
X94287Y1451103D01*
X94517Y1451258D01*
X94708Y1451465D01*
G01X96122Y1452292D02*
X96390Y1452653D01*
X96620Y1452860D01*
X96927Y1452963D01*
X97195Y1452860D01*
X97387Y1452653D01*
X97540Y1452343D01*
X97578Y1451982D01*
X97540Y1451672D01*
X97387Y1451362D01*
X97157Y1451103D01*
X96888Y1451000D01*
X96582Y1451103D01*
X96313Y1451413D01*
X96160Y1451878D01*
X96122Y1452395D01*
X96198Y1453067D01*
X96313Y1453428D01*
X96505Y1453790D01*
X96773Y1454048D01*
X97042Y1454100D01*
X97310Y1453997D01*
X97502Y1453738D01*
G01X99222Y1452292D02*
X99490Y1452653D01*
X99720Y1452860D01*
X100027Y1452963D01*
X100295Y1452860D01*
X100487Y1452653D01*
X100640Y1452343D01*
X100678Y1451982D01*
X100640Y1451672D01*
X100487Y1451362D01*
X100257Y1451103D01*
X99988Y1451000D01*
X99682Y1451103D01*
X99413Y1451413D01*
X99260Y1451878D01*
X99222Y1452395D01*
X99298Y1453067D01*
X99413Y1453428D01*
X99605Y1453790D01*
X99873Y1454048D01*
X100142Y1454100D01*
X100410Y1453997D01*
X100602Y1453738D01*
G01X102207Y1451620D02*
X102437Y1451258D01*
X102743Y1451052D01*
X103088Y1451000D01*
X103395Y1451052D01*
X103702Y1451310D01*
X103893Y1451620D01*
X103932Y1451930D01*
X103855Y1452292D01*
X103587Y1452550D01*
X103318Y1452653D01*
X102973D01*
G01X103318D02*
X103548Y1452808D01*
X103740Y1453067D01*
X103817Y1453377D01*
X103740Y1453687D01*
X103548Y1453945D01*
X103203Y1454100D01*
X102858Y1454048D01*
X102513Y1453842D01*
G01X106150Y1451000D02*
Y1454100D01*
X105690Y1453480D01*
G01Y1451000D02*
X106610D01*
G01X87445Y1459448D02*
X94572D01*
G01X87445Y1478102D02*
Y1459448D01*
G01X85099D02*
Y1478102D01*
G01X86901Y1489905D02*
Y1515495D01*
G01X90896Y1489905D02*
X86901D01*
G01X83916Y1515495D02*
Y1489905D01*
G01X90445Y1481102D02*
X87445Y1478102D01*
G01X94572Y1481102D02*
X90445D01*
G01X85099Y1478102D02*
X82099Y1481102D01*
G01X89005Y1520935D02*
Y1517735D01*
G01X82805Y1520935D02*
X89005D01*
G01X82805Y1517735D02*
Y1520935D01*
G01X89005Y1517735D02*
X82805D01*
G01X86005Y1521735D02*
X82805D01*
G01X86005Y1527935D02*
Y1521735D01*
G01X82805D02*
Y1527935D01*
G01X86901Y1515495D02*
X90896D01*
G01X91105Y1519111D02*
Y1521711D01*
G01X91898Y1519111D02*
X91105D01*
G01X84774Y1535271D02*
X87974D01*
G01X84774Y1529071D02*
Y1535271D01*
G01X87974Y1529071D02*
X84774D01*
G01X87974Y1535271D02*
Y1529071D01*
G01Y1536071D02*
X84774D01*
G01D02*
Y1542271D01*
G01X87974Y1541000D02*
Y1536071D01*
G01X82805Y1527935D02*
X86005D01*
G01X91105Y1528322D02*
Y1530020D01*
G01X83296Y1550969D02*
Y1547769D01*
G01X84774Y1542271D02*
X85500D01*
G01X90296Y1550969D02*
Y1547769D01*
G01X84096Y1550969D02*
X90296D01*
G01X84096Y1547769D02*
Y1550969D01*
G01X90296Y1547769D02*
X84096D01*
G01X87796Y1546469D02*
Y1545000D01*
G01X93911Y1551196D02*
Y1554396D01*
G01X100111Y1551196D02*
X93911D01*
G01X91105Y1542733D02*
X92113D01*
G01X91105Y1540879D02*
Y1542733D01*
G01X93911Y1554396D02*
X100111D01*
G01X89383Y1569500D02*
Y1572600D01*
X90303D01*
X90610Y1572445D01*
X90840Y1572083D01*
X90917Y1571670D01*
X90840Y1571257D01*
X90648Y1570947D01*
X90303Y1570792D01*
X89383D01*
G01X92483Y1572600D02*
Y1569500D01*
X94017D01*
G01X95622Y1570792D02*
X95890Y1571153D01*
X96120Y1571360D01*
X96427Y1571463D01*
X96695Y1571360D01*
X96887Y1571153D01*
X97040Y1570843D01*
X97078Y1570482D01*
X97040Y1570172D01*
X96887Y1569862D01*
X96657Y1569603D01*
X96388Y1569500D01*
X96082Y1569603D01*
X95813Y1569913D01*
X95660Y1570378D01*
X95622Y1570895D01*
X95698Y1571567D01*
X95813Y1571928D01*
X96005Y1572290D01*
X96273Y1572548D01*
X96542Y1572600D01*
X96810Y1572497D01*
X97002Y1572238D01*
G01X98607Y1569965D02*
X98837Y1569707D01*
X99105Y1569552D01*
X99450Y1569500D01*
X99795Y1569603D01*
X100063Y1569810D01*
X100255Y1570172D01*
X100293Y1570585D01*
X100217Y1570998D01*
X100025Y1571257D01*
X99757Y1571463D01*
X99488Y1571515D01*
X99220Y1571463D01*
X98875Y1571257D01*
X98990Y1572600D01*
X100025D01*
G01X102550Y1569500D02*
Y1572600D01*
X102090Y1571980D01*
G01Y1569500D02*
X103010D01*
G01X105650Y1572600D02*
X105343Y1572497D01*
X105113Y1572238D01*
X104960Y1571928D01*
X104845Y1571515D01*
X104807Y1571050D01*
X104845Y1570585D01*
X104960Y1570172D01*
X105113Y1569862D01*
X105343Y1569603D01*
X105650Y1569500D01*
X105957Y1569603D01*
X106187Y1569862D01*
X106340Y1570172D01*
X106455Y1570585D01*
X106493Y1571050D01*
X106455Y1571515D01*
X106340Y1571928D01*
X106187Y1572238D01*
X105957Y1572497D01*
X105650Y1572600D01*
G01X88619Y1576181D02*
Y1593897D01*
G01X92027Y1576181D02*
X88619D01*
G01X82606Y1601007D02*
Y1594807D01*
G01X88619Y1593897D02*
X92027D01*
G01X84206Y1609307D02*
Y1603107D01*
G01X83733Y1613496D02*
Y1610296D01*
G01Y1626996D02*
Y1623796D01*
G01Y1622496D02*
Y1619296D01*
G01Y1617996D02*
Y1614796D01*
G01X82383Y1661538D02*
Y1664738D01*
G01X88583Y1661538D02*
X82383D01*
G01X88583Y1664738D02*
Y1661538D01*
G01X82383Y1664738D02*
X88583D01*
G01X82342Y1665527D02*
Y1668727D01*
G01X88542Y1665527D02*
X82342D01*
G01X88542Y1668727D02*
Y1665527D01*
G01X82342Y1668727D02*
X88542D01*
G01X88527Y1680287D02*
Y1686487D01*
G01X91727Y1680287D02*
X88527D01*
G01X91727Y1686487D02*
Y1680287D01*
G01X83727Y1686487D02*
Y1680287D01*
G01X87727D02*
X84527D01*
G01X87727Y1686487D02*
Y1680287D01*
G01X84527D02*
Y1686487D01*
G01X88527D02*
X91727D01*
G01X84527D02*
X87727D01*
G01X90900Y1697350D02*
Y1703550D01*
G01X94100Y1697350D02*
X90900D01*
G01X94100Y1703550D02*
Y1697350D01*
G01X90020Y1704111D02*
Y1700911D01*
G01D02*
X83820D01*
G01D02*
Y1704111D01*
G01Y1700111D02*
X90020D01*
G01D02*
Y1696911D01*
G01D02*
X83820D01*
G01D02*
Y1700111D01*
G01X96867Y1714641D02*
X90667D01*
G01D02*
Y1717841D01*
G01X83820Y1708111D02*
X90020D01*
G01Y1704911D02*
X83820D01*
G01D02*
Y1708111D01*
G01X90020D02*
Y1704911D01*
G01X90900Y1703550D02*
X94100D01*
G01X83820Y1704111D02*
X90020D01*
G01X89857Y1717931D02*
Y1714731D01*
G01D02*
X83657D01*
G01D02*
Y1717931D01*
G01X92858Y1712411D02*
Y1710189D01*
X93011Y1709724D01*
X93318Y1709414D01*
X93701Y1709311D01*
X94084Y1709414D01*
X94391Y1709724D01*
X94544Y1710189D01*
Y1712411D01*
G01X96801Y1709311D02*
Y1712411D01*
X96341Y1711791D01*
G01Y1709311D02*
X97261D01*
G01X99249Y1709673D02*
X99518Y1709414D01*
X99824Y1709311D01*
X100131Y1709414D01*
X100399Y1709724D01*
X100591Y1710189D01*
X100668Y1710654D01*
Y1711223D01*
X100591Y1711688D01*
X100399Y1712101D01*
X100169Y1712308D01*
X99901Y1712411D01*
X99594Y1712308D01*
X99364Y1712101D01*
X99211Y1711791D01*
X99134Y1711378D01*
X99211Y1711016D01*
X99403Y1710654D01*
X99633Y1710448D01*
X99901Y1710396D01*
X100208Y1710499D01*
X100438Y1710758D01*
X100668Y1711223D01*
G01X103461Y1709311D02*
Y1712411D01*
X102043Y1710189D01*
X103959D01*
G01X90667Y1717841D02*
X96867D01*
G01X89857Y1725931D02*
Y1722731D01*
G01X83657Y1725931D02*
X89857D01*
G01Y1722731D02*
X83657D01*
G01D02*
Y1725931D01*
G01X89857Y1721931D02*
Y1718731D01*
G01X83657Y1721931D02*
X89857D01*
G01Y1718731D02*
X83657D01*
G01D02*
Y1721931D01*
G01Y1717931D02*
X89857D01*
G01X90657Y1725931D02*
X93857D01*
G01D02*
Y1719731D01*
G01D02*
X90657D01*
G01D02*
Y1725931D01*
G01X110000Y51142D02*
X108000D01*
G01X102500D02*
X100000D01*
G01X100154Y152091D02*
Y155291D01*
G01X106354Y152091D02*
X100154D01*
G01X106354Y155291D02*
Y152091D01*
G01X100154Y155291D02*
X106354D01*
G01X100154Y156591D02*
Y159791D01*
G01X106354Y156591D02*
X100154D01*
G01X106354Y159791D02*
Y156591D01*
G01X100154Y159791D02*
X106354D01*
G01X97360Y162697D02*
Y160744D01*
G01Y152838D02*
Y150885D01*
G01X120739Y193954D02*
X107353D01*
G01D02*
Y195191D01*
G01Y209291D02*
Y210191D01*
G01Y204291D02*
Y205191D01*
G01Y199291D02*
Y200191D01*
G01X106179Y217728D02*
X106371Y217418D01*
X106601Y217211D01*
X106869Y217108D01*
X107176Y217211D01*
X107406Y217418D01*
X107636Y217728D01*
X107713Y218141D01*
Y220208D01*
G01X110506Y217108D02*
Y220208D01*
X109088Y217986D01*
X111004D01*
G01X112494Y217470D02*
X112763Y217211D01*
X113069Y217108D01*
X113376Y217211D01*
X113644Y217521D01*
X113836Y217986D01*
X113913Y218451D01*
Y219020D01*
X113836Y219485D01*
X113644Y219898D01*
X113414Y220105D01*
X113146Y220208D01*
X112839Y220105D01*
X112609Y219898D01*
X112456Y219588D01*
X112379Y219175D01*
X112456Y218813D01*
X112648Y218451D01*
X112878Y218245D01*
X113146Y218193D01*
X113453Y218296D01*
X113683Y218555D01*
X113913Y219020D01*
G01X107353Y215528D02*
X120739D01*
G01X107353Y214291D02*
Y215528D01*
G01X104926Y294743D02*
Y284901D01*
G01Y315177D02*
Y305335D01*
G01X98301Y1306708D02*
Y1350016D01*
G01X103642Y1306708D02*
X98301D01*
G01X101158Y1354816D02*
Y1351616D01*
G01X99724Y1361316D02*
Y1355116D01*
G01X102758Y1353233D02*
Y1355833D01*
G01X103551Y1353233D02*
X102758D01*
G01X98301Y1350016D02*
X103642D01*
G01X99701Y1374300D02*
Y1372437D01*
G01Y1368137D02*
Y1361937D01*
G01X102758Y1362444D02*
Y1364142D01*
G01X99701Y1378637D02*
Y1377500D01*
G01X103595Y1381068D02*
X100395D01*
G01X103595Y1387268D02*
Y1381068D01*
G01X100395Y1387268D02*
X103595D01*
G01X100395Y1381068D02*
Y1387268D01*
G01X104365Y1383962D02*
Y1387162D01*
G01X110565Y1383962D02*
X104365D01*
G01X110565Y1387162D02*
Y1383962D01*
G01X104365Y1387162D02*
X110565D01*
G01X102758Y1376855D02*
X103766D01*
G01X102758Y1375001D02*
Y1376855D01*
G01X100883Y1394000D02*
Y1397100D01*
X101803D01*
X102110Y1396945D01*
X102340Y1396583D01*
X102417Y1396170D01*
X102340Y1395757D01*
X102148Y1395447D01*
X101803Y1395292D01*
X100883D01*
G01X103907Y1397100D02*
Y1394878D01*
X104060Y1394413D01*
X104367Y1394103D01*
X104750Y1394000D01*
X105133Y1394103D01*
X105440Y1394413D01*
X105593Y1394878D01*
Y1397100D01*
G01X107007Y1394465D02*
X107237Y1394207D01*
X107505Y1394052D01*
X107850Y1394000D01*
X108195Y1394103D01*
X108463Y1394310D01*
X108655Y1394672D01*
X108693Y1395085D01*
X108617Y1395498D01*
X108425Y1395757D01*
X108157Y1395963D01*
X107888Y1396015D01*
X107620Y1395963D01*
X107275Y1395757D01*
X107390Y1397100D01*
X108425D01*
G01X110107Y1394620D02*
X110337Y1394258D01*
X110643Y1394052D01*
X110988Y1394000D01*
X111295Y1394052D01*
X111602Y1394310D01*
X111793Y1394620D01*
X111832Y1394930D01*
X111755Y1395292D01*
X111487Y1395550D01*
X111218Y1395653D01*
X110873D01*
G01X111218D02*
X111448Y1395808D01*
X111640Y1396067D01*
X111717Y1396377D01*
X111640Y1396687D01*
X111448Y1396945D01*
X111103Y1397100D01*
X110758Y1397048D01*
X110413Y1396842D01*
G01X100684Y1389516D02*
Y1392616D01*
X101604D01*
X101911Y1392461D01*
X102141Y1392099D01*
X102218Y1391686D01*
X102141Y1391273D01*
X101949Y1390963D01*
X101604Y1390808D01*
X100684D01*
G01X103784Y1392616D02*
Y1389516D01*
X105318D01*
G01X106923Y1390808D02*
X107191Y1391169D01*
X107421Y1391376D01*
X107728Y1391479D01*
X107996Y1391376D01*
X108188Y1391169D01*
X108341Y1390859D01*
X108379Y1390498D01*
X108341Y1390188D01*
X108188Y1389878D01*
X107958Y1389619D01*
X107689Y1389516D01*
X107383Y1389619D01*
X107114Y1389929D01*
X106961Y1390394D01*
X106923Y1390911D01*
X106999Y1391583D01*
X107114Y1391944D01*
X107306Y1392306D01*
X107574Y1392564D01*
X107843Y1392616D01*
X108111Y1392513D01*
X108303Y1392254D01*
G01X110674Y1389516D02*
X110751Y1390188D01*
X110866Y1390756D01*
X111019Y1391273D01*
X111211Y1391841D01*
X111518Y1392616D01*
X109984D01*
G01X105400Y1416100D02*
X111600D01*
G01Y1412900D02*
X105400D01*
G01D02*
Y1416100D01*
G01Y1405900D02*
Y1412100D01*
G01X108600D02*
Y1405900D01*
G01D02*
X105400D01*
G01Y1412100D02*
X108600D01*
G01X100600Y1414100D02*
Y1410900D01*
G01Y1409600D02*
Y1406400D01*
G01Y1418600D02*
Y1415400D01*
G01X110899Y1417110D02*
Y1420210D01*
X111819D01*
X112126Y1420055D01*
X112356Y1419693D01*
X112433Y1419280D01*
X112356Y1418867D01*
X112164Y1418557D01*
X111819Y1418402D01*
X110899D01*
G01X113923Y1420210D02*
Y1417988D01*
X114076Y1417523D01*
X114383Y1417213D01*
X114766Y1417110D01*
X115149Y1417213D01*
X115456Y1417523D01*
X115609Y1417988D01*
Y1420210D01*
G01X117023Y1417730D02*
X117253Y1417368D01*
X117559Y1417162D01*
X117904Y1417110D01*
X118211Y1417162D01*
X118518Y1417420D01*
X118709Y1417730D01*
X118748Y1418040D01*
X118671Y1418402D01*
X118403Y1418660D01*
X118134Y1418763D01*
X117789D01*
G01X118134D02*
X118364Y1418918D01*
X118556Y1419177D01*
X118633Y1419487D01*
X118556Y1419797D01*
X118364Y1420055D01*
X118019Y1420210D01*
X117674Y1420158D01*
X117329Y1419952D01*
G01X121426Y1417110D02*
Y1420210D01*
X120008Y1417988D01*
X121924D01*
G01X100600Y1427600D02*
Y1424400D01*
G01Y1432100D02*
Y1428900D01*
G01Y1423100D02*
Y1419900D01*
G01X110439Y1421591D02*
X108091D01*
G01D02*
Y1423939D01*
G01X100600Y1441600D02*
Y1438400D01*
G01Y1437100D02*
Y1433900D01*
G01Y1450100D02*
Y1446900D01*
G01Y1446100D02*
Y1442900D01*
G01X108091Y1443061D02*
Y1445409D01*
G01D02*
X110439D01*
G01X109099Y1459448D02*
Y1478102D01*
G01X101972Y1459448D02*
X109099D01*
G01X112491Y1489905D02*
X108496D01*
G01X106099Y1481102D02*
X101972D01*
G01X109099Y1478102D02*
X106099Y1481102D01*
G01X108496Y1515495D02*
X112491D01*
G01X110791Y1519111D02*
X109998D01*
G01X110791Y1521711D02*
Y1519111D01*
G01X106911Y1551596D02*
X110111D01*
G01X106911Y1545396D02*
Y1551596D01*
G01X110111Y1545396D02*
X106911D01*
G01X110111Y1551596D02*
Y1545396D01*
G01X106111D02*
X102911D01*
G01X106111Y1551596D02*
Y1545396D01*
G01X102911Y1551596D02*
X106111D01*
G01X102911Y1545396D02*
Y1551596D01*
G01X100111Y1554396D02*
Y1551196D01*
G01X111272Y1548558D02*
Y1551658D01*
X112192D01*
X112499Y1551503D01*
X112729Y1551141D01*
X112806Y1550728D01*
X112729Y1550315D01*
X112537Y1550005D01*
X112192Y1549850D01*
X111272D01*
G01X114296Y1551658D02*
Y1549436D01*
X114449Y1548971D01*
X114756Y1548661D01*
X115139Y1548558D01*
X115522Y1548661D01*
X115829Y1548971D01*
X115982Y1549436D01*
Y1551658D01*
G01X117511Y1549850D02*
X117779Y1550211D01*
X118009Y1550418D01*
X118316Y1550521D01*
X118584Y1550418D01*
X118776Y1550211D01*
X118929Y1549901D01*
X118967Y1549540D01*
X118929Y1549230D01*
X118776Y1548920D01*
X118546Y1548661D01*
X118277Y1548558D01*
X117971Y1548661D01*
X117702Y1548971D01*
X117549Y1549436D01*
X117511Y1549953D01*
X117587Y1550625D01*
X117702Y1550986D01*
X117894Y1551348D01*
X118162Y1551606D01*
X118431Y1551658D01*
X118699Y1551555D01*
X118891Y1551296D01*
G01X120496Y1549023D02*
X120726Y1548765D01*
X120994Y1548610D01*
X121339Y1548558D01*
X121684Y1548661D01*
X121952Y1548868D01*
X122144Y1549230D01*
X122182Y1549643D01*
X122106Y1550056D01*
X121914Y1550315D01*
X121646Y1550521D01*
X121377Y1550573D01*
X121109Y1550521D01*
X120764Y1550315D01*
X120879Y1551658D01*
X121914D01*
G01X124439Y1548558D02*
Y1551658D01*
X123979Y1551038D01*
G01Y1548558D02*
X124899D01*
G01X126811Y1551141D02*
X127041Y1551451D01*
X127309Y1551606D01*
X127616Y1551658D01*
X127999Y1551555D01*
X128267Y1551296D01*
X128344Y1550986D01*
X128306Y1550676D01*
X128152Y1550418D01*
X127386Y1549901D01*
X127041Y1549540D01*
X126811Y1549023D01*
X126734Y1548558D01*
X128344D01*
G01X110791Y1542733D02*
Y1540542D01*
G01X110058Y1542733D02*
X110791D01*
G01X109221Y1555669D02*
Y1552469D01*
G01X103021Y1555669D02*
X109221D01*
G01X103021Y1552469D02*
Y1555669D01*
G01X109221Y1552469D02*
X103021D01*
G01X106335Y1576181D02*
X102927D01*
G01X106335Y1593897D02*
Y1576181D01*
G01X102993Y1596197D02*
Y1599397D01*
G01X109193Y1596197D02*
X102993D01*
G01X109193Y1599397D02*
Y1596197D01*
G01X102927Y1593897D02*
X106335D01*
G01X102993Y1599397D02*
X109193D01*
G01X110753Y1653687D02*
X113953D01*
G01X110753Y1647487D02*
Y1653687D01*
G01X113953Y1647487D02*
X110753D01*
G01X115450Y1656152D02*
X109250D01*
Y1658600D01*
G01X112300D02*
Y1656152D01*
X106100D01*
G01X117453Y1668713D02*
X111253D01*
G01D02*
Y1671913D01*
G01X108586Y1669761D02*
X102386D01*
G01D02*
Y1672961D01*
G01X108586D02*
Y1669761D01*
G01Y1665761D02*
X102386D01*
G01D02*
Y1668961D01*
G01D02*
X108586D01*
G01D02*
Y1665761D01*
G01X106095Y1664319D02*
X112295D01*
Y1661600D01*
G01X107800Y1661119D02*
X106095D01*
G01X109245Y1661600D02*
Y1664319D01*
X115445D01*
G01X106100Y1659352D02*
X107800D01*
G01X108586Y1677964D02*
X102386D01*
G01D02*
Y1681164D01*
G01X108586D02*
Y1677964D01*
G01X102386Y1681164D02*
X108586D01*
G01X111253Y1675913D02*
X117453D01*
G01Y1672713D02*
X111253D01*
G01D02*
Y1675913D01*
G01Y1671913D02*
X117453D01*
G01X102386Y1677164D02*
X108586D01*
G01Y1673964D02*
X102386D01*
G01D02*
Y1677164D01*
G01X108586D02*
Y1673964D01*
G01X102386Y1672961D02*
X108586D01*
G01X116718Y1696666D02*
X105918D01*
G01D02*
Y1708666D01*
G01X96867Y1717841D02*
Y1714641D01*
G01X105900Y1710850D02*
Y1714050D01*
G01X112100Y1710850D02*
X105900D01*
G01Y1714050D02*
X112100D01*
G01X105918Y1708666D02*
X109318D01*
G01D02*
X111318Y1706666D01*
G01D02*
X113318Y1708666D01*
G01X99201Y1734593D02*
Y1732371D01*
X99354Y1731906D01*
X99661Y1731596D01*
X100044Y1731493D01*
X100427Y1731596D01*
X100734Y1731906D01*
X100887Y1732371D01*
Y1734593D01*
G01X102416Y1734076D02*
X102646Y1734386D01*
X102914Y1734541D01*
X103221Y1734593D01*
X103604Y1734490D01*
X103872Y1734231D01*
X103949Y1733921D01*
X103911Y1733611D01*
X103757Y1733353D01*
X102991Y1732836D01*
X102646Y1732475D01*
X102416Y1731958D01*
X102339Y1731493D01*
X103949D01*
G01X106244Y1734593D02*
X105937Y1734490D01*
X105707Y1734231D01*
X105554Y1733921D01*
X105439Y1733508D01*
X105401Y1733043D01*
X105439Y1732578D01*
X105554Y1732165D01*
X105707Y1731855D01*
X105937Y1731596D01*
X106244Y1731493D01*
X106551Y1731596D01*
X106781Y1731855D01*
X106934Y1732165D01*
X107049Y1732578D01*
X107087Y1733043D01*
X107049Y1733508D01*
X106934Y1733921D01*
X106781Y1734231D01*
X106551Y1734490D01*
X106244Y1734593D01*
G01X109344D02*
X109037Y1734490D01*
X108807Y1734231D01*
X108654Y1733921D01*
X108539Y1733508D01*
X108501Y1733043D01*
X108539Y1732578D01*
X108654Y1732165D01*
X108807Y1731855D01*
X109037Y1731596D01*
X109344Y1731493D01*
X109651Y1731596D01*
X109881Y1731855D01*
X110034Y1732165D01*
X110149Y1732578D01*
X110187Y1733043D01*
X110149Y1733508D01*
X110034Y1733921D01*
X109881Y1734231D01*
X109651Y1734490D01*
X109344Y1734593D01*
G01X105972Y1728277D02*
X116772D01*
G01X105972Y1716277D02*
Y1728277D01*
G01X113372Y1716277D02*
X111372Y1718277D01*
G01D02*
X109372Y1716277D01*
G01D02*
X105972D01*
G01X125000Y51142D02*
X123000D01*
G01X118000D02*
X115500D01*
G01X120739Y195191D02*
Y193954D01*
G01Y210191D02*
Y209291D01*
G01Y205191D02*
Y204291D01*
G01Y200191D02*
Y199291D01*
G01Y215528D02*
Y214291D01*
G01X118416Y293097D02*
Y299297D01*
G01D02*
X121616D01*
G01D02*
Y293097D01*
G01D02*
X118416D01*
G01X116616Y299297D02*
Y293097D01*
G01D02*
X113416D01*
G01D02*
Y299297D01*
G01D02*
X116616D01*
G01X118416Y313531D02*
Y319731D01*
G01X121616D02*
Y313531D01*
G01D02*
X118416D01*
G01X116616Y319731D02*
Y313531D01*
G01D02*
X113416D01*
G01D02*
Y319731D01*
G01X118416D02*
X121616D01*
G01X113416D02*
X116616D01*
G01X120007Y525891D02*
Y519691D01*
G01D02*
X116807D01*
G01D02*
Y525891D01*
G01X122046Y518695D02*
Y516473D01*
X122199Y516008D01*
X122506Y515698D01*
X122889Y515595D01*
X123272Y515698D01*
X123579Y516008D01*
X123732Y516473D01*
Y518695D01*
G01X125261Y518178D02*
X125491Y518488D01*
X125759Y518643D01*
X126066Y518695D01*
X126449Y518592D01*
X126717Y518333D01*
X126794Y518023D01*
X126756Y517713D01*
X126602Y517455D01*
X125836Y516938D01*
X125491Y516577D01*
X125261Y516060D01*
X125184Y515595D01*
X126794D01*
G01X129549D02*
Y518695D01*
X128131Y516473D01*
X130047D01*
G01X132189Y515595D02*
X132457Y515647D01*
X132764Y515802D01*
X132956Y516060D01*
X133032Y516422D01*
X132956Y516783D01*
X132726Y517093D01*
X132381Y517248D01*
X131997D01*
X131767Y517352D01*
X131576Y517610D01*
X131499Y517972D01*
X131614Y518333D01*
X131882Y518592D01*
X132189Y518695D01*
X132496Y518592D01*
X132764Y518333D01*
X132879Y517972D01*
X132802Y517610D01*
X132611Y517352D01*
X132381Y517248D01*
X131997D01*
X131652Y517093D01*
X131422Y516783D01*
X131346Y516422D01*
X131422Y516060D01*
X131614Y515802D01*
X131921Y515647D01*
X132189Y515595D01*
G01X133211Y522594D02*
X121411D01*
G01D02*
Y531256D01*
G01X116807Y525891D02*
X120007D01*
G01X121411Y531256D02*
X133211D01*
G01X120633Y683120D02*
X120825Y682810D01*
X121055Y682603D01*
X121323Y682500D01*
X121630Y682603D01*
X121860Y682810D01*
X122090Y683120D01*
X122167Y683533D01*
Y685600D01*
G01X123657Y683120D02*
X123887Y682758D01*
X124193Y682552D01*
X124538Y682500D01*
X124845Y682552D01*
X125152Y682810D01*
X125343Y683120D01*
X125382Y683430D01*
X125305Y683792D01*
X125037Y684050D01*
X124768Y684153D01*
X124423D01*
G01X124768D02*
X124998Y684308D01*
X125190Y684567D01*
X125267Y684877D01*
X125190Y685187D01*
X124998Y685445D01*
X124653Y685600D01*
X124308Y685548D01*
X123963Y685342D01*
G01X127600Y685600D02*
X127293Y685497D01*
X127063Y685238D01*
X126910Y684928D01*
X126795Y684515D01*
X126757Y684050D01*
X126795Y683585D01*
X126910Y683172D01*
X127063Y682862D01*
X127293Y682603D01*
X127600Y682500D01*
X127907Y682603D01*
X128137Y682862D01*
X128290Y683172D01*
X128405Y683585D01*
X128443Y684050D01*
X128405Y684515D01*
X128290Y684928D01*
X128137Y685238D01*
X127907Y685497D01*
X127600Y685600D01*
G01X124000Y687245D02*
Y1303000D01*
G01X131380Y687245D02*
X124000D01*
G01X119890Y1303000D02*
Y687245D01*
G01X149590Y720710D02*
X124000D01*
G01X149590Y1291576D02*
X124000D01*
G01X122488Y1306708D02*
X127829D01*
G01X122444Y1353233D02*
X121651D01*
G01X122444Y1355833D02*
Y1353233D01*
G01X127829Y1350016D02*
X122488D01*
G01X125310Y1368735D02*
X128510D01*
G01X125310Y1362535D02*
Y1368735D01*
G01X128510Y1362535D02*
X125310D01*
G01X125817Y1380705D02*
Y1383905D01*
G01X132017Y1380705D02*
X125817D01*
G01Y1383905D02*
X132017D01*
G01X118032Y1386458D02*
X121232D01*
G01X118032Y1380258D02*
Y1386458D01*
G01X121232Y1380258D02*
X118032D01*
G01X121232Y1386458D02*
Y1380258D01*
G01X117190D02*
X113990D01*
G01X117190Y1386458D02*
Y1380258D01*
G01X113990Y1386458D02*
X117190D01*
G01X113990Y1380258D02*
Y1386458D01*
G01X122444Y1376855D02*
Y1374664D01*
G01X121711Y1376855D02*
X122444D01*
G01X111600Y1416100D02*
Y1412900D01*
G01X117500Y1490383D02*
X114400D01*
Y1491303D01*
X114555Y1491610D01*
X114917Y1491840D01*
X115330Y1491917D01*
X115743Y1491840D01*
X116053Y1491648D01*
X116208Y1491303D01*
Y1490383D01*
G01X114400Y1493483D02*
X117500D01*
Y1495017D01*
G01X116208Y1496622D02*
X115847Y1496890D01*
X115640Y1497120D01*
X115537Y1497427D01*
X115640Y1497695D01*
X115847Y1497887D01*
X116157Y1498040D01*
X116518Y1498078D01*
X116828Y1498040D01*
X117138Y1497887D01*
X117397Y1497657D01*
X117500Y1497388D01*
X117397Y1497082D01*
X117087Y1496813D01*
X116622Y1496660D01*
X116105Y1496622D01*
X115433Y1496698D01*
X115072Y1496813D01*
X114710Y1497005D01*
X114452Y1497273D01*
X114400Y1497542D01*
X114503Y1497810D01*
X114762Y1498002D01*
G01X117035Y1499607D02*
X117293Y1499837D01*
X117448Y1500105D01*
X117500Y1500450D01*
X117397Y1500795D01*
X117190Y1501063D01*
X116828Y1501255D01*
X116415Y1501293D01*
X116002Y1501217D01*
X115743Y1501025D01*
X115537Y1500757D01*
X115485Y1500488D01*
X115537Y1500220D01*
X115743Y1499875D01*
X114400Y1499990D01*
Y1501025D01*
G01X117500Y1503550D02*
X114400D01*
X115020Y1503090D01*
G01X117500D02*
Y1504010D01*
G01X114917Y1505922D02*
X114607Y1506152D01*
X114452Y1506420D01*
X114400Y1506727D01*
X114503Y1507110D01*
X114762Y1507378D01*
X115072Y1507455D01*
X115382Y1507417D01*
X115640Y1507263D01*
X116157Y1506497D01*
X116518Y1506152D01*
X117035Y1505922D01*
X117500Y1505845D01*
Y1507455D01*
G01X112491Y1515495D02*
Y1489905D01*
G01X113466Y1534327D02*
X116666D01*
G01X113466Y1528127D02*
Y1534327D01*
G01X116666Y1528127D02*
X113466D01*
G01X116666Y1534327D02*
Y1528127D01*
G01X115798Y1561553D02*
Y1567553D01*
G01X127798Y1561553D02*
X115798D01*
G01X115848Y1560644D02*
X127848D01*
G01X115848Y1554644D02*
Y1560644D01*
G01X127848Y1554644D02*
X115848D01*
G01X114080Y1576608D02*
Y1572481D01*
X117080Y1569481D01*
G01D02*
X135734D01*
Y1576608D01*
G01X115798Y1567553D02*
X127798D01*
G01X118883Y1593000D02*
Y1596100D01*
X119803D01*
X120110Y1595945D01*
X120340Y1595583D01*
X120417Y1595170D01*
X120340Y1594757D01*
X120148Y1594447D01*
X119803Y1594292D01*
X118883D01*
G01X123593Y1595842D02*
X123363Y1595997D01*
X123095Y1596100D01*
X122788D01*
X122443Y1595945D01*
X122175Y1595687D01*
X121983Y1595377D01*
X121830Y1594860D01*
X121792Y1594395D01*
X121868Y1593930D01*
X121983Y1593620D01*
X122213Y1593310D01*
X122482Y1593103D01*
X122750Y1593000D01*
X123018D01*
X123287Y1593103D01*
X123517Y1593258D01*
X123708Y1593465D01*
G01X126310Y1593000D02*
Y1596100D01*
X124892Y1593878D01*
X126808D01*
G01X128873Y1593000D02*
X128950Y1593672D01*
X129065Y1594240D01*
X129218Y1594757D01*
X129410Y1595325D01*
X129717Y1596100D01*
X128183D01*
G01X131207Y1593620D02*
X131437Y1593258D01*
X131743Y1593052D01*
X132088Y1593000D01*
X132395Y1593052D01*
X132702Y1593310D01*
X132893Y1593620D01*
X132932Y1593930D01*
X132855Y1594292D01*
X132587Y1594550D01*
X132318Y1594653D01*
X131973D01*
G01X132318D02*
X132548Y1594808D01*
X132740Y1595067D01*
X132817Y1595377D01*
X132740Y1595687D01*
X132548Y1595945D01*
X132203Y1596100D01*
X131858Y1596048D01*
X131513Y1595842D01*
G01X135734Y1584008D02*
Y1591135D01*
X117080D01*
X114080Y1588135D01*
Y1584008D01*
G01X118753Y1653687D02*
X121953D01*
G01X118753Y1647487D02*
Y1653687D01*
G01X121953D02*
Y1647487D01*
G01D02*
X118753D01*
G01X122753Y1653687D02*
X125953D01*
G01D02*
Y1647487D01*
G01D02*
X122753D01*
G01D02*
Y1653687D01*
G01X113953D02*
Y1647487D01*
G01X114753Y1653687D02*
X117953D01*
G01D02*
Y1647487D01*
G01D02*
X114753D01*
G01D02*
Y1653687D01*
G01X123405Y1654469D02*
X123155Y1654629D01*
X123030Y1654816D01*
X122988Y1655029D01*
X123071Y1655296D01*
X123280Y1655483D01*
X123530Y1655536D01*
X123780Y1655509D01*
X123988Y1655403D01*
X124405Y1654869D01*
X124696Y1654629D01*
X125113Y1654469D01*
X125488Y1654416D01*
Y1655536D01*
G01X124446Y1656669D02*
X124155Y1656856D01*
X123988Y1657016D01*
X123905Y1657229D01*
X123988Y1657416D01*
X124155Y1657549D01*
X124405Y1657656D01*
X124696Y1657683D01*
X124946Y1657656D01*
X125196Y1657549D01*
X125405Y1657389D01*
X125488Y1657203D01*
X125405Y1656989D01*
X125155Y1656803D01*
X124780Y1656696D01*
X124363Y1656669D01*
X123821Y1656723D01*
X123530Y1656803D01*
X123238Y1656936D01*
X123030Y1657123D01*
X122988Y1657309D01*
X123071Y1657496D01*
X123280Y1657629D01*
G01X121753Y1662687D02*
X127953D01*
G01Y1659487D02*
X121753D01*
G01D02*
Y1662687D01*
G01X117453Y1671913D02*
Y1668713D01*
G01X117618Y1663579D02*
X117368Y1663739D01*
X117243Y1663926D01*
X117201Y1664139D01*
X117284Y1664406D01*
X117493Y1664593D01*
X117743Y1664646D01*
X117993Y1664619D01*
X118201Y1664513D01*
X118618Y1663979D01*
X118909Y1663739D01*
X119326Y1663579D01*
X119701Y1663526D01*
Y1664646D01*
G01X119326Y1665699D02*
X119534Y1665859D01*
X119659Y1666046D01*
X119701Y1666286D01*
X119618Y1666526D01*
X119451Y1666713D01*
X119159Y1666846D01*
X118826Y1666873D01*
X118493Y1666819D01*
X118284Y1666686D01*
X118118Y1666499D01*
X118076Y1666313D01*
X118118Y1666126D01*
X118284Y1665886D01*
X117201Y1665966D01*
Y1666686D01*
G01X115445Y1661119D02*
X113700D01*
G01Y1659352D02*
X115450D01*
G01X117453Y1675913D02*
Y1672713D01*
G01X124870Y1680842D02*
X122370D01*
X122870Y1680522D01*
G01X124870D02*
Y1681162D01*
G01X123828Y1682535D02*
X123537Y1682722D01*
X123370Y1682882D01*
X123287Y1683095D01*
X123370Y1683282D01*
X123537Y1683415D01*
X123787Y1683522D01*
X124078Y1683549D01*
X124328Y1683522D01*
X124578Y1683415D01*
X124787Y1683255D01*
X124870Y1683069D01*
X124787Y1682855D01*
X124537Y1682669D01*
X124162Y1682562D01*
X123745Y1682535D01*
X123203Y1682589D01*
X122912Y1682669D01*
X122620Y1682802D01*
X122412Y1682989D01*
X122370Y1683175D01*
X122453Y1683362D01*
X122662Y1683495D01*
G01X124953Y1672887D02*
X128153D01*
G01X125753Y1688987D02*
Y1695187D01*
G01X128953Y1688987D02*
X125753D01*
G01Y1695187D02*
X128953D01*
G01X113753Y1688866D02*
Y1695066D01*
G01D02*
X116953D01*
G01D02*
Y1688866D01*
G01D02*
X113753D01*
G01X117753D02*
Y1695066D01*
G01D02*
X120953D01*
G01D02*
Y1688866D01*
G01D02*
X117753D01*
G01X124953Y1695066D02*
Y1688866D01*
G01D02*
X121753D01*
G01D02*
Y1695066D01*
G01D02*
X124953D01*
G01X116718Y1708666D02*
Y1696666D01*
G01X119100Y1714050D02*
Y1710850D01*
G01X112900Y1714050D02*
X119100D01*
G01X112900Y1710850D02*
Y1714050D01*
G01X119100Y1710850D02*
X112900D01*
G01X112100Y1714050D02*
Y1710850D01*
G01X113318Y1708666D02*
X116718D01*
G01X116772Y1728277D02*
Y1716277D01*
G01D02*
X113372D01*
G01X147722Y43779D02*
X130982D01*
G01X151500Y51142D02*
X130000D01*
G01X141960Y428680D02*
Y422480D01*
X138760D01*
Y428680D01*
X141960D01*
G01X135703Y449180D02*
X135651Y448873D01*
X135445Y448605D01*
X135135Y448375D01*
X134773Y448222D01*
X134360Y448145D01*
X133946D01*
X133533Y448222D01*
X133171Y448375D01*
X132861Y448605D01*
X132655Y448873D01*
X132603Y449180D01*
X132655Y449487D01*
X132861Y449755D01*
X133171Y449985D01*
X133533Y450138D01*
X133946Y450215D01*
X134360D01*
X134773Y450138D01*
X135135Y449985D01*
X135445Y449755D01*
X135651Y449487D01*
X135703Y449180D01*
G01X134876Y449487D02*
X135703Y449947D01*
G01Y452203D02*
X135031Y452280D01*
X134463Y452395D01*
X133946Y452548D01*
X133378Y452740D01*
X132603Y453047D01*
Y451513D01*
G01Y455380D02*
X132706Y455073D01*
X132965Y454843D01*
X133275Y454690D01*
X133688Y454575D01*
X134153Y454537D01*
X134618Y454575D01*
X135031Y454690D01*
X135341Y454843D01*
X135600Y455073D01*
X135703Y455380D01*
X135600Y455687D01*
X135341Y455917D01*
X135031Y456070D01*
X134618Y456185D01*
X134153Y456223D01*
X133688Y456185D01*
X133275Y456070D01*
X132965Y455917D01*
X132706Y455687D01*
X132603Y455380D01*
G01Y458480D02*
X132706Y458173D01*
X132965Y457943D01*
X133275Y457790D01*
X133688Y457675D01*
X134153Y457637D01*
X134618Y457675D01*
X135031Y457790D01*
X135341Y457943D01*
X135600Y458173D01*
X135703Y458480D01*
X135600Y458787D01*
X135341Y459017D01*
X135031Y459170D01*
X134618Y459285D01*
X134153Y459323D01*
X133688Y459285D01*
X133275Y459170D01*
X132965Y459017D01*
X132706Y458787D01*
X132603Y458480D01*
G01X135703Y461580D02*
X132603D01*
X133223Y461120D01*
G01X135703D02*
Y462040D01*
G01X137670Y448378D02*
X136837D01*
Y466882D01*
X137470D01*
G01X153983Y477135D02*
Y510125D01*
X140597D01*
Y477135D01*
X153983D01*
G01X146092Y520397D02*
X139892D01*
G01D02*
Y523597D01*
G01X133211Y531256D02*
Y522594D01*
G01X146092Y529397D02*
X139892D01*
G01D02*
Y532597D01*
G01D02*
X146092D01*
G01X139892Y528597D02*
X146092D01*
G01Y525397D02*
X139892D01*
G01D02*
Y528597D01*
G01Y523597D02*
X146092D01*
G01Y533397D02*
X139892D01*
G01D02*
Y536597D01*
G01D02*
X146092D01*
G01X141444Y584681D02*
Y587781D01*
G01X143054D02*
Y584681D01*
G01Y586231D02*
X141444D01*
G01X145349Y584681D02*
Y587781D01*
X144889Y587161D01*
G01Y584681D02*
X145809D01*
G01X147721Y587264D02*
X147951Y587574D01*
X148219Y587729D01*
X148526Y587781D01*
X148909Y587678D01*
X149177Y587419D01*
X149254Y587109D01*
X149216Y586799D01*
X149062Y586541D01*
X148296Y586024D01*
X147951Y585663D01*
X147721Y585146D01*
X147644Y584681D01*
X149254D01*
G01X151472D02*
X151549Y585353D01*
X151664Y585921D01*
X151817Y586438D01*
X152009Y587006D01*
X152316Y587781D01*
X150782D01*
G01X130227Y672890D02*
X136427D01*
Y669690D01*
X130227D01*
Y672890D01*
G01X133377D02*
X139577D01*
Y669690D01*
X133377D01*
Y672890D01*
G01Y680890D02*
X139577D01*
G01D02*
Y677690D01*
G01D02*
X133377D01*
G01D02*
Y680890D01*
G01Y676890D02*
X139577D01*
G01D02*
Y673690D01*
G01D02*
X133377D01*
G01D02*
Y676890D01*
G01X149590Y687245D02*
X141260D01*
G01X130227Y684890D02*
X136427D01*
Y681690D01*
X130227D01*
Y684890D01*
G01X133377D02*
X139577D01*
Y681690D01*
X133377D01*
Y684890D01*
G01X130901Y1306708D02*
Y1350016D01*
G01X136242Y1306708D02*
X130901D01*
G01X127829D02*
Y1350016D01*
G01X133758Y1354816D02*
Y1351616D01*
G01X127558Y1354816D02*
X133758D01*
G01X127558Y1351616D02*
Y1354816D01*
G01X133758Y1351616D02*
X127558D01*
G01X132324Y1355116D02*
X129124D01*
G01X132324Y1361316D02*
Y1355116D01*
G01X129124D02*
Y1361316D01*
G01X135358Y1353233D02*
Y1355833D01*
G01X136151Y1353233D02*
X135358D01*
G01X130901Y1350016D02*
X136242D01*
G01X132301Y1372437D02*
X129101D01*
G01D02*
Y1378637D01*
G01X132301Y1374600D02*
Y1372437D01*
G01X129101Y1368137D02*
X132301D01*
G01X129101Y1361937D02*
Y1368137D01*
G01X132301Y1361937D02*
X129101D01*
G01X132301Y1368137D02*
Y1361937D01*
G01X128510Y1368735D02*
Y1362535D01*
G01X129124Y1361316D02*
X132324D01*
G01X135358Y1362444D02*
Y1364142D01*
G01X132301Y1378637D02*
Y1377300D01*
G01X129101Y1378637D02*
X132301D01*
G01X136195Y1381068D02*
X132995D01*
G01X136195Y1387268D02*
Y1381068D01*
G01X132995Y1387268D02*
X136195D01*
G01X132995Y1381068D02*
Y1387268D01*
G01X132017Y1383905D02*
Y1380705D01*
G01X136965Y1383962D02*
Y1387162D01*
G01X143165Y1383962D02*
X136965D01*
G01Y1387162D02*
X143165D01*
G01X135358Y1376855D02*
X136366D01*
G01X135358Y1375001D02*
Y1376855D01*
G01X133883Y1394000D02*
Y1397100D01*
X134803D01*
X135110Y1396945D01*
X135340Y1396583D01*
X135417Y1396170D01*
X135340Y1395757D01*
X135148Y1395447D01*
X134803Y1395292D01*
X133883D01*
G01X136907Y1397100D02*
Y1394878D01*
X137060Y1394413D01*
X137367Y1394103D01*
X137750Y1394000D01*
X138133Y1394103D01*
X138440Y1394413D01*
X138593Y1394878D01*
Y1397100D01*
G01X140007Y1394465D02*
X140237Y1394207D01*
X140505Y1394052D01*
X140850Y1394000D01*
X141195Y1394103D01*
X141463Y1394310D01*
X141655Y1394672D01*
X141693Y1395085D01*
X141617Y1395498D01*
X141425Y1395757D01*
X141157Y1395963D01*
X140888Y1396015D01*
X140620Y1395963D01*
X140275Y1395757D01*
X140390Y1397100D01*
X141425D01*
G01X143222Y1396583D02*
X143452Y1396893D01*
X143720Y1397048D01*
X144027Y1397100D01*
X144410Y1396997D01*
X144678Y1396738D01*
X144755Y1396428D01*
X144717Y1396118D01*
X144563Y1395860D01*
X143797Y1395343D01*
X143452Y1394982D01*
X143222Y1394465D01*
X143145Y1394000D01*
X144755D01*
G01X133784Y1389516D02*
Y1392616D01*
X134704D01*
X135011Y1392461D01*
X135241Y1392099D01*
X135318Y1391686D01*
X135241Y1391273D01*
X135049Y1390963D01*
X134704Y1390808D01*
X133784D01*
G01X136884Y1392616D02*
Y1389516D01*
X138418D01*
G01X140023Y1390808D02*
X140291Y1391169D01*
X140521Y1391376D01*
X140828Y1391479D01*
X141096Y1391376D01*
X141288Y1391169D01*
X141441Y1390859D01*
X141479Y1390498D01*
X141441Y1390188D01*
X141288Y1389878D01*
X141058Y1389619D01*
X140789Y1389516D01*
X140483Y1389619D01*
X140214Y1389929D01*
X140061Y1390394D01*
X140023Y1390911D01*
X140099Y1391583D01*
X140214Y1391944D01*
X140406Y1392306D01*
X140674Y1392564D01*
X140943Y1392616D01*
X141211Y1392513D01*
X141403Y1392254D01*
G01X143851Y1389516D02*
X144119Y1389568D01*
X144426Y1389723D01*
X144618Y1389981D01*
X144694Y1390343D01*
X144618Y1390704D01*
X144388Y1391014D01*
X144043Y1391169D01*
X143659D01*
X143429Y1391273D01*
X143238Y1391531D01*
X143161Y1391893D01*
X143276Y1392254D01*
X143544Y1392513D01*
X143851Y1392616D01*
X144158Y1392513D01*
X144426Y1392254D01*
X144541Y1391893D01*
X144464Y1391531D01*
X144273Y1391273D01*
X144043Y1391169D01*
X143659D01*
X143314Y1391014D01*
X143084Y1390704D01*
X143008Y1390343D01*
X143084Y1389981D01*
X143276Y1389723D01*
X143583Y1389568D01*
X143851Y1389516D01*
G01X145600Y1415900D02*
X139400D01*
G01D02*
Y1419100D01*
G01D02*
X145600D01*
G01X131909Y1421591D02*
X129561D01*
G01X131909Y1423939D02*
Y1421591D01*
G01X139428Y1447512D02*
Y1453712D01*
G01X142628Y1447512D02*
X139428D01*
G01X138720Y1453758D02*
Y1447558D01*
G01D02*
X135520D01*
G01D02*
Y1453758D01*
G01X131520Y1447558D02*
Y1453758D01*
G01X134720D02*
Y1447558D01*
G01D02*
X131520D01*
G01X129561Y1445409D02*
X131909D01*
G01D02*
Y1443061D01*
G01X139428Y1453712D02*
X142628D01*
G01X135520Y1453758D02*
X138720D01*
G01X131520D02*
X134720D01*
G01X134909Y1548659D02*
Y1551759D01*
G01X136519D02*
Y1548659D01*
G01Y1550209D02*
X134909D01*
G01X137971Y1549124D02*
X138201Y1548866D01*
X138469Y1548711D01*
X138814Y1548659D01*
X139159Y1548762D01*
X139427Y1548969D01*
X139619Y1549331D01*
X139657Y1549744D01*
X139581Y1550157D01*
X139389Y1550416D01*
X139121Y1550622D01*
X138852Y1550674D01*
X138584Y1550622D01*
X138239Y1550416D01*
X138354Y1551759D01*
X139389D01*
G01X127798Y1567553D02*
Y1561553D01*
G01X127848Y1560644D02*
Y1554644D01*
G01X130753Y1653687D02*
X133953D01*
G01X130753Y1647487D02*
Y1653687D01*
G01X133953D02*
Y1647487D01*
G01D02*
X130753D01*
G01X134753Y1653687D02*
X137953D01*
G01X134753Y1647487D02*
Y1653687D01*
G01X137953D02*
Y1647487D01*
G01D02*
X134753D01*
G01X138753Y1653687D02*
X141953D01*
G01Y1647487D02*
X138753D01*
G01D02*
Y1653687D01*
G01X126753D02*
X129953D01*
G01D02*
Y1647487D01*
G01D02*
X126753D01*
G01D02*
Y1653687D01*
G01X127953Y1662687D02*
Y1659487D01*
G01X128203Y1664987D02*
X126703D01*
G01X129735Y1664150D02*
Y1663032D01*
G01D02*
X130853D01*
G01X138853D02*
X139971D01*
G01D02*
Y1664150D01*
G01X138053Y1661487D02*
Y1658287D01*
G01X142133Y1685685D02*
X139633D01*
X140133Y1685365D01*
G01X142133D02*
Y1686005D01*
G01Y1687885D02*
X139633D01*
X140133Y1687565D01*
G01X142133D02*
Y1688205D01*
G01X129614Y1684919D02*
X127114D01*
X127614Y1684599D01*
G01X129614D02*
Y1685239D01*
G01X129239Y1686532D02*
X129447Y1686692D01*
X129572Y1686879D01*
X129614Y1687119D01*
X129531Y1687359D01*
X129364Y1687546D01*
X129072Y1687679D01*
X128739Y1687706D01*
X128406Y1687652D01*
X128197Y1687519D01*
X128031Y1687332D01*
X127989Y1687146D01*
X128031Y1686959D01*
X128197Y1686719D01*
X127114Y1686799D01*
Y1687519D01*
G01X131753Y1684237D02*
Y1682737D01*
G01X130853Y1681142D02*
X129735D01*
G01D02*
Y1680024D01*
G01X139971D02*
Y1681142D01*
G01D02*
X138853D01*
G01X141520Y1699411D02*
X135320D01*
G01D02*
Y1702611D01*
G01X134020Y1706111D02*
Y1699911D01*
G01X130820D02*
Y1706111D01*
G01X134020Y1699911D02*
X130820D01*
G01X128953Y1695187D02*
Y1688987D01*
G01X137753D02*
Y1695187D01*
G01D02*
X140953D01*
G01D02*
Y1688987D01*
G01D02*
X137753D01*
G01X129753D02*
Y1695187D01*
G01D02*
X132953D01*
G01D02*
Y1688987D01*
G01D02*
X129753D01*
G01X133753D02*
Y1695187D01*
G01D02*
X136953D01*
G01D02*
Y1688987D01*
G01D02*
X133753D01*
G01X127968Y1710946D02*
X134168D01*
G01Y1707746D02*
X127968D01*
G01D02*
Y1710946D01*
G01X134168D02*
Y1707746D01*
G01X135218Y1710766D02*
X141418D01*
G01Y1707566D02*
X135218D01*
G01D02*
Y1710766D01*
G01X141418Y1703566D02*
X135218D01*
G01D02*
Y1706766D01*
G01D02*
X141418D01*
G01X135320Y1702611D02*
X141520D01*
G01X130820Y1706111D02*
X134020D01*
G01X137367Y1716641D02*
X131167D01*
G01D02*
Y1719841D01*
G01D02*
X137367D01*
G01D02*
Y1716641D01*
G01X131167Y1727841D02*
X134367D01*
G01Y1721641D02*
X131167D01*
G01D02*
Y1727841D01*
G01X134367D02*
Y1721641D01*
G01X144367Y1724641D02*
X138167D01*
G01D02*
Y1727841D01*
G01D02*
X144367D01*
G01Y1720641D02*
X138167D01*
G01D02*
Y1723841D01*
G01D02*
X144367D01*
G01X138167Y1719841D02*
X144367D01*
G01Y1716641D02*
X138167D01*
G01D02*
Y1719841D01*
G01X151918Y215058D02*
Y208858D01*
X148718D01*
Y215058D01*
X151918D01*
G01Y223058D02*
Y216858D01*
X148718D01*
Y223058D01*
X151918D01*
G01X157234Y222251D02*
X154134D01*
Y223017D01*
X154289Y223324D01*
X154496Y223554D01*
X154806Y223746D01*
X155167Y223899D01*
X155684Y223937D01*
X156201Y223899D01*
X156562Y223746D01*
X156872Y223554D01*
X157079Y223324D01*
X157234Y223017D01*
Y222251D01*
G01Y226194D02*
X157182Y226462D01*
X157027Y226769D01*
X156769Y226961D01*
X156407Y227037D01*
X156046Y226961D01*
X155736Y226731D01*
X155581Y226386D01*
Y226002D01*
X155477Y225772D01*
X155219Y225581D01*
X154857Y225504D01*
X154496Y225619D01*
X154237Y225887D01*
X154134Y226194D01*
X154237Y226501D01*
X154496Y226769D01*
X154857Y226884D01*
X155219Y226807D01*
X155477Y226616D01*
X155581Y226386D01*
Y226002D01*
X155736Y225657D01*
X156046Y225427D01*
X156407Y225351D01*
X156769Y225427D01*
X157027Y225619D01*
X157182Y225926D01*
X157234Y226194D01*
G01X154134Y229294D02*
X154237Y228987D01*
X154496Y228757D01*
X154806Y228604D01*
X155219Y228489D01*
X155684Y228451D01*
X156149Y228489D01*
X156562Y228604D01*
X156872Y228757D01*
X157131Y228987D01*
X157234Y229294D01*
X157131Y229601D01*
X156872Y229831D01*
X156562Y229984D01*
X156149Y230099D01*
X155684Y230137D01*
X155219Y230099D01*
X154806Y229984D01*
X154496Y229831D01*
X154237Y229601D01*
X154134Y229294D01*
G01Y232394D02*
X154237Y232087D01*
X154496Y231857D01*
X154806Y231704D01*
X155219Y231589D01*
X155684Y231551D01*
X156149Y231589D01*
X156562Y231704D01*
X156872Y231857D01*
X157131Y232087D01*
X157234Y232394D01*
X157131Y232701D01*
X156872Y232931D01*
X156562Y233084D01*
X156149Y233199D01*
X155684Y233237D01*
X155219Y233199D01*
X154806Y233084D01*
X154496Y232931D01*
X154237Y232701D01*
X154134Y232394D01*
G01X157234Y235494D02*
X154134D01*
X154754Y235034D01*
G01X157234D02*
Y235954D01*
G01X148418Y225438D02*
Y232528D01*
X152218D01*
Y225388D01*
X148468D01*
G01X148418Y225838D02*
Y233028D01*
X152218D01*
Y225838D01*
G01X148418Y226438D02*
Y233528D01*
X152218D01*
Y226438D01*
G01X151083Y398457D02*
X153305D01*
X153770Y398610D01*
X154080Y398917D01*
X154183Y399300D01*
X154080Y399683D01*
X153770Y399990D01*
X153305Y400143D01*
X151083D01*
G01X153718Y401557D02*
X153976Y401787D01*
X154131Y402055D01*
X154183Y402400D01*
X154080Y402745D01*
X153873Y403013D01*
X153511Y403205D01*
X153098Y403243D01*
X152685Y403167D01*
X152426Y402975D01*
X152220Y402707D01*
X152168Y402438D01*
X152220Y402170D01*
X152426Y401825D01*
X151083Y401940D01*
Y402975D01*
G01X154183Y405423D02*
X153511Y405500D01*
X152943Y405615D01*
X152426Y405768D01*
X151858Y405960D01*
X151083Y406267D01*
Y404733D01*
G01X155719Y398493D02*
X164381D01*
Y409007D01*
X155719D01*
Y398493D01*
G01X167860Y417250D02*
Y411250D01*
X155860D01*
Y417250D01*
X167860D01*
G01X143010Y422480D02*
Y428680D01*
X146210D01*
Y422480D01*
X143010D01*
G01X148734Y434352D02*
X160546D01*
Y421728D01*
X148734D01*
Y434352D01*
G01X156300Y437210D02*
X150100D01*
Y440410D01*
X156300D01*
Y437210D01*
G01X159263Y494703D02*
X156163D01*
Y495662D01*
X156318Y495968D01*
X156525Y496160D01*
X156938Y496237D01*
X157351Y496160D01*
X157610Y495930D01*
X157765Y495662D01*
Y494703D01*
G01Y495662D02*
X159263Y496237D01*
G01Y498570D02*
X156163D01*
X156783Y498110D01*
G01X159263D02*
Y499030D01*
G01Y502130D02*
X156163D01*
X158385Y500712D01*
Y502628D01*
G01X159263Y504770D02*
X159211Y505038D01*
X159056Y505345D01*
X158798Y505537D01*
X158436Y505613D01*
X158075Y505537D01*
X157765Y505307D01*
X157610Y504962D01*
Y504578D01*
X157506Y504348D01*
X157248Y504157D01*
X156886Y504080D01*
X156525Y504195D01*
X156266Y504463D01*
X156163Y504770D01*
X156266Y505077D01*
X156525Y505345D01*
X156886Y505460D01*
X157248Y505383D01*
X157506Y505192D01*
X157610Y504962D01*
Y504578D01*
X157765Y504233D01*
X158075Y504003D01*
X158436Y503927D01*
X158798Y504003D01*
X159056Y504195D01*
X159211Y504502D01*
X159263Y504770D01*
G01X156163Y507870D02*
X156266Y507563D01*
X156525Y507333D01*
X156835Y507180D01*
X157248Y507065D01*
X157713Y507027D01*
X158178Y507065D01*
X158591Y507180D01*
X158901Y507333D01*
X159160Y507563D01*
X159263Y507870D01*
X159160Y508177D01*
X158901Y508407D01*
X158591Y508560D01*
X158178Y508675D01*
X157713Y508713D01*
X157248Y508675D01*
X156835Y508560D01*
X156525Y508407D01*
X156266Y508177D01*
X156163Y507870D01*
G01X146092Y523597D02*
Y520397D01*
G01Y532597D02*
Y529397D01*
G01Y528597D02*
Y525397D01*
G01Y536597D02*
Y533397D01*
G01X156412Y668311D02*
Y666089D01*
X156565Y665624D01*
X156872Y665314D01*
X157255Y665211D01*
X157638Y665314D01*
X157945Y665624D01*
X158098Y666089D01*
Y668311D01*
G01X160355Y665211D02*
Y668311D01*
X159895Y667691D01*
G01Y665211D02*
X160815D01*
G01X163455Y668311D02*
X163148Y668208D01*
X162918Y667949D01*
X162765Y667639D01*
X162650Y667226D01*
X162612Y666761D01*
X162650Y666296D01*
X162765Y665883D01*
X162918Y665573D01*
X163148Y665314D01*
X163455Y665211D01*
X163762Y665314D01*
X163992Y665573D01*
X164145Y665883D01*
X164260Y666296D01*
X164298Y666761D01*
X164260Y667226D01*
X164145Y667639D01*
X163992Y667949D01*
X163762Y668208D01*
X163455Y668311D01*
G01X166478Y665211D02*
X166555Y665883D01*
X166670Y666451D01*
X166823Y666968D01*
X167015Y667536D01*
X167322Y668311D01*
X165788D01*
G01X156775Y672032D02*
X148635D01*
G01D02*
Y682146D01*
G01X154347Y666761D02*
X148147D01*
G01D02*
Y669961D01*
G01D02*
X154347D01*
G01D02*
Y666761D01*
G01X148635Y682146D02*
X156775D01*
G01X153701Y687245D02*
Y1303000D01*
G01X179291Y687245D02*
X153701D01*
G01X149590Y1303000D02*
Y687245D01*
G01X179291Y720710D02*
X153701D01*
G01X179291Y1291576D02*
X153701D01*
G01X155088Y1306708D02*
X160429D01*
G01X155044Y1353233D02*
X154251D01*
G01X155044Y1355833D02*
Y1353233D01*
G01X160429Y1350016D02*
X155088D01*
G01X150632Y1386458D02*
X153832D01*
G01X150632Y1380258D02*
Y1386458D01*
G01X153832Y1380258D02*
X150632D01*
G01X153832Y1386458D02*
Y1380258D01*
G01X149790D02*
X146590D01*
G01X149790Y1386458D02*
Y1380258D01*
G01X146590Y1386458D02*
X149790D01*
G01X146590Y1380258D02*
Y1386458D01*
G01X143165Y1387162D02*
Y1383962D01*
G01X155044Y1376855D02*
Y1374664D01*
G01X154311Y1376855D02*
X155044D01*
G01X145600Y1419100D02*
Y1415900D01*
G01X146400Y1412900D02*
Y1419100D01*
G01X149600D02*
Y1412900D01*
G01D02*
X146400D01*
G01X154685Y1413649D02*
X159622Y1408712D01*
G01X154685Y1435484D02*
Y1413649D01*
G01X149600Y1435100D02*
Y1431900D01*
G01D02*
X143400D01*
G01D02*
Y1435100D01*
G01X149600Y1431100D02*
Y1427900D01*
G01D02*
X143400D01*
G01D02*
Y1431100D01*
G01D02*
X149600D01*
G01X146400Y1419100D02*
X149600D01*
G01Y1419900D02*
X143400D01*
G01D02*
Y1423100D01*
G01D02*
X149600D01*
G01D02*
Y1419900D01*
G01Y1423900D02*
X143400D01*
G01D02*
Y1427100D01*
G01X149600D02*
Y1423900D01*
G01X143400Y1427100D02*
X149600D01*
G01X142628Y1453712D02*
Y1447512D01*
G01X143428D02*
Y1453712D01*
G01X146628D02*
Y1447512D01*
G01D02*
X143428D01*
G01X143400Y1435100D02*
X149600D01*
G01X143400Y1439100D02*
X149600D01*
G01D02*
Y1435900D01*
G01D02*
X143400D01*
G01D02*
Y1439100D01*
G01X145100Y1447100D02*
Y1440900D01*
G01D02*
X141900D01*
G01D02*
Y1447100D01*
G01D02*
X145100D01*
G01X147428Y1447512D02*
Y1453712D01*
G01X150628D02*
Y1447512D01*
G01D02*
X147428D01*
G01X149400Y1440900D02*
Y1447100D01*
G01D02*
X152600D01*
G01D02*
Y1440900D01*
G01D02*
X149400D01*
G01X148600Y1447100D02*
Y1440900D01*
G01X145400D02*
Y1447100D01*
G01D02*
X148600D01*
G01Y1440900D02*
X145400D01*
G01X164371Y1435484D02*
X154685D01*
G01X143428Y1453712D02*
X146628D01*
G01X147428D02*
X150628D01*
G01X145459Y1553825D02*
X155120Y1544164D01*
Y1544779D01*
X145998Y1553901D01*
Y1553957D01*
X146524D01*
X155177Y1545304D01*
Y1545229D01*
X155195Y1545247D01*
Y1545906D01*
X147181Y1553920D01*
X147735D01*
X155206Y1546449D01*
X155271D01*
Y1547050D01*
X148552Y1553769D01*
X148476D01*
X148551Y1553694D01*
X149170D01*
X155139Y1547725D01*
Y1547407D01*
X155233Y1547501D01*
Y1548364D01*
X149939Y1553658D01*
X149608D01*
X149626Y1553676D01*
X150527D01*
X155332Y1548871D01*
Y1548721D01*
X155314Y1548739D01*
Y1549547D01*
X151109Y1553752D01*
X150696D01*
X150771Y1553827D01*
X151578D01*
X155201Y1550204D01*
Y1550016D01*
X155220Y1550035D01*
Y1550917D01*
X152404Y1553733D01*
X152066D01*
X152178Y1553845D01*
X152836D01*
X155182Y1551499D01*
Y1552250D01*
X153624Y1553808D01*
X153230D01*
X153343Y1553695D01*
X154187D01*
X155163Y1552719D01*
Y1552700D01*
X155088Y1552775D01*
Y1553395D01*
X154750Y1553733D01*
X154582D01*
X154638Y1553789D01*
X155069D01*
X155257Y1553601D01*
G01X147181Y1553920D02*
Y1553899D01*
X155174Y1545906D01*
X155195D01*
G01X147735Y1553920D02*
X148626D01*
X155271Y1547275D01*
Y1547050D01*
X155046D01*
X148271Y1553825D01*
X144435D01*
X144332Y1553722D01*
X144510D01*
X155198Y1543034D01*
Y1543578D01*
X144951Y1553825D01*
X145459D01*
X155120Y1544164D01*
Y1544066D01*
G01X149170Y1553694D02*
X149903D01*
X155233Y1548364D01*
Y1547819D01*
X155139Y1547725D01*
X154358Y1548506D01*
Y1548945D01*
X153795Y1549508D01*
X153608D01*
X149608Y1553508D01*
Y1553658D01*
X151061D01*
X155314Y1549405D01*
Y1548739D01*
X154428Y1549625D01*
Y1549653D01*
X150423Y1553658D01*
X149939D01*
G01X152404Y1553733D02*
Y1553039D01*
X155220Y1550223D01*
X155182D01*
X155201Y1550204D01*
X155220Y1550223D01*
Y1550917D01*
X152404Y1553733D01*
X152066D01*
X152141Y1553808D01*
X153624D01*
X153511Y1553695D01*
X153343D01*
X154788Y1552250D01*
X155182D01*
Y1551499D01*
X155069Y1551612D01*
G01X155472Y1542362D02*
Y1554173D01*
X143661D01*
X155472Y1542362D01*
G01X150753Y1653687D02*
X153953D01*
G01D02*
Y1647487D01*
G01D02*
X150753D01*
G01D02*
Y1653687D01*
G01X146753D02*
X149953D01*
G01X146753Y1647487D02*
Y1653687D01*
G01X149953D02*
Y1647487D01*
G01D02*
X146753D01*
G01X142653Y1653687D02*
X145853D01*
G01D02*
Y1647487D01*
G01D02*
X142653D01*
G01D02*
Y1653687D01*
G01X141953D02*
Y1647487D01*
G01X148253Y1668487D02*
Y1671687D01*
G01X154453D02*
Y1668487D01*
G01D02*
X148253D01*
G01X146182Y1660448D02*
X146474Y1660608D01*
X146640Y1660822D01*
X146682Y1661062D01*
X146640Y1661275D01*
X146432Y1661488D01*
X146182Y1661622D01*
X145932Y1661648D01*
X145640Y1661595D01*
X145432Y1661408D01*
X145349Y1661222D01*
Y1660982D01*
G01Y1661222D02*
X145224Y1661382D01*
X145015Y1661515D01*
X144765Y1661568D01*
X144515Y1661515D01*
X144307Y1661382D01*
X144182Y1661142D01*
X144224Y1660902D01*
X144390Y1660662D01*
G01X144182Y1663235D02*
X144265Y1663022D01*
X144474Y1662862D01*
X144724Y1662755D01*
X145057Y1662675D01*
X145432Y1662648D01*
X145807Y1662675D01*
X146140Y1662755D01*
X146390Y1662862D01*
X146599Y1663022D01*
X146682Y1663235D01*
X146599Y1663448D01*
X146390Y1663608D01*
X146140Y1663715D01*
X145807Y1663795D01*
X145432Y1663822D01*
X145057Y1663795D01*
X144724Y1663715D01*
X144474Y1663608D01*
X144265Y1663448D01*
X144182Y1663235D01*
G01X142253Y1684187D02*
X148453D01*
G01D02*
Y1680987D01*
G01D02*
X142253D01*
G01D02*
Y1684187D01*
G01X148253Y1671687D02*
X154453D01*
G01X153811Y1681869D02*
X151311D01*
X151811Y1681549D01*
G01X153811D02*
Y1682189D01*
G01X151311Y1684069D02*
X151394Y1683856D01*
X151603Y1683696D01*
X151853Y1683589D01*
X152186Y1683509D01*
X152561Y1683482D01*
X152936Y1683509D01*
X153269Y1683589D01*
X153519Y1683696D01*
X153728Y1683856D01*
X153811Y1684069D01*
X153728Y1684282D01*
X153519Y1684442D01*
X153269Y1684549D01*
X152936Y1684629D01*
X152561Y1684656D01*
X152186Y1684629D01*
X151853Y1684549D01*
X151603Y1684442D01*
X151394Y1684282D01*
X151311Y1684069D01*
G01X141553Y1679187D02*
X144753D01*
G01X141503Y1671287D02*
X142627D01*
G01X151035Y1680984D02*
X157235D01*
Y1678300D01*
G01X152800Y1677784D02*
X151035D01*
G01X154185Y1678300D02*
Y1680984D01*
X160385D01*
G01X151035Y1675839D02*
X152800D01*
G01X157235Y1675400D02*
Y1672639D01*
X151035D01*
G01X160385D02*
X154185D01*
Y1675400D01*
G01X141520Y1702611D02*
Y1699411D01*
G01X152953Y1695187D02*
Y1688987D01*
G01X149753D02*
Y1695187D01*
G01X152953Y1688987D02*
X149753D01*
G01Y1695187D02*
X152953D01*
G01X148853D02*
Y1688987D01*
G01D02*
X145653D01*
G01D02*
Y1695187D01*
G01D02*
X148853D01*
G01X141753Y1688987D02*
Y1695187D01*
G01D02*
X144953D01*
G01D02*
Y1688987D01*
G01D02*
X141753D01*
G01X153753D02*
Y1695187D01*
G01D02*
X156953D01*
G01Y1688987D02*
X153753D01*
G01X141418Y1710766D02*
Y1707566D01*
G01Y1706766D02*
Y1703566D01*
G01X153140Y1712100D02*
X156340D01*
G01X153140Y1705900D02*
Y1712100D01*
G01X156340Y1705900D02*
X153140D01*
G01X148300Y1711266D02*
Y1717466D01*
G01X151500Y1711266D02*
X148300D01*
G01X151500Y1717466D02*
Y1711266D01*
G01X153700Y1714169D02*
Y1722831D01*
G01X164300Y1714169D02*
X153700D01*
G01X144367Y1727841D02*
Y1724641D01*
G01Y1723841D02*
Y1720641D01*
G01Y1719841D02*
Y1716641D01*
G01X154215Y1728100D02*
X160415D01*
G01X154215Y1724900D02*
Y1728100D01*
G01X160415Y1724900D02*
X154215D01*
G01X151500Y1724466D02*
Y1718266D01*
G01X148300Y1724466D02*
X151500D01*
G01X148300Y1718266D02*
Y1724466D01*
G01X151500Y1718266D02*
X148300D01*
G01Y1717466D02*
X151500D01*
G01X156362Y1722831D02*
X159000Y1720000D01*
G01X153700Y1722831D02*
X156362D01*
G01X167000Y51142D02*
X164500D01*
G01X159000D02*
X157500D01*
G01X170613Y161998D02*
Y159776D01*
X170766Y159311D01*
X171073Y159001D01*
X171456Y158898D01*
X171839Y159001D01*
X172146Y159311D01*
X172299Y159776D01*
Y161998D01*
G01X173713Y159518D02*
X173943Y159156D01*
X174249Y158950D01*
X174594Y158898D01*
X174901Y158950D01*
X175208Y159208D01*
X175399Y159518D01*
X175438Y159828D01*
X175361Y160190D01*
X175093Y160448D01*
X174824Y160551D01*
X174479D01*
G01X174824D02*
X175054Y160706D01*
X175246Y160965D01*
X175323Y161275D01*
X175246Y161585D01*
X175054Y161843D01*
X174709Y161998D01*
X174364Y161946D01*
X174019Y161740D01*
G01X176928Y161481D02*
X177158Y161791D01*
X177426Y161946D01*
X177733Y161998D01*
X178116Y161895D01*
X178384Y161636D01*
X178461Y161326D01*
X178423Y161016D01*
X178269Y160758D01*
X177503Y160241D01*
X177158Y159880D01*
X176928Y159363D01*
X176851Y158898D01*
X178461D01*
G01X168081Y194450D02*
X167926Y194603D01*
X167667Y194718D01*
X167306Y194795D01*
X166996Y194718D01*
X166789Y194565D01*
X166634Y194296D01*
Y193261D01*
X169734D01*
Y194526D01*
X169527Y194795D01*
X169217Y194948D01*
X168856Y195025D01*
X168494Y194948D01*
X168184Y194718D01*
X168081Y194450D01*
Y193261D01*
G01X169734Y197243D02*
X166634D01*
G01X167667Y199691D02*
X169114D01*
X169476Y199845D01*
X169682Y200075D01*
X169734Y200343D01*
X169682Y200611D01*
X169476Y200841D01*
X169114Y200995D01*
G01X169734D02*
X167667D01*
G01X168339Y202868D02*
Y204095D01*
X167977Y203980D01*
X167771Y203788D01*
X167667Y203520D01*
X167719Y203251D01*
X167874Y203021D01*
X168236Y202868D01*
X168546Y202791D01*
X168856D01*
X169166Y202868D01*
X169476Y203060D01*
X169682Y203290D01*
X169734Y203558D01*
X169631Y203826D01*
X169321Y204095D01*
G01X166634Y208876D02*
X169734D01*
Y210410D01*
G01X167667Y212743D02*
X169734D01*
G01X166841D02*
X166789Y212666D01*
X166686D01*
X166634Y212743D01*
X166686Y212820D01*
X166789D01*
X166841Y212743D01*
G01X170509Y215306D02*
X170716Y215575D01*
X170767Y215881D01*
X170716Y216150D01*
X170457Y216380D01*
X170096Y216533D01*
X167667D01*
G01X168081D02*
X167874Y216380D01*
X167719Y216150D01*
X167667Y215881D01*
X167771Y215575D01*
X167977Y215383D01*
X168339Y215230D01*
X168701Y215153D01*
X169011Y215191D01*
X169372Y215345D01*
X169631Y215575D01*
X169734Y215881D01*
X169682Y216111D01*
X169476Y216380D01*
X169269Y216533D01*
G01X169734Y218291D02*
X166634D01*
G01X168132D02*
X167874Y218483D01*
X167719Y218675D01*
X167667Y218981D01*
X167719Y219211D01*
X167926Y219480D01*
X168236Y219595D01*
X169734D01*
G01X166634Y222043D02*
X169734D01*
G01X167667Y221506D02*
Y222580D01*
G01X166634Y227476D02*
X169734D01*
Y229010D01*
G01Y232110D02*
Y230576D01*
X166634D01*
Y232110D01*
G01X168132Y231496D02*
Y230576D01*
G01X169734Y233600D02*
X166634D01*
Y234366D01*
X166789Y234673D01*
X166996Y234903D01*
X167306Y235095D01*
X167667Y235248D01*
X168184Y235286D01*
X168701Y235248D01*
X169062Y235095D01*
X169372Y234903D01*
X169579Y234673D01*
X169734Y234366D01*
Y233600D01*
G01X162959Y206803D02*
X159859D01*
Y207723D01*
X160014Y208030D01*
X160376Y208260D01*
X160789Y208337D01*
X161202Y208260D01*
X161512Y208068D01*
X161667Y207723D01*
Y206803D01*
G01X162959Y210670D02*
X159859D01*
X160479Y210210D01*
G01X162959D02*
Y211130D01*
G01X160376Y213042D02*
X160066Y213272D01*
X159911Y213540D01*
X159859Y213847D01*
X159962Y214230D01*
X160221Y214498D01*
X160531Y214575D01*
X160841Y214537D01*
X161099Y214383D01*
X161616Y213617D01*
X161977Y213272D01*
X162494Y213042D01*
X162959Y212965D01*
Y214575D01*
G01X159859Y215912D02*
X162959Y216870D01*
X159859Y217828D01*
G01X163992Y218820D02*
Y221120D01*
G01X162959Y222303D02*
X159859D01*
Y223223D01*
X160014Y223530D01*
X160376Y223760D01*
X160789Y223837D01*
X161202Y223760D01*
X161512Y223568D01*
X161667Y223223D01*
Y222303D01*
G01X162546Y225365D02*
X162804Y225672D01*
X162959Y226017D01*
Y226323D01*
X162804Y226630D01*
X162546Y226860D01*
X162184Y226975D01*
X161822Y226898D01*
X161512Y226707D01*
X161306Y226362D01*
X161202Y225902D01*
X160996Y225633D01*
X160634Y225518D01*
X160272Y225595D01*
X160014Y225787D01*
X159859Y226055D01*
Y226323D01*
X159962Y226592D01*
X160221Y226822D01*
G01X159859Y228427D02*
X162081D01*
X162546Y228580D01*
X162856Y228887D01*
X162959Y229270D01*
X162856Y229653D01*
X162546Y229960D01*
X162081Y230113D01*
X159859D01*
G01X172950Y393440D02*
X166750D01*
Y396640D01*
X172950D01*
Y393440D01*
G01X166760Y402160D02*
X172960D01*
Y398960D01*
X166760D01*
Y402160D01*
G01X166330Y422150D02*
X166278Y421843D01*
X166072Y421575D01*
X165762Y421345D01*
X165400Y421192D01*
X164987Y421115D01*
X164573D01*
X164160Y421192D01*
X163798Y421345D01*
X163488Y421575D01*
X163282Y421843D01*
X163230Y422150D01*
X163282Y422457D01*
X163488Y422725D01*
X163798Y422955D01*
X164160Y423108D01*
X164573Y423185D01*
X164987D01*
X165400Y423108D01*
X165762Y422955D01*
X166072Y422725D01*
X166278Y422457D01*
X166330Y422150D01*
G01X165503Y422457D02*
X166330Y422917D01*
G01Y425173D02*
X165658Y425250D01*
X165090Y425365D01*
X164573Y425518D01*
X164005Y425710D01*
X163230Y426017D01*
Y424483D01*
G01Y428350D02*
X163333Y428043D01*
X163592Y427813D01*
X163902Y427660D01*
X164315Y427545D01*
X164780Y427507D01*
X165245Y427545D01*
X165658Y427660D01*
X165968Y427813D01*
X166227Y428043D01*
X166330Y428350D01*
X166227Y428657D01*
X165968Y428887D01*
X165658Y429040D01*
X165245Y429155D01*
X164780Y429193D01*
X164315Y429155D01*
X163902Y429040D01*
X163592Y428887D01*
X163333Y428657D01*
X163230Y428350D01*
G01Y431450D02*
X163333Y431143D01*
X163592Y430913D01*
X163902Y430760D01*
X164315Y430645D01*
X164780Y430607D01*
X165245Y430645D01*
X165658Y430760D01*
X165968Y430913D01*
X166227Y431143D01*
X166330Y431450D01*
X166227Y431757D01*
X165968Y431987D01*
X165658Y432140D01*
X165245Y432255D01*
X164780Y432293D01*
X164315Y432255D01*
X163902Y432140D01*
X163592Y431987D01*
X163333Y431757D01*
X163230Y431450D01*
G01Y434550D02*
X163333Y434243D01*
X163592Y434013D01*
X163902Y433860D01*
X164315Y433745D01*
X164780Y433707D01*
X165245Y433745D01*
X165658Y433860D01*
X165968Y434013D01*
X166227Y434243D01*
X166330Y434550D01*
X166227Y434857D01*
X165968Y435087D01*
X165658Y435240D01*
X165245Y435355D01*
X164780Y435393D01*
X164315Y435355D01*
X163902Y435240D01*
X163592Y435087D01*
X163333Y434857D01*
X163230Y434550D01*
G01X173920Y422150D02*
X173868Y421843D01*
X173662Y421575D01*
X173352Y421345D01*
X172990Y421192D01*
X172577Y421115D01*
X172163D01*
X171750Y421192D01*
X171388Y421345D01*
X171078Y421575D01*
X170872Y421843D01*
X170820Y422150D01*
X170872Y422457D01*
X171078Y422725D01*
X171388Y422955D01*
X171750Y423108D01*
X172163Y423185D01*
X172577D01*
X172990Y423108D01*
X173352Y422955D01*
X173662Y422725D01*
X173868Y422457D01*
X173920Y422150D01*
G01X173093Y422457D02*
X173920Y422917D01*
G01Y425173D02*
X173248Y425250D01*
X172680Y425365D01*
X172163Y425518D01*
X171595Y425710D01*
X170820Y426017D01*
Y424483D01*
G01Y428350D02*
X170923Y428043D01*
X171182Y427813D01*
X171492Y427660D01*
X171905Y427545D01*
X172370Y427507D01*
X172835Y427545D01*
X173248Y427660D01*
X173558Y427813D01*
X173817Y428043D01*
X173920Y428350D01*
X173817Y428657D01*
X173558Y428887D01*
X173248Y429040D01*
X172835Y429155D01*
X172370Y429193D01*
X171905Y429155D01*
X171492Y429040D01*
X171182Y428887D01*
X170923Y428657D01*
X170820Y428350D01*
G01Y431450D02*
X170923Y431143D01*
X171182Y430913D01*
X171492Y430760D01*
X171905Y430645D01*
X172370Y430607D01*
X172835Y430645D01*
X173248Y430760D01*
X173558Y430913D01*
X173817Y431143D01*
X173920Y431450D01*
X173817Y431757D01*
X173558Y431987D01*
X173248Y432140D01*
X172835Y432255D01*
X172370Y432293D01*
X171905Y432255D01*
X171492Y432140D01*
X171182Y431987D01*
X170923Y431757D01*
X170820Y431450D01*
G01X171337Y433822D02*
X171027Y434052D01*
X170872Y434320D01*
X170820Y434627D01*
X170923Y435010D01*
X171182Y435278D01*
X171492Y435355D01*
X171802Y435317D01*
X172060Y435163D01*
X172577Y434397D01*
X172938Y434052D01*
X173455Y433822D01*
X173920Y433745D01*
Y435355D01*
G01X157703Y466882D02*
Y448378D01*
X156770D01*
G01X162483Y448640D02*
X162431Y448333D01*
X162225Y448065D01*
X161915Y447835D01*
X161553Y447682D01*
X161140Y447605D01*
X160726D01*
X160313Y447682D01*
X159951Y447835D01*
X159641Y448065D01*
X159435Y448333D01*
X159383Y448640D01*
X159435Y448947D01*
X159641Y449215D01*
X159951Y449445D01*
X160313Y449598D01*
X160726Y449675D01*
X161140D01*
X161553Y449598D01*
X161915Y449445D01*
X162225Y449215D01*
X162431Y448947D01*
X162483Y448640D01*
G01X161656Y448947D02*
X162483Y449407D01*
G01Y451663D02*
X161811Y451740D01*
X161243Y451855D01*
X160726Y452008D01*
X160158Y452200D01*
X159383Y452507D01*
Y450973D01*
G01Y454840D02*
X159486Y454533D01*
X159745Y454303D01*
X160055Y454150D01*
X160468Y454035D01*
X160933Y453997D01*
X161398Y454035D01*
X161811Y454150D01*
X162121Y454303D01*
X162380Y454533D01*
X162483Y454840D01*
X162380Y455147D01*
X162121Y455377D01*
X161811Y455530D01*
X161398Y455645D01*
X160933Y455683D01*
X160468Y455645D01*
X160055Y455530D01*
X159745Y455377D01*
X159486Y455147D01*
X159383Y454840D01*
G01Y457940D02*
X159486Y457633D01*
X159745Y457403D01*
X160055Y457250D01*
X160468Y457135D01*
X160933Y457097D01*
X161398Y457135D01*
X161811Y457250D01*
X162121Y457403D01*
X162380Y457633D01*
X162483Y457940D01*
X162380Y458247D01*
X162121Y458477D01*
X161811Y458630D01*
X161398Y458745D01*
X160933Y458783D01*
X160468Y458745D01*
X160055Y458630D01*
X159745Y458477D01*
X159486Y458247D01*
X159383Y457940D01*
G01X161863Y460197D02*
X162225Y460427D01*
X162431Y460733D01*
X162483Y461078D01*
X162431Y461385D01*
X162173Y461692D01*
X161863Y461883D01*
X161553Y461922D01*
X161191Y461845D01*
X160933Y461577D01*
X160830Y461308D01*
Y460963D01*
G01Y461308D02*
X160675Y461538D01*
X160416Y461730D01*
X160106Y461807D01*
X159796Y461730D01*
X159538Y461538D01*
X159383Y461193D01*
X159435Y460848D01*
X159641Y460503D01*
G01X164450Y447838D02*
X163617D01*
Y466342D01*
X164250D01*
G01X157070Y466882D02*
X157703D01*
G01X180763Y476595D02*
Y509585D01*
X167377D01*
Y476595D01*
X180763D01*
G01X164450Y494773D02*
X161350D01*
Y495732D01*
X161505Y496038D01*
X161712Y496230D01*
X162125Y496307D01*
X162538Y496230D01*
X162797Y496000D01*
X162952Y495732D01*
Y494773D01*
G01Y495732D02*
X164450Y496307D01*
G01Y498640D02*
X161350D01*
X161970Y498180D01*
G01X164450D02*
Y499100D01*
G01Y502200D02*
X161350D01*
X163572Y500782D01*
Y502698D01*
G01X164450Y504840D02*
X164398Y505108D01*
X164243Y505415D01*
X163985Y505607D01*
X163623Y505683D01*
X163262Y505607D01*
X162952Y505377D01*
X162797Y505032D01*
Y504648D01*
X162693Y504418D01*
X162435Y504227D01*
X162073Y504150D01*
X161712Y504265D01*
X161453Y504533D01*
X161350Y504840D01*
X161453Y505147D01*
X161712Y505415D01*
X162073Y505530D01*
X162435Y505453D01*
X162693Y505262D01*
X162797Y505032D01*
Y504648D01*
X162952Y504303D01*
X163262Y504073D01*
X163623Y503997D01*
X163985Y504073D01*
X164243Y504265D01*
X164398Y504572D01*
X164450Y504840D01*
G01Y507940D02*
X161350D01*
X161970Y507480D01*
G01X164450D02*
Y508400D01*
G01X156775Y682146D02*
Y672032D01*
G01X168050Y672100D02*
X174250D01*
Y668900D01*
X168050D01*
Y672100D01*
G01X164900D02*
X171100D01*
Y668900D01*
X164900D01*
Y672100D01*
G01X170966Y683199D02*
X164766D01*
G01D02*
Y686399D01*
G01D02*
X170966D01*
G01D02*
Y683199D01*
G01Y679199D02*
X164766D01*
G01D02*
Y682399D01*
G01D02*
X170966D01*
G01D02*
Y679199D01*
G01X168050Y678100D02*
X174250D01*
Y674900D01*
X168050D01*
Y678100D01*
G01X164900D02*
X171100D01*
Y674900D01*
X164900D01*
Y678100D01*
G01X163401Y1306708D02*
Y1350016D01*
G01X168742Y1306708D02*
X163401D01*
G01X160429D02*
Y1350016D01*
G01X166458Y1354816D02*
Y1351616D01*
G01X160258Y1354816D02*
X166458D01*
G01X160258Y1351616D02*
Y1354816D01*
G01X166458Y1351616D02*
X160258D01*
G01X165024Y1355116D02*
X161824D01*
G01X165024Y1361316D02*
Y1355116D01*
G01X161824D02*
Y1361316D01*
G01X168058Y1353233D02*
Y1355833D01*
G01X168851Y1353233D02*
X168058D01*
G01X163401Y1350016D02*
X168742D01*
G01X157910Y1368508D02*
X161110D01*
G01X157910Y1362308D02*
Y1368508D01*
G01X161110Y1362308D02*
X157910D01*
G01X161110Y1368508D02*
Y1362308D01*
G01X165001Y1372437D02*
X161801D01*
G01D02*
Y1378637D01*
G01X165001Y1374300D02*
Y1372437D01*
G01X161801Y1368137D02*
X165001D01*
G01X161801Y1361937D02*
Y1368137D01*
G01X165001Y1361937D02*
X161801D01*
G01X165001Y1368137D02*
Y1361937D01*
G01X161824Y1361316D02*
X165024D01*
G01X168058Y1362444D02*
Y1364142D01*
G01X165001Y1378637D02*
Y1377500D01*
G01X161801Y1378637D02*
X165001D01*
G01X168895Y1381068D02*
X165695D01*
G01X168895Y1387268D02*
Y1381068D01*
G01X165695Y1387268D02*
X168895D01*
G01X165695Y1381068D02*
Y1387268D01*
G01X158517Y1380705D02*
Y1383905D01*
G01X164717Y1380705D02*
X158517D01*
G01X164717Y1383905D02*
Y1380705D01*
G01X158517Y1383905D02*
X164717D01*
G01X169665Y1383962D02*
Y1387162D01*
G01X175865Y1383962D02*
X169665D01*
G01Y1387162D02*
X175865D01*
G01X168058Y1376855D02*
X169066D01*
G01X168058Y1375001D02*
Y1376855D01*
G01X166383Y1394000D02*
Y1397100D01*
X167303D01*
X167610Y1396945D01*
X167840Y1396583D01*
X167917Y1396170D01*
X167840Y1395757D01*
X167648Y1395447D01*
X167303Y1395292D01*
X166383D01*
G01X169407Y1397100D02*
Y1394878D01*
X169560Y1394413D01*
X169867Y1394103D01*
X170250Y1394000D01*
X170633Y1394103D01*
X170940Y1394413D01*
X171093Y1394878D01*
Y1397100D01*
G01X173810Y1394000D02*
Y1397100D01*
X172392Y1394878D01*
X174308D01*
G01X176450Y1397100D02*
X176143Y1396997D01*
X175913Y1396738D01*
X175760Y1396428D01*
X175645Y1396015D01*
X175607Y1395550D01*
X175645Y1395085D01*
X175760Y1394672D01*
X175913Y1394362D01*
X176143Y1394103D01*
X176450Y1394000D01*
X176757Y1394103D01*
X176987Y1394362D01*
X177140Y1394672D01*
X177255Y1395085D01*
X177293Y1395550D01*
X177255Y1396015D01*
X177140Y1396428D01*
X176987Y1396738D01*
X176757Y1396997D01*
X176450Y1397100D01*
G01X166284Y1389516D02*
Y1392616D01*
X167204D01*
X167511Y1392461D01*
X167741Y1392099D01*
X167818Y1391686D01*
X167741Y1391273D01*
X167549Y1390963D01*
X167204Y1390808D01*
X166284D01*
G01X169384Y1392616D02*
Y1389516D01*
X170918D01*
G01X173711D02*
Y1392616D01*
X172293Y1390394D01*
X174209D01*
G01X176351Y1389516D02*
X176619Y1389568D01*
X176926Y1389723D01*
X177118Y1389981D01*
X177194Y1390343D01*
X177118Y1390704D01*
X176888Y1391014D01*
X176543Y1391169D01*
X176159D01*
X175929Y1391273D01*
X175738Y1391531D01*
X175661Y1391893D01*
X175776Y1392254D01*
X176044Y1392513D01*
X176351Y1392616D01*
X176658Y1392513D01*
X176926Y1392254D01*
X177041Y1391893D01*
X176964Y1391531D01*
X176773Y1391273D01*
X176543Y1391169D01*
X176159D01*
X175814Y1391014D01*
X175584Y1390704D01*
X175508Y1390343D01*
X175584Y1389981D01*
X175776Y1389723D01*
X176083Y1389568D01*
X176351Y1389516D01*
G01X159622Y1408712D02*
X164371D01*
G01X165383Y1441000D02*
Y1444100D01*
X166303D01*
X166610Y1443945D01*
X166840Y1443583D01*
X166917Y1443170D01*
X166840Y1442757D01*
X166648Y1442447D01*
X166303Y1442292D01*
X165383D01*
G01X170093Y1443842D02*
X169863Y1443997D01*
X169595Y1444100D01*
X169288D01*
X168943Y1443945D01*
X168675Y1443687D01*
X168483Y1443377D01*
X168330Y1442860D01*
X168292Y1442395D01*
X168368Y1441930D01*
X168483Y1441620D01*
X168713Y1441310D01*
X168982Y1441103D01*
X169250Y1441000D01*
X169518D01*
X169787Y1441103D01*
X170017Y1441258D01*
X170208Y1441465D01*
G01X172810Y1441000D02*
Y1444100D01*
X171392Y1441878D01*
X173308D01*
G01X174607Y1441465D02*
X174837Y1441207D01*
X175105Y1441052D01*
X175450Y1441000D01*
X175795Y1441103D01*
X176063Y1441310D01*
X176255Y1441672D01*
X176293Y1442085D01*
X176217Y1442498D01*
X176025Y1442757D01*
X175757Y1442963D01*
X175488Y1443015D01*
X175220Y1442963D01*
X174875Y1442757D01*
X174990Y1444100D01*
X176025D01*
G01X179010Y1441000D02*
Y1444100D01*
X177592Y1441878D01*
X179508D01*
G01X157742Y1550342D02*
Y1568058D01*
G01X161150Y1550342D02*
X157742D01*
G01X170582Y1570190D02*
Y1574790D01*
G01X180782Y1570190D02*
X170582D01*
G01Y1574790D02*
X180782D01*
G01X157883Y1575100D02*
Y1572000D01*
X159417D01*
G01X162210D02*
Y1575100D01*
X160792Y1572878D01*
X162708D01*
G01X157742Y1568058D02*
X161150D01*
G01X160988Y1685882D02*
Y1683660D01*
X161141Y1683195D01*
X161448Y1682885D01*
X161831Y1682782D01*
X162214Y1682885D01*
X162521Y1683195D01*
X162674Y1683660D01*
Y1685882D01*
G01X164203Y1685365D02*
X164433Y1685675D01*
X164701Y1685830D01*
X165008Y1685882D01*
X165391Y1685779D01*
X165659Y1685520D01*
X165736Y1685210D01*
X165698Y1684900D01*
X165544Y1684642D01*
X164778Y1684125D01*
X164433Y1683764D01*
X164203Y1683247D01*
X164126Y1682782D01*
X165736D01*
G01X167188Y1683402D02*
X167418Y1683040D01*
X167724Y1682834D01*
X168069Y1682782D01*
X168376Y1682834D01*
X168683Y1683092D01*
X168874Y1683402D01*
X168913Y1683712D01*
X168836Y1684074D01*
X168568Y1684332D01*
X168299Y1684435D01*
X167954D01*
G01X168299D02*
X168529Y1684590D01*
X168721Y1684849D01*
X168798Y1685159D01*
X168721Y1685469D01*
X168529Y1685727D01*
X168184Y1685882D01*
X167839Y1685830D01*
X167494Y1685624D01*
G01X171054Y1682782D02*
X171131Y1683454D01*
X171246Y1684022D01*
X171399Y1684539D01*
X171591Y1685107D01*
X171898Y1685882D01*
X170364D01*
G01X160385Y1677784D02*
X158700D01*
G01Y1675839D02*
X160385D01*
G01X161027Y1695187D02*
Y1688987D01*
G01D02*
X157827D01*
G01D02*
Y1695187D01*
G01D02*
X161027D01*
G01X156953D02*
Y1688987D01*
G01X169100Y1713900D02*
X165900D01*
G01D02*
Y1720100D01*
G01X169100D02*
Y1713900D01*
G01X161140Y1712100D02*
X164340D01*
G01X161140Y1705900D02*
Y1712100D01*
G01X164340Y1705900D02*
X161140D01*
G01X164340Y1712100D02*
Y1705900D01*
G01X156340Y1712100D02*
Y1705900D01*
G01X160340D02*
X157140D01*
G01X160340Y1712100D02*
Y1705900D01*
G01X157140Y1712100D02*
X160340D01*
G01X157140Y1705900D02*
Y1712100D01*
G01X170400Y1712600D02*
X176600D01*
G01X170400Y1709400D02*
Y1712600D01*
G01X176600Y1709400D02*
X170400D01*
G01Y1713400D02*
Y1716600D01*
G01X176600Y1713400D02*
X170400D01*
G01X164300Y1722831D02*
Y1714169D01*
G01X165900Y1720100D02*
X169100D01*
G01X160415Y1728100D02*
Y1724900D01*
G01X161215D02*
Y1728100D01*
G01X167415Y1724900D02*
X161215D01*
G01X167415Y1728100D02*
Y1724900D01*
G01X161215Y1728100D02*
X167415D01*
G01X170400Y1722600D02*
X176600D01*
G01X170400Y1719400D02*
Y1722600D01*
G01X176600Y1719400D02*
X170400D01*
G01Y1726600D02*
X176600D01*
G01X170400Y1723400D02*
Y1726600D01*
G01X176600Y1723400D02*
X170400D01*
G01Y1716600D02*
X176600D01*
G01X157681Y1734088D02*
Y1731866D01*
X157834Y1731401D01*
X158141Y1731091D01*
X158524Y1730988D01*
X158907Y1731091D01*
X159214Y1731401D01*
X159367Y1731866D01*
Y1734088D01*
G01X160896Y1733571D02*
X161126Y1733881D01*
X161394Y1734036D01*
X161701Y1734088D01*
X162084Y1733985D01*
X162352Y1733726D01*
X162429Y1733416D01*
X162391Y1733106D01*
X162237Y1732848D01*
X161471Y1732331D01*
X161126Y1731970D01*
X160896Y1731453D01*
X160819Y1730988D01*
X162429D01*
G01X163881Y1731453D02*
X164111Y1731195D01*
X164379Y1731040D01*
X164724Y1730988D01*
X165069Y1731091D01*
X165337Y1731298D01*
X165529Y1731660D01*
X165567Y1732073D01*
X165491Y1732486D01*
X165299Y1732745D01*
X165031Y1732951D01*
X164762Y1733003D01*
X164494Y1732951D01*
X164149Y1732745D01*
X164264Y1734088D01*
X165299D01*
G01X167096Y1732280D02*
X167364Y1732641D01*
X167594Y1732848D01*
X167901Y1732951D01*
X168169Y1732848D01*
X168361Y1732641D01*
X168514Y1732331D01*
X168552Y1731970D01*
X168514Y1731660D01*
X168361Y1731350D01*
X168131Y1731091D01*
X167862Y1730988D01*
X167556Y1731091D01*
X167287Y1731401D01*
X167134Y1731866D01*
X167096Y1732383D01*
X167172Y1733055D01*
X167287Y1733416D01*
X167479Y1733778D01*
X167747Y1734036D01*
X168016Y1734088D01*
X168284Y1733985D01*
X168476Y1733726D01*
G01X161638Y1722831D02*
X164300D01*
G01X159000Y1720000D02*
X161638Y1722831D01*
G01X194222Y43779D02*
X181022D01*
G01X196000Y51142D02*
X181500D01*
G01X174000D02*
X172500D01*
G01X184133Y106979D02*
X186355D01*
X186820Y107132D01*
X187130Y107439D01*
X187233Y107822D01*
X187130Y108205D01*
X186820Y108512D01*
X186355Y108665D01*
X184133D01*
G01X184650Y110194D02*
X184340Y110424D01*
X184185Y110692D01*
X184133Y110999D01*
X184236Y111382D01*
X184495Y111650D01*
X184805Y111727D01*
X185115Y111689D01*
X185373Y111535D01*
X185890Y110769D01*
X186251Y110424D01*
X186768Y110194D01*
X187233Y110117D01*
Y111727D01*
G01Y114022D02*
X187181Y114290D01*
X187026Y114597D01*
X186768Y114789D01*
X186406Y114865D01*
X186045Y114789D01*
X185735Y114559D01*
X185580Y114214D01*
Y113830D01*
X185476Y113600D01*
X185218Y113409D01*
X184856Y113332D01*
X184495Y113447D01*
X184236Y113715D01*
X184133Y114022D01*
X184236Y114329D01*
X184495Y114597D01*
X184856Y114712D01*
X185218Y114635D01*
X185476Y114444D01*
X185580Y114214D01*
Y113830D01*
X185735Y113485D01*
X186045Y113255D01*
X186406Y113179D01*
X186768Y113255D01*
X187026Y113447D01*
X187181Y113754D01*
X187233Y114022D01*
G01X185941Y116394D02*
X185580Y116662D01*
X185373Y116892D01*
X185270Y117199D01*
X185373Y117467D01*
X185580Y117659D01*
X185890Y117812D01*
X186251Y117850D01*
X186561Y117812D01*
X186871Y117659D01*
X187130Y117429D01*
X187233Y117160D01*
X187130Y116854D01*
X186820Y116585D01*
X186355Y116432D01*
X185838Y116394D01*
X185166Y116470D01*
X184805Y116585D01*
X184443Y116777D01*
X184185Y117045D01*
X184133Y117314D01*
X184236Y117582D01*
X184495Y117774D01*
G01X174823Y144661D02*
Y157339D01*
G01X190177Y144661D02*
X174823D01*
G01Y157339D02*
X190177D01*
G01X182290Y389060D02*
Y395260D01*
X185490D01*
Y389060D01*
X182290D01*
G01X177670Y398577D02*
X179892D01*
X180357Y398730D01*
X180667Y399037D01*
X180770Y399420D01*
X180667Y399803D01*
X180357Y400110D01*
X179892Y400263D01*
X177670D01*
G01X179478Y401792D02*
X179117Y402060D01*
X178910Y402290D01*
X178807Y402597D01*
X178910Y402865D01*
X179117Y403057D01*
X179427Y403210D01*
X179788Y403248D01*
X180098Y403210D01*
X180408Y403057D01*
X180667Y402827D01*
X180770Y402558D01*
X180667Y402252D01*
X180357Y401983D01*
X179892Y401830D01*
X179375Y401792D01*
X178703Y401868D01*
X178342Y401983D01*
X177980Y402175D01*
X177722Y402443D01*
X177670Y402712D01*
X177773Y402980D01*
X178032Y403172D01*
G01X177670Y405620D02*
X177773Y405313D01*
X178032Y405083D01*
X178342Y404930D01*
X178755Y404815D01*
X179220Y404777D01*
X179685Y404815D01*
X180098Y404930D01*
X180408Y405083D01*
X180667Y405313D01*
X180770Y405620D01*
X180667Y405927D01*
X180408Y406157D01*
X180098Y406310D01*
X179685Y406425D01*
X179220Y406463D01*
X178755Y406425D01*
X178342Y406310D01*
X178032Y406157D01*
X177773Y405927D01*
X177670Y405620D01*
G01X182499Y397953D02*
X191161D01*
Y408467D01*
X182499D01*
Y397953D01*
G01X179200Y415000D02*
X173000D01*
Y418200D01*
X179200D01*
Y415000D01*
G01X173000Y413950D02*
X179200D01*
Y410750D01*
X173000D01*
Y413950D01*
G01X194640Y416710D02*
Y410710D01*
X182640D01*
Y416710D01*
X194640D01*
G01X175514Y433812D02*
X187326D01*
Y421188D01*
X175514D01*
Y433812D01*
G01X183080Y436670D02*
X176880D01*
Y439870D01*
X183080D01*
Y436670D01*
G01X184483Y466342D02*
Y447838D01*
X183550D01*
G01X183850Y466342D02*
X184483D01*
G01X181100Y670900D02*
X174900D01*
G01D02*
Y674100D01*
G01X181100D02*
Y670900D01*
G01Y674900D02*
X174900D01*
G01D02*
Y678100D01*
G01D02*
X181100D01*
G01D02*
Y674900D01*
G01X174900Y674100D02*
X181100D01*
G01X183402Y687245D02*
Y1303000D01*
G01X208992Y687245D02*
X183402D01*
G01X173953Y681624D02*
X174145Y681314D01*
X174375Y681107D01*
X174643Y681004D01*
X174950Y681107D01*
X175180Y681314D01*
X175410Y681624D01*
X175487Y682037D01*
Y684104D01*
G01X177092Y683587D02*
X177322Y683897D01*
X177590Y684052D01*
X177897Y684104D01*
X178280Y684001D01*
X178548Y683742D01*
X178625Y683432D01*
X178587Y683122D01*
X178433Y682864D01*
X177667Y682347D01*
X177322Y681986D01*
X177092Y681469D01*
X177015Y681004D01*
X178625D01*
G01X180920D02*
X181188Y681056D01*
X181495Y681211D01*
X181687Y681469D01*
X181763Y681831D01*
X181687Y682192D01*
X181457Y682502D01*
X181112Y682657D01*
X180728D01*
X180498Y682761D01*
X180307Y683019D01*
X180230Y683381D01*
X180345Y683742D01*
X180613Y684001D01*
X180920Y684104D01*
X181227Y684001D01*
X181495Y683742D01*
X181610Y683381D01*
X181533Y683019D01*
X181342Y682761D01*
X181112Y682657D01*
X180728D01*
X180383Y682502D01*
X180153Y682192D01*
X180077Y681831D01*
X180153Y681469D01*
X180345Y681211D01*
X180652Y681056D01*
X180920Y681004D01*
G01X179291Y1303000D02*
Y687245D01*
G01X208992Y720710D02*
X183402D01*
G01X208992Y1291576D02*
X183402D01*
G01X183332Y1386458D02*
X186532D01*
G01X183332Y1380258D02*
Y1386458D01*
G01X186532Y1380258D02*
X183332D01*
G01X182490D02*
X179290D01*
G01X182490Y1386458D02*
Y1380258D01*
G01X179290Y1386458D02*
X182490D01*
G01X179290Y1380258D02*
Y1386458D01*
G01X175865Y1387162D02*
Y1383962D01*
G01X183534Y1405416D02*
X189645D01*
G01X183534Y1429432D02*
Y1405416D01*
G01X176520Y1408712D02*
X171771D01*
G01X181457Y1413649D02*
X176520Y1408712D01*
G01X181457Y1435484D02*
Y1413649D01*
G01X189645Y1429432D02*
X183534D01*
G01X171771Y1435484D02*
X181457D01*
G01X177433Y1507451D02*
Y1524600D01*
G01X182200Y1507451D02*
X177433D01*
G01Y1528000D02*
Y1542491D01*
G01X175458Y1568058D02*
Y1550342D01*
G01D02*
X172050D01*
G01X177433Y1542491D02*
X183900D01*
G01X182459Y1562098D02*
X194459D01*
G01X182459Y1556098D02*
Y1562098D01*
G01X194459Y1556098D02*
X182459D01*
G01X182433Y1562952D02*
Y1568952D01*
G01X194433Y1562952D02*
X182433D01*
G01X176382Y1570190D02*
Y1574790D01*
G01X186582Y1570190D02*
X176382D01*
G01Y1574790D02*
X186582D01*
G01X180782D02*
Y1570190D01*
G01X182433Y1568952D02*
X194433D01*
G01X172050Y1568058D02*
X175458D01*
G01X180160Y1711988D02*
X183360D01*
G01X180160Y1705788D02*
Y1711988D01*
G01X183360Y1705788D02*
X180160D01*
G01X183360Y1711988D02*
Y1705788D01*
G01X184160Y1711988D02*
X187360D01*
G01Y1705788D02*
X184160D01*
G01D02*
Y1711988D01*
G01X176600Y1712600D02*
Y1709400D01*
G01Y1716600D02*
Y1713400D01*
G01X180200Y1713669D02*
Y1722331D01*
G01X190800Y1713669D02*
X180200D01*
G01X184160Y1730476D02*
X187360D01*
G01X184160Y1724276D02*
Y1730476D01*
G01X187360Y1724276D02*
X184160D01*
G01X183360D02*
X180160D01*
G01X183360Y1730476D02*
Y1724276D01*
G01X180160Y1730476D02*
X183360D01*
G01X180160Y1724276D02*
Y1730476D01*
G01X176600Y1722600D02*
Y1719400D01*
G01Y1726600D02*
Y1723400D01*
G01X185500Y1719500D02*
X188138Y1722331D01*
G01X182862D02*
X185500Y1719500D01*
G01X180200Y1722331D02*
X182862D01*
G01X172833Y1735878D02*
Y1733656D01*
X172986Y1733191D01*
X173293Y1732881D01*
X173676Y1732778D01*
X174059Y1732881D01*
X174366Y1733191D01*
X174519Y1733656D01*
Y1735878D01*
G01X176776Y1732778D02*
Y1735878D01*
X176316Y1735258D01*
G01Y1732778D02*
X177236D01*
G01X179224Y1733140D02*
X179493Y1732881D01*
X179799Y1732778D01*
X180106Y1732881D01*
X180374Y1733191D01*
X180566Y1733656D01*
X180643Y1734121D01*
Y1734690D01*
X180566Y1735155D01*
X180374Y1735568D01*
X180144Y1735775D01*
X179876Y1735878D01*
X179569Y1735775D01*
X179339Y1735568D01*
X179186Y1735258D01*
X179109Y1734845D01*
X179186Y1734483D01*
X179378Y1734121D01*
X179608Y1733915D01*
X179876Y1733863D01*
X180183Y1733966D01*
X180413Y1734225D01*
X180643Y1734690D01*
G01X182248Y1734070D02*
X182516Y1734431D01*
X182746Y1734638D01*
X183053Y1734741D01*
X183321Y1734638D01*
X183513Y1734431D01*
X183666Y1734121D01*
X183704Y1733760D01*
X183666Y1733450D01*
X183513Y1733140D01*
X183283Y1732881D01*
X183014Y1732778D01*
X182708Y1732881D01*
X182439Y1733191D01*
X182286Y1733656D01*
X182248Y1734173D01*
X182324Y1734845D01*
X182439Y1735206D01*
X182631Y1735568D01*
X182899Y1735826D01*
X183168Y1735878D01*
X183436Y1735775D01*
X183628Y1735516D01*
G01X194379Y96542D02*
Y102742D01*
G01D02*
X197579D01*
G01D02*
Y96542D01*
G01D02*
X194379D01*
G01X197751Y122274D02*
Y111250D01*
G01D02*
X189089D01*
G01Y122274D02*
Y111250D01*
G01X189261Y123977D02*
Y130177D01*
G01D02*
X192461D01*
G01D02*
Y123977D01*
G01D02*
X189261D01*
G01X196045Y129087D02*
Y135287D01*
G01D02*
X199245D01*
G01D02*
Y129087D01*
G01D02*
X196045D01*
G01X189089Y122274D02*
X197751D01*
G01X197520Y139362D02*
X191320D01*
G01D02*
Y142562D01*
G01D02*
X197520D01*
G01D02*
Y139362D01*
G01X191320Y146562D02*
X197520D01*
G01D02*
Y143362D01*
G01D02*
X191320D01*
G01D02*
Y146562D01*
G01X192400Y147400D02*
Y150600D01*
G01X198600Y147400D02*
X192400D01*
G01X198600Y150600D02*
Y147400D01*
G01X190177Y157142D02*
Y144661D01*
G01X200676Y146398D02*
X214324D01*
G01X200676Y158602D02*
Y146398D01*
G01X192900Y154900D02*
Y158100D01*
G01X199100Y154900D02*
X192900D01*
G01X199100Y158100D02*
Y154900D01*
G01X192900Y158100D02*
X199100D01*
G01X200236Y166925D02*
Y163725D01*
G01X194036D02*
Y166925D01*
G01X200236Y163725D02*
X194036D01*
G01X192400Y150600D02*
X198600D01*
G01X204898Y158602D02*
X200676D01*
G01X194036Y166925D02*
X200236D01*
G01X191010Y395260D02*
Y389060D01*
X187810D01*
Y395260D01*
X191010D01*
G01X199289Y594145D02*
X211289D01*
G01X199289Y588145D02*
Y594145D01*
G01X211289Y588145D02*
X199289D01*
G01Y596245D02*
Y602245D01*
G01X211289Y596245D02*
X199289D01*
G01Y602245D02*
X211289D01*
G01X195099Y681125D02*
X195291Y680815D01*
X195521Y680608D01*
X195789Y680505D01*
X196096Y680608D01*
X196326Y680815D01*
X196556Y681125D01*
X196633Y681538D01*
Y683605D01*
G01X198238Y683088D02*
X198468Y683398D01*
X198736Y683553D01*
X199043Y683605D01*
X199426Y683502D01*
X199694Y683243D01*
X199771Y682933D01*
X199733Y682623D01*
X199579Y682365D01*
X198813Y681848D01*
X198468Y681487D01*
X198238Y680970D01*
X198161Y680505D01*
X199771D01*
G01X201338Y681797D02*
X201606Y682158D01*
X201836Y682365D01*
X202143Y682468D01*
X202411Y682365D01*
X202603Y682158D01*
X202756Y681848D01*
X202794Y681487D01*
X202756Y681177D01*
X202603Y680867D01*
X202373Y680608D01*
X202104Y680505D01*
X201798Y680608D01*
X201529Y680918D01*
X201376Y681383D01*
X201338Y681900D01*
X201414Y682572D01*
X201529Y682933D01*
X201721Y683295D01*
X201989Y683553D01*
X202258Y683605D01*
X202526Y683502D01*
X202718Y683243D01*
G01X192896Y673395D02*
Y676495D01*
G01X194506D02*
Y673395D01*
G01Y674945D02*
X192896D01*
G01X196801Y673395D02*
X197069Y673447D01*
X197376Y673602D01*
X197568Y673860D01*
X197644Y674222D01*
X197568Y674583D01*
X197338Y674893D01*
X196993Y675048D01*
X196609D01*
X196379Y675152D01*
X196188Y675410D01*
X196111Y675772D01*
X196226Y676133D01*
X196494Y676392D01*
X196801Y676495D01*
X197108Y676392D01*
X197376Y676133D01*
X197491Y675772D01*
X197414Y675410D01*
X197223Y675152D01*
X196993Y675048D01*
X196609D01*
X196264Y674893D01*
X196034Y674583D01*
X195958Y674222D01*
X196034Y673860D01*
X196226Y673602D01*
X196533Y673447D01*
X196801Y673395D01*
G01X199901Y676495D02*
X199594Y676392D01*
X199364Y676133D01*
X199211Y675823D01*
X199096Y675410D01*
X199058Y674945D01*
X199096Y674480D01*
X199211Y674067D01*
X199364Y673757D01*
X199594Y673498D01*
X199901Y673395D01*
X200208Y673498D01*
X200438Y673757D01*
X200591Y674067D01*
X200706Y674480D01*
X200744Y674945D01*
X200706Y675410D01*
X200591Y675823D01*
X200438Y676133D01*
X200208Y676392D01*
X199901Y676495D01*
G01X202273Y675978D02*
X202503Y676288D01*
X202771Y676443D01*
X203078Y676495D01*
X203461Y676392D01*
X203729Y676133D01*
X203806Y675823D01*
X203768Y675513D01*
X203614Y675255D01*
X202848Y674738D01*
X202503Y674377D01*
X202273Y673860D01*
X202196Y673395D01*
X203806D01*
G01X206101D02*
X206369Y673447D01*
X206676Y673602D01*
X206868Y673860D01*
X206944Y674222D01*
X206868Y674583D01*
X206638Y674893D01*
X206293Y675048D01*
X205909D01*
X205679Y675152D01*
X205488Y675410D01*
X205411Y675772D01*
X205526Y676133D01*
X205794Y676392D01*
X206101Y676495D01*
X206408Y676392D01*
X206676Y676133D01*
X206791Y675772D01*
X206714Y675410D01*
X206523Y675152D01*
X206293Y675048D01*
X205909D01*
X205564Y674893D01*
X205334Y674583D01*
X205258Y674222D01*
X205334Y673860D01*
X205526Y673602D01*
X205833Y673447D01*
X206101Y673395D01*
G01X196001Y1306708D02*
Y1350016D01*
G01X201342Y1306708D02*
X196001D01*
G01X192929D02*
Y1350016D01*
G01X187588Y1306708D02*
X192929D01*
G01X199358Y1354816D02*
Y1351616D01*
G01X193158Y1354816D02*
X199358D01*
G01X193158Y1351616D02*
Y1354816D01*
G01X199358Y1351616D02*
X193158D01*
G01X197924Y1355116D02*
X194724D01*
G01X197924Y1361316D02*
Y1355116D01*
G01X194724D02*
Y1361316D01*
G01X200958Y1353233D02*
Y1355833D01*
G01X201751Y1353233D02*
X200958D01*
G01X187744D02*
X186951D01*
G01X187744Y1355833D02*
Y1353233D01*
G01X196001Y1350016D02*
X201342D01*
G01X192929D02*
X187588D01*
G01X190610Y1368735D02*
X193810D01*
G01X190610Y1362535D02*
Y1368735D01*
G01X193810Y1362535D02*
X190610D01*
G01X193810Y1368735D02*
Y1362535D01*
G01X197901Y1372437D02*
X194701D01*
G01D02*
Y1378637D01*
G01X197901Y1374500D02*
Y1372437D01*
G01X194701Y1368137D02*
X197901D01*
G01X194701Y1361937D02*
Y1368137D01*
G01X197901Y1361937D02*
X194701D01*
G01X197901Y1368137D02*
Y1361937D01*
G01X194724Y1361316D02*
X197924D01*
G01X200958Y1362444D02*
Y1364142D01*
G01X197901Y1378637D02*
Y1377300D01*
G01X194701Y1378637D02*
X197901D01*
G01X201795Y1381068D02*
X198595D01*
G01Y1387268D02*
X201795D01*
G01X198595Y1381068D02*
Y1387268D01*
G01X191417Y1380705D02*
Y1383905D01*
G01X197617Y1380705D02*
X191417D01*
G01X197617Y1383905D02*
Y1380705D01*
G01X191417Y1383905D02*
X197617D01*
G01X186532Y1386458D02*
Y1380258D01*
G01X200958Y1376855D02*
X201966D01*
G01X200958Y1375001D02*
Y1376855D01*
G01X187744D02*
Y1374664D01*
G01X187011Y1376855D02*
X187744D01*
G01X198883Y1394000D02*
Y1397100D01*
X199803D01*
X200110Y1396945D01*
X200340Y1396583D01*
X200417Y1396170D01*
X200340Y1395757D01*
X200148Y1395447D01*
X199803Y1395292D01*
X198883D01*
G01X201907Y1397100D02*
Y1394878D01*
X202060Y1394413D01*
X202367Y1394103D01*
X202750Y1394000D01*
X203133Y1394103D01*
X203440Y1394413D01*
X203593Y1394878D01*
Y1397100D01*
G01X205007Y1394620D02*
X205237Y1394258D01*
X205543Y1394052D01*
X205888Y1394000D01*
X206195Y1394052D01*
X206502Y1394310D01*
X206693Y1394620D01*
X206732Y1394930D01*
X206655Y1395292D01*
X206387Y1395550D01*
X206118Y1395653D01*
X205773D01*
G01X206118D02*
X206348Y1395808D01*
X206540Y1396067D01*
X206617Y1396377D01*
X206540Y1396687D01*
X206348Y1396945D01*
X206003Y1397100D01*
X205658Y1397048D01*
X205313Y1396842D01*
G01X208298Y1394362D02*
X208567Y1394103D01*
X208873Y1394000D01*
X209180Y1394103D01*
X209448Y1394413D01*
X209640Y1394878D01*
X209717Y1395343D01*
Y1395912D01*
X209640Y1396377D01*
X209448Y1396790D01*
X209218Y1396997D01*
X208950Y1397100D01*
X208643Y1396997D01*
X208413Y1396790D01*
X208260Y1396480D01*
X208183Y1396067D01*
X208260Y1395705D01*
X208452Y1395343D01*
X208682Y1395137D01*
X208950Y1395085D01*
X209257Y1395188D01*
X209487Y1395447D01*
X209717Y1395912D01*
G01X198884Y1389516D02*
Y1392616D01*
X199804D01*
X200111Y1392461D01*
X200341Y1392099D01*
X200418Y1391686D01*
X200341Y1391273D01*
X200149Y1390963D01*
X199804Y1390808D01*
X198884D01*
G01X201984Y1392616D02*
Y1389516D01*
X203518D01*
G01X206311D02*
Y1392616D01*
X204893Y1390394D01*
X206809D01*
G01X208874Y1389516D02*
X208951Y1390188D01*
X209066Y1390756D01*
X209219Y1391273D01*
X209411Y1391841D01*
X209718Y1392616D01*
X208184D01*
G01X189883Y1433000D02*
Y1436100D01*
X190803D01*
X191110Y1435945D01*
X191340Y1435583D01*
X191417Y1435170D01*
X191340Y1434757D01*
X191148Y1434447D01*
X190803Y1434292D01*
X189883D01*
G01X192983Y1436100D02*
Y1433000D01*
X194517D01*
G01X197310D02*
Y1436100D01*
X195892Y1433878D01*
X197808D01*
G01X199298Y1433362D02*
X199567Y1433103D01*
X199873Y1433000D01*
X200180Y1433103D01*
X200448Y1433413D01*
X200640Y1433878D01*
X200717Y1434343D01*
Y1434912D01*
X200640Y1435377D01*
X200448Y1435790D01*
X200218Y1435997D01*
X199950Y1436100D01*
X199643Y1435997D01*
X199413Y1435790D01*
X199260Y1435480D01*
X199183Y1435067D01*
X199260Y1434705D01*
X199452Y1434343D01*
X199682Y1434137D01*
X199950Y1434085D01*
X200257Y1434188D01*
X200487Y1434447D01*
X200717Y1434912D01*
G01X194459Y1562098D02*
Y1556098D01*
G01X194433Y1568952D02*
Y1562952D01*
G01X196106Y1557857D02*
Y1555635D01*
X196259Y1555170D01*
X196566Y1554860D01*
X196949Y1554757D01*
X197332Y1554860D01*
X197639Y1555170D01*
X197792Y1555635D01*
Y1557857D01*
G01X199321Y1556049D02*
X199589Y1556410D01*
X199819Y1556617D01*
X200126Y1556720D01*
X200394Y1556617D01*
X200586Y1556410D01*
X200739Y1556100D01*
X200777Y1555739D01*
X200739Y1555429D01*
X200586Y1555119D01*
X200356Y1554860D01*
X200087Y1554757D01*
X199781Y1554860D01*
X199512Y1555170D01*
X199359Y1555635D01*
X199321Y1556152D01*
X199397Y1556824D01*
X199512Y1557185D01*
X199704Y1557547D01*
X199972Y1557805D01*
X200241Y1557857D01*
X200509Y1557754D01*
X200701Y1557495D01*
G01X203149Y1557857D02*
X202842Y1557754D01*
X202612Y1557495D01*
X202459Y1557185D01*
X202344Y1556772D01*
X202306Y1556307D01*
X202344Y1555842D01*
X202459Y1555429D01*
X202612Y1555119D01*
X202842Y1554860D01*
X203149Y1554757D01*
X203456Y1554860D01*
X203686Y1555119D01*
X203839Y1555429D01*
X203954Y1555842D01*
X203992Y1556307D01*
X203954Y1556772D01*
X203839Y1557185D01*
X203686Y1557495D01*
X203456Y1557754D01*
X203149Y1557857D01*
G01X206249Y1554757D02*
Y1557857D01*
X205789Y1557237D01*
G01Y1554757D02*
X206709D01*
G01X209809D02*
Y1557857D01*
X208391Y1555635D01*
X210307D01*
G01X186582Y1574790D02*
Y1570190D01*
G01X194038Y1582454D02*
Y1570454D01*
G01X188038D02*
Y1582454D01*
G01X194038Y1570454D02*
X188038D01*
G01X194853Y1588610D02*
X200853D01*
Y1576610D01*
X194853D01*
Y1588610D01*
G01X188038Y1582454D02*
X194038D01*
G01X192400Y1713400D02*
Y1719600D01*
G01X195600Y1713400D02*
X192400D01*
G01X195600Y1719600D02*
Y1713400D01*
G01X188160Y1711988D02*
X191360D01*
G01X188160Y1705788D02*
Y1711988D01*
G01X191360Y1705788D02*
X188160D01*
G01X191360Y1711988D02*
Y1705788D01*
G01X187360Y1711988D02*
Y1705788D01*
G01X197400Y1708600D02*
X203600D01*
G01X197400Y1705400D02*
Y1708600D01*
G01X203600Y1705400D02*
X197400D01*
G01X190800Y1722331D02*
Y1713669D01*
G01X197200Y1710669D02*
Y1719331D01*
G01X207800Y1710669D02*
X197200D01*
G01X192400Y1719600D02*
X195600D01*
G01X191360Y1724276D02*
X188160D01*
G01X191360Y1730476D02*
Y1724276D01*
G01X188160Y1730476D02*
X191360D01*
G01X188160Y1724276D02*
Y1730476D01*
G01X187360D02*
Y1724276D01*
G01X196179Y1724600D02*
X202379D01*
G01X196179Y1721400D02*
Y1724600D01*
G01X202379Y1721400D02*
X196179D01*
G01X188138Y1722331D02*
X190800D01*
G01X195636Y1729905D02*
Y1727683D01*
X195789Y1727218D01*
X196096Y1726908D01*
X196479Y1726805D01*
X196862Y1726908D01*
X197169Y1727218D01*
X197322Y1727683D01*
Y1729905D01*
G01X198851Y1729388D02*
X199081Y1729698D01*
X199349Y1729853D01*
X199656Y1729905D01*
X200039Y1729802D01*
X200307Y1729543D01*
X200384Y1729233D01*
X200346Y1728923D01*
X200192Y1728665D01*
X199426Y1728148D01*
X199081Y1727787D01*
X198851Y1727270D01*
X198774Y1726805D01*
X200384D01*
G01X201836Y1727270D02*
X202066Y1727012D01*
X202334Y1726857D01*
X202679Y1726805D01*
X203024Y1726908D01*
X203292Y1727115D01*
X203484Y1727477D01*
X203522Y1727890D01*
X203446Y1728303D01*
X203254Y1728562D01*
X202986Y1728768D01*
X202717Y1728820D01*
X202449Y1728768D01*
X202104Y1728562D01*
X202219Y1729905D01*
X203254D01*
G01X205051Y1729388D02*
X205281Y1729698D01*
X205549Y1729853D01*
X205856Y1729905D01*
X206239Y1729802D01*
X206507Y1729543D01*
X206584Y1729233D01*
X206546Y1728923D01*
X206392Y1728665D01*
X205626Y1728148D01*
X205281Y1727787D01*
X205051Y1727270D01*
X204974Y1726805D01*
X206584D01*
G01X199862Y1719331D02*
X202500Y1716500D01*
G01X197200Y1719331D02*
X199862D01*
G01X213400Y-601572D02*
X214200Y-602238D01*
X215100Y-602638D01*
X215900D01*
X216700Y-602238D01*
X217300Y-601572D01*
X217600Y-600638D01*
X217400Y-599705D01*
X216900Y-598905D01*
X216000Y-598371D01*
X214800Y-598105D01*
X214100Y-597571D01*
X213800Y-596638D01*
X214000Y-595705D01*
X214500Y-595038D01*
X215200Y-594638D01*
X215900D01*
X216600Y-594905D01*
X217200Y-595571D01*
G01X222300Y-594638D02*
X224700D01*
G01X223500D02*
Y-602638D01*
G01X222300D02*
X224700D01*
G01X229500Y-594638D02*
Y-602638D01*
X233500D01*
G01X237300D02*
Y-594638D01*
G01X241100D02*
X237300Y-599572D01*
G01X241700Y-602638D02*
X239000Y-597305D01*
G01X246200Y-599971D02*
X248800D01*
G01X255500Y-594638D02*
Y-602638D01*
G01X253200Y-594638D02*
X257800D01*
G01X263500Y-602638D02*
X262700Y-602505D01*
X262000Y-601971D01*
X261400Y-601171D01*
X261000Y-600238D01*
X260800Y-599171D01*
Y-598105D01*
X261000Y-597038D01*
X261400Y-596105D01*
X262000Y-595305D01*
X262700Y-594771D01*
X263500Y-594638D01*
X264300Y-594771D01*
X265000Y-595305D01*
X265600Y-596105D01*
X266000Y-597038D01*
X266200Y-598105D01*
Y-599171D01*
X266000Y-600238D01*
X265600Y-601171D01*
X265000Y-601971D01*
X264300Y-602505D01*
X263500Y-602638D01*
G01X269500D02*
Y-594638D01*
X271900D01*
X272700Y-595038D01*
X273300Y-595971D01*
X273500Y-597038D01*
X273300Y-598105D01*
X272800Y-598905D01*
X271900Y-599305D01*
X269500D01*
G01X202000Y-569638D02*
Y-577638D01*
X206000D01*
G01X213800D02*
Y-572305D01*
G01Y-573238D02*
X213400Y-572705D01*
X212800Y-572438D01*
X212100Y-572305D01*
X211400Y-572571D01*
X210800Y-573105D01*
X210400Y-573905D01*
X210200Y-574971D01*
X210400Y-576038D01*
X210800Y-576838D01*
X211400Y-577371D01*
X212100Y-577638D01*
X212800Y-577505D01*
X213400Y-577105D01*
X213800Y-576572D01*
G01X217900Y-580038D02*
X218500Y-580305D01*
X219300Y-580038D01*
X219800Y-579505D01*
X220200Y-578838D01*
X220800Y-576705D01*
X222100Y-572305D01*
G01X218900D02*
X220800Y-576705D01*
G01X226500Y-574038D02*
X229700D01*
X229400Y-573105D01*
X228900Y-572571D01*
X228200Y-572305D01*
X227500Y-572438D01*
X226900Y-572838D01*
X226500Y-573771D01*
X226300Y-574572D01*
Y-575371D01*
X226500Y-576171D01*
X227000Y-576971D01*
X227600Y-577505D01*
X228300Y-577638D01*
X229000Y-577371D01*
X229700Y-576572D01*
G01X234600Y-577638D02*
Y-572305D01*
G01Y-573371D02*
X235100Y-572838D01*
X235600Y-572438D01*
X236300Y-572305D01*
X236800Y-572438D01*
X237400Y-572838D01*
G01X212000Y51142D02*
X208000D01*
G01X204000D02*
X201000D01*
G01X206579Y96542D02*
Y102742D01*
G01D02*
X209779D01*
G01D02*
Y96542D01*
G01D02*
X206579D01*
G01X209951Y122274D02*
Y111250D01*
G01D02*
X201289D01*
G01Y122274D02*
Y111250D01*
G01X201461Y123977D02*
Y130177D01*
G01D02*
X204661D01*
G01D02*
Y123977D01*
G01D02*
X201461D01*
G01X201289Y122274D02*
X209951D01*
G01X214324Y146398D02*
Y158602D01*
G01X204334Y164473D02*
Y162251D01*
X204487Y161786D01*
X204794Y161476D01*
X205177Y161373D01*
X205560Y161476D01*
X205867Y161786D01*
X206020Y162251D01*
Y164473D01*
G01X207434Y161993D02*
X207664Y161631D01*
X207970Y161425D01*
X208315Y161373D01*
X208622Y161425D01*
X208929Y161683D01*
X209120Y161993D01*
X209159Y162303D01*
X209082Y162665D01*
X208814Y162923D01*
X208545Y163026D01*
X208200D01*
G01X208545D02*
X208775Y163181D01*
X208967Y163440D01*
X209044Y163750D01*
X208967Y164060D01*
X208775Y164318D01*
X208430Y164473D01*
X208085Y164421D01*
X207740Y164215D01*
G01X211377Y161373D02*
Y164473D01*
X210917Y163853D01*
G01Y161373D02*
X211837D01*
G01X210102Y158602D02*
X207500Y156000D01*
G01X214324Y158602D02*
X210102D01*
G01X207500Y156000D02*
X204898Y158602D01*
G01X211289Y594145D02*
Y588145D01*
G01Y602245D02*
Y596245D01*
G01X201814Y623857D02*
Y616730D01*
G01D02*
X220468D01*
G01X202072Y640290D02*
Y643390D01*
X202992D01*
X203299Y643235D01*
X203529Y642873D01*
X203606Y642460D01*
X203529Y642047D01*
X203337Y641737D01*
X202992Y641582D01*
X202072D01*
G01X206782Y643132D02*
X206552Y643287D01*
X206284Y643390D01*
X205977D01*
X205632Y643235D01*
X205364Y642977D01*
X205172Y642667D01*
X205019Y642150D01*
X204981Y641685D01*
X205057Y641220D01*
X205172Y640910D01*
X205402Y640600D01*
X205671Y640393D01*
X205939Y640290D01*
X206207D01*
X206476Y640393D01*
X206706Y640548D01*
X206897Y640755D01*
G01X209039Y640290D02*
X209307Y640342D01*
X209614Y640497D01*
X209806Y640755D01*
X209882Y641117D01*
X209806Y641478D01*
X209576Y641788D01*
X209231Y641943D01*
X208847D01*
X208617Y642047D01*
X208426Y642305D01*
X208349Y642667D01*
X208464Y643028D01*
X208732Y643287D01*
X209039Y643390D01*
X209346Y643287D01*
X209614Y643028D01*
X209729Y642667D01*
X209652Y642305D01*
X209461Y642047D01*
X209231Y641943D01*
X208847D01*
X208502Y641788D01*
X208272Y641478D01*
X208196Y641117D01*
X208272Y640755D01*
X208464Y640497D01*
X208771Y640342D01*
X209039Y640290D01*
G01X211487Y640652D02*
X211756Y640393D01*
X212062Y640290D01*
X212369Y640393D01*
X212637Y640703D01*
X212829Y641168D01*
X212906Y641633D01*
Y642202D01*
X212829Y642667D01*
X212637Y643080D01*
X212407Y643287D01*
X212139Y643390D01*
X211832Y643287D01*
X211602Y643080D01*
X211449Y642770D01*
X211372Y642357D01*
X211449Y641995D01*
X211641Y641633D01*
X211871Y641427D01*
X212139Y641375D01*
X212446Y641478D01*
X212676Y641737D01*
X212906Y642202D01*
G01X220468Y638384D02*
X201814D01*
G01D02*
Y631257D01*
G01X214492Y672348D02*
X214684Y672038D01*
X214914Y671831D01*
X215182Y671728D01*
X215489Y671831D01*
X215719Y672038D01*
X215949Y672348D01*
X216026Y672761D01*
Y674828D01*
G01X217631Y674311D02*
X217861Y674621D01*
X218129Y674776D01*
X218436Y674828D01*
X218819Y674725D01*
X219087Y674466D01*
X219164Y674156D01*
X219126Y673846D01*
X218972Y673588D01*
X218206Y673071D01*
X217861Y672710D01*
X217631Y672193D01*
X217554Y671728D01*
X219164D01*
G01X221919D02*
Y674828D01*
X220501Y672606D01*
X222417D01*
G01X219157Y679424D02*
X215162D01*
G01D02*
Y705014D01*
G01X213103Y687245D02*
Y1303000D01*
G01X208992D02*
Y687245D01*
G01X215162Y705014D02*
X219157D01*
G01X238693Y720710D02*
X213103D01*
G01X238693Y1291576D02*
X213103D01*
G01X201795Y1387268D02*
Y1381068D01*
G01X202565Y1383962D02*
Y1387162D01*
G01X208765Y1383962D02*
X202565D01*
G01X208765Y1387162D02*
Y1383962D01*
G01X202565Y1387162D02*
X208765D01*
G01X215390Y1380258D02*
X212190D01*
G01X215390Y1386458D02*
Y1380258D01*
G01X212190Y1386458D02*
X215390D01*
G01X212190Y1380258D02*
Y1386458D01*
G01X208973Y1417587D02*
Y1420787D01*
G01X215173Y1417587D02*
X208973D01*
G01X215173Y1420787D02*
Y1417587D01*
G01X207156Y1405416D02*
Y1429432D01*
G01X201045Y1405416D02*
X207156D01*
G01X208973Y1420787D02*
X215173D01*
G01X207156Y1429432D02*
X201045D01*
G01X210965Y1566590D02*
X213205D01*
G01X211992Y1568215D02*
Y1564965D01*
G01X210203Y1563307D02*
X209973Y1563462D01*
X209705Y1563565D01*
X209398D01*
X209053Y1563410D01*
X208785Y1563152D01*
X208593Y1562842D01*
X208440Y1562325D01*
X208402Y1561860D01*
X208478Y1561395D01*
X208593Y1561085D01*
X208823Y1560775D01*
X209092Y1560568D01*
X209360Y1560465D01*
X209628D01*
X209897Y1560568D01*
X210127Y1560723D01*
X210318Y1560930D01*
G01X212383Y1560465D02*
X212460Y1561137D01*
X212575Y1561705D01*
X212728Y1562222D01*
X212920Y1562790D01*
X213227Y1563565D01*
X211693D01*
G01X215560D02*
X215253Y1563462D01*
X215023Y1563203D01*
X214870Y1562893D01*
X214755Y1562480D01*
X214717Y1562015D01*
X214755Y1561550D01*
X214870Y1561137D01*
X215023Y1560827D01*
X215253Y1560568D01*
X215560Y1560465D01*
X215867Y1560568D01*
X216097Y1560827D01*
X216250Y1561137D01*
X216365Y1561550D01*
X216403Y1562015D01*
X216365Y1562480D01*
X216250Y1562893D01*
X216097Y1563203D01*
X215867Y1563462D01*
X215560Y1563565D01*
G01X217817Y1561085D02*
X218047Y1560723D01*
X218353Y1560517D01*
X218698Y1560465D01*
X219005Y1560517D01*
X219312Y1560775D01*
X219503Y1561085D01*
X219542Y1561395D01*
X219465Y1561757D01*
X219197Y1562015D01*
X218928Y1562118D01*
X218583D01*
G01X218928D02*
X219158Y1562273D01*
X219350Y1562532D01*
X219427Y1562842D01*
X219350Y1563152D01*
X219158Y1563410D01*
X218813Y1563565D01*
X218468Y1563513D01*
X218123Y1563307D01*
G01X221683Y1560465D02*
X221760Y1561137D01*
X221875Y1561705D01*
X222028Y1562222D01*
X222220Y1562790D01*
X222527Y1563565D01*
X220993D01*
G01X201768Y1588634D02*
X207768D01*
Y1576634D01*
X201768D01*
Y1588634D01*
G01X210040Y1586243D02*
X245780D01*
Y1569313D01*
X210040D01*
Y1586243D01*
G01X208890Y1569312D02*
X210399Y1569316D01*
G01X208840Y1586245D02*
X208846Y1569262D01*
G01X209440Y1586245D02*
X209436Y1569270D01*
G01X210040Y1586245D02*
X210037Y1569305D01*
G01X208840Y1586245D02*
X210040D01*
G01X214173Y1617677D02*
X223400D01*
G01X212157Y1629411D02*
X212467Y1629603D01*
X212674Y1629833D01*
X212777Y1630101D01*
X212674Y1630408D01*
X212467Y1630638D01*
X212157Y1630868D01*
X211744Y1630945D01*
X209677D01*
G01X212777Y1633278D02*
X209677D01*
X210297Y1632818D01*
G01X212777D02*
Y1633738D01*
G01Y1636378D02*
X209677D01*
X210297Y1635918D01*
G01X212777D02*
Y1636838D01*
G01X210194Y1638750D02*
X209884Y1638980D01*
X209729Y1639248D01*
X209677Y1639555D01*
X209780Y1639938D01*
X210039Y1640206D01*
X210349Y1640283D01*
X210659Y1640245D01*
X210917Y1640091D01*
X211434Y1639325D01*
X211795Y1638980D01*
X212312Y1638750D01*
X212777Y1638673D01*
Y1640283D01*
G01X214173Y1710500D02*
Y1626700D01*
G01X218627Y1645387D02*
X215527D01*
Y1646307D01*
X215682Y1646614D01*
X216044Y1646844D01*
X216457Y1646921D01*
X216870Y1646844D01*
X217180Y1646652D01*
X217335Y1646307D01*
Y1645387D01*
G01X218627Y1648487D02*
X215527D01*
Y1649446D01*
X215682Y1649752D01*
X215889Y1649944D01*
X216302Y1650021D01*
X216715Y1649944D01*
X216974Y1649714D01*
X217129Y1649446D01*
Y1648487D01*
G01Y1649446D02*
X218627Y1650021D01*
G01Y1653121D02*
Y1651587D01*
X215527D01*
Y1653121D01*
G01X217025Y1652507D02*
Y1651587D01*
G01X218214Y1654649D02*
X218472Y1654956D01*
X218627Y1655301D01*
Y1655607D01*
X218472Y1655914D01*
X218214Y1656144D01*
X217852Y1656259D01*
X217490Y1656182D01*
X217180Y1655991D01*
X216974Y1655646D01*
X216870Y1655186D01*
X216664Y1654917D01*
X216302Y1654802D01*
X215940Y1654879D01*
X215682Y1655071D01*
X215527Y1655339D01*
Y1655607D01*
X215630Y1655876D01*
X215889Y1656106D01*
G01X218214Y1657749D02*
X218472Y1658056D01*
X218627Y1658401D01*
Y1658707D01*
X218472Y1659014D01*
X218214Y1659244D01*
X217852Y1659359D01*
X217490Y1659282D01*
X217180Y1659091D01*
X216974Y1658746D01*
X216870Y1658286D01*
X216664Y1658017D01*
X216302Y1657902D01*
X215940Y1657979D01*
X215682Y1658171D01*
X215527Y1658439D01*
Y1658707D01*
X215630Y1658976D01*
X215889Y1659206D01*
G01X217594Y1661156D02*
Y1662152D01*
G01X218627Y1664026D02*
X215527D01*
Y1665482D01*
G01X217025Y1664946D02*
Y1664026D01*
G01X215527Y1667394D02*
Y1668314D01*
G01Y1667854D02*
X218627D01*
G01Y1667394D02*
Y1668314D01*
G01X215527Y1670954D02*
X218627D01*
G01X215527Y1670072D02*
Y1671836D01*
G01X212600Y1710400D02*
X209400D01*
G01D02*
Y1716600D01*
G01X212600D02*
Y1710400D01*
G01X203600Y1708600D02*
Y1705400D01*
G01X204400D02*
Y1708600D01*
G01X210600Y1705400D02*
X204400D01*
G01X210600Y1708600D02*
Y1705400D01*
G01X204400Y1708600D02*
X210600D01*
G01X207800Y1719331D02*
Y1710669D01*
G01X209400Y1716600D02*
X212600D01*
G01X204715Y1721400D02*
Y1724600D01*
G01X210915Y1721400D02*
X204715D01*
G01X210915Y1724600D02*
Y1721400D01*
G01X204715Y1724600D02*
X210915D01*
G01X202379D02*
Y1721400D01*
G01X214173Y1736118D02*
Y1717000D01*
G01X205138Y1719331D02*
X207800D01*
G01X202500Y1716500D02*
X205138Y1719331D01*
G01X226000Y-626038D02*
X226500Y-626838D01*
X227100Y-627371D01*
X227800Y-627638D01*
X228600Y-627371D01*
X229200Y-626838D01*
X229800Y-626038D01*
X230000Y-624971D01*
Y-619638D01*
G01X237800Y-627638D02*
Y-622305D01*
G01Y-623238D02*
X237400Y-622705D01*
X236800Y-622438D01*
X236100Y-622305D01*
X235400Y-622571D01*
X234800Y-623105D01*
X234400Y-623905D01*
X234200Y-624971D01*
X234400Y-626038D01*
X234800Y-626838D01*
X235400Y-627371D01*
X236100Y-627638D01*
X236800Y-627505D01*
X237400Y-627105D01*
X237800Y-626572D01*
G01X245600Y-622971D02*
X244900Y-622438D01*
X244300Y-622305D01*
X243500Y-622571D01*
X242900Y-623105D01*
X242500Y-624038D01*
X242400Y-624971D01*
X242500Y-625905D01*
X242900Y-626705D01*
X243500Y-627371D01*
X244300Y-627638D01*
X245000Y-627371D01*
X245600Y-626838D01*
G01X250300Y-627638D02*
Y-619638D01*
G01X253500Y-622305D02*
X250300Y-625371D01*
G01X251600Y-624171D02*
X253700Y-627638D01*
G01X219500Y51142D02*
X216500D01*
G01X225580Y122262D02*
Y119062D01*
G01D02*
X219380D01*
G01D02*
Y122262D01*
G01X216277Y107291D02*
X218499D01*
X218964Y107444D01*
X219274Y107751D01*
X219377Y108134D01*
X219274Y108517D01*
X218964Y108824D01*
X218499Y108977D01*
X216277D01*
G01X216794Y110506D02*
X216484Y110736D01*
X216329Y111004D01*
X216277Y111311D01*
X216380Y111694D01*
X216639Y111962D01*
X216949Y112039D01*
X217259Y112001D01*
X217517Y111847D01*
X218034Y111081D01*
X218395Y110736D01*
X218912Y110506D01*
X219377Y110429D01*
Y112039D01*
G01X216794Y113606D02*
X216484Y113836D01*
X216329Y114104D01*
X216277Y114411D01*
X216380Y114794D01*
X216639Y115062D01*
X216949Y115139D01*
X217259Y115101D01*
X217517Y114947D01*
X218034Y114181D01*
X218395Y113836D01*
X218912Y113606D01*
X219377Y113529D01*
Y115139D01*
G01X218912Y116591D02*
X219170Y116821D01*
X219325Y117089D01*
X219377Y117434D01*
X219274Y117779D01*
X219067Y118047D01*
X218705Y118239D01*
X218292Y118277D01*
X217879Y118201D01*
X217620Y118009D01*
X217414Y117741D01*
X217362Y117472D01*
X217414Y117204D01*
X217620Y116859D01*
X216277Y116974D01*
Y118009D01*
G01X219380Y122262D02*
X225580D01*
G01X219380Y126262D02*
X225580D01*
G01D02*
Y123062D01*
G01D02*
X219380D01*
G01D02*
Y126262D01*
G01X231116Y150459D02*
X227916D01*
G01D02*
Y156659D01*
G01X220752Y147150D02*
Y150350D01*
G01X226952Y147150D02*
X220752D01*
G01X226952Y150350D02*
Y147150D01*
G01X220752Y150350D02*
X226952D01*
G01Y143110D02*
X220752D01*
Y146310D01*
X226952D01*
Y143110D01*
G01X216400Y154900D02*
Y158100D01*
G01X222600Y154900D02*
X216400D01*
G01X222600Y158100D02*
Y154900D01*
G01X216400Y158100D02*
X222600D01*
G01X235120Y157471D02*
X228920D01*
G01D02*
Y160671D01*
G01D02*
X235120D01*
G01X227916Y156659D02*
X231116D01*
G01X223490Y151870D02*
Y158070D01*
X226690D01*
Y151870D01*
X223490D01*
G01X222729Y181521D02*
X219629D01*
G01Y183131D02*
X222729D01*
G01X221179D02*
Y181521D01*
G01X222729Y185349D02*
X222057Y185426D01*
X221489Y185541D01*
X220972Y185694D01*
X220404Y185886D01*
X219629Y186193D01*
Y184659D01*
G01X222729Y188986D02*
X219629D01*
X221851Y187568D01*
Y189484D01*
G01X222920Y208420D02*
X229120D01*
Y205220D01*
X222920D01*
Y208420D01*
G01X229409Y203428D02*
Y201206D01*
X229562Y200741D01*
X229869Y200431D01*
X230252Y200328D01*
X230635Y200431D01*
X230942Y200741D01*
X231095Y201206D01*
Y203428D01*
G01X232700Y200690D02*
X232969Y200431D01*
X233275Y200328D01*
X233582Y200431D01*
X233850Y200741D01*
X234042Y201206D01*
X234119Y201671D01*
Y202240D01*
X234042Y202705D01*
X233850Y203118D01*
X233620Y203325D01*
X233352Y203428D01*
X233045Y203325D01*
X232815Y203118D01*
X232662Y202808D01*
X232585Y202395D01*
X232662Y202033D01*
X232854Y201671D01*
X233084Y201465D01*
X233352Y201413D01*
X233659Y201516D01*
X233889Y201775D01*
X234119Y202240D01*
G01X236452Y203428D02*
X236145Y203325D01*
X235915Y203066D01*
X235762Y202756D01*
X235647Y202343D01*
X235609Y201878D01*
X235647Y201413D01*
X235762Y201000D01*
X235915Y200690D01*
X236145Y200431D01*
X236452Y200328D01*
X236759Y200431D01*
X236989Y200690D01*
X237142Y201000D01*
X237257Y201413D01*
X237295Y201878D01*
X237257Y202343D01*
X237142Y202756D01*
X236989Y203066D01*
X236759Y203325D01*
X236452Y203428D01*
G01X238709Y200793D02*
X238939Y200535D01*
X239207Y200380D01*
X239552Y200328D01*
X239897Y200431D01*
X240165Y200638D01*
X240357Y201000D01*
X240395Y201413D01*
X240319Y201826D01*
X240127Y202085D01*
X239859Y202291D01*
X239590Y202343D01*
X239322Y202291D01*
X238977Y202085D01*
X239092Y203428D01*
X240127D01*
G01X242652Y200328D02*
Y203428D01*
X242192Y202808D01*
G01Y200328D02*
X243112D01*
G01X229902Y271154D02*
X230602Y269454D01*
X231302Y271154D01*
G01X228402Y272054D02*
Y269454D01*
G01X226052Y270654D02*
X225952Y270754D01*
X225802Y270854D01*
X225652Y270904D01*
X225402D01*
X225202Y270854D01*
X225052Y270754D01*
X224902Y270604D01*
X224852Y270504D01*
X224802Y270354D01*
Y270154D01*
X224852Y269904D01*
X224952Y269754D01*
X225052Y269654D01*
X225202Y269554D01*
X225352Y269504D01*
X225552D01*
X225802Y269554D01*
X225952Y269654D01*
X226052Y269754D01*
G01X226212Y270204D02*
G03I-710J0D01*
G01X226052Y272004D02*
Y269454D01*
G01X222752Y270654D02*
X222852Y270854D01*
X222952Y271004D01*
X223052Y271104D01*
X223252Y271154D01*
X223402D01*
X223602Y271104D01*
X223752Y270904D01*
X223852Y270704D01*
Y269454D01*
G01X222752Y271154D02*
Y269454D01*
G01X220602Y271554D02*
X220702Y271754D01*
X220802Y271854D01*
X220952Y271954D01*
X221152Y272004D01*
X221402Y271954D01*
X221652Y271704D01*
X221702Y271554D01*
Y271204D01*
X221652Y271054D01*
X221552Y270904D01*
X221452Y270804D01*
X221302Y270704D01*
X221102Y270554D01*
X220952Y270354D01*
X220852Y270254D01*
X220752Y270104D01*
X220652Y269804D01*
X220602Y269454D01*
X221802D01*
G01X226752Y262604D02*
G03X233552Y257604I6035J1083D01*
G01X233452Y267804D02*
G03X226752Y262604I-585J-6163D01*
G01X227752Y287604D02*
X238752Y276104D01*
G01X240962Y281604D02*
G03I-8010J0D01*
G01X221012Y298307D02*
Y306307D01*
X223512D01*
X224312Y305907D01*
X224812Y305374D01*
X225012Y304307D01*
X224812Y303240D01*
X224212Y302574D01*
X223512Y302174D01*
X221012D01*
G01X223512D02*
X225012Y298307D01*
G01X229512Y301907D02*
X232712D01*
X232412Y302840D01*
X231912Y303374D01*
X231212Y303640D01*
X230512Y303507D01*
X229912Y303107D01*
X229512Y302174D01*
X229312Y301373D01*
Y300574D01*
X229512Y299774D01*
X230012Y298974D01*
X230612Y298440D01*
X231312Y298307D01*
X232012Y298574D01*
X232712Y299373D01*
G01X237212Y303640D02*
X239012Y298307D01*
X240812Y303640D01*
G01X247012Y298040D02*
X246812Y298174D01*
Y298440D01*
X247012Y298574D01*
X247212Y298440D01*
Y298174D01*
X247012Y298040D01*
G01Y301640D02*
X246812Y301774D01*
Y302040D01*
X247012Y302174D01*
X247212Y302040D01*
Y301774D01*
X247012Y301640D01*
G01X257212Y305640D02*
X256612Y306040D01*
X255912Y306307D01*
X255112D01*
X254212Y305907D01*
X253512Y305240D01*
X253012Y304440D01*
X252612Y303107D01*
X252512Y301907D01*
X252712Y300707D01*
X253012Y299907D01*
X253612Y299107D01*
X254312Y298574D01*
X255012Y298307D01*
X255712D01*
X256412Y298574D01*
X257012Y298974D01*
X257512Y299507D01*
G01X221439Y312444D02*
Y319944D01*
X223679D01*
X224426Y319569D01*
X224986Y318694D01*
X225173Y317694D01*
X224986Y316694D01*
X224519Y315944D01*
X223679Y315569D01*
X221439D01*
G01X229126Y312194D02*
X232486Y319944D01*
G01X236159Y312444D02*
Y319944D01*
X240453Y312444D01*
Y319944D01*
G01X245806Y312194D02*
X245619Y312319D01*
Y312569D01*
X245806Y312694D01*
X245993Y312569D01*
Y312319D01*
X245806Y312194D01*
G01Y315569D02*
X245619Y315694D01*
Y315944D01*
X245806Y316069D01*
X245993Y315944D01*
Y315694D01*
X245806Y315569D01*
G01X251253Y312444D02*
Y319944D01*
X253119D01*
X253866Y319569D01*
X254426Y319069D01*
X254893Y318319D01*
X255266Y317444D01*
X255359Y316194D01*
X255266Y314944D01*
X254893Y314069D01*
X254426Y313319D01*
X253866Y312819D01*
X253119Y312444D01*
X251253D01*
G01X258473D02*
X260806Y319944D01*
X263139Y312444D01*
G01X262299Y315069D02*
X259313D01*
G01X266533Y312444D02*
Y319944D01*
X270079D01*
G01X268773Y316319D02*
X266533D01*
G01X275806Y319944D02*
X275059Y319694D01*
X274499Y319069D01*
X274126Y318319D01*
X273846Y317319D01*
X273753Y316194D01*
X273846Y315069D01*
X274126Y314069D01*
X274499Y313319D01*
X275059Y312694D01*
X275806Y312444D01*
X276553Y312694D01*
X277113Y313319D01*
X277486Y314069D01*
X277766Y315069D01*
X277859Y316194D01*
X277766Y317319D01*
X277486Y318319D01*
X277113Y319069D01*
X276553Y319694D01*
X275806Y319944D01*
G01X283306D02*
Y312444D01*
G01X281159Y319944D02*
X285453D01*
G01X288379Y312444D02*
Y319944D01*
X290806Y313694D01*
X293233Y319944D01*
Y312444D01*
G01X299053Y316444D02*
X299426Y316819D01*
X299706Y317444D01*
X299893Y318319D01*
X299706Y319069D01*
X299333Y319569D01*
X298679Y319944D01*
X296159D01*
Y312444D01*
X299239D01*
X299893Y312944D01*
X300266Y313694D01*
X300453Y314569D01*
X300266Y315444D01*
X299706Y316194D01*
X299053Y316444D01*
X296159D01*
G01X303753Y313944D02*
X304313Y313069D01*
X305059Y312569D01*
X305899Y312444D01*
X306646Y312569D01*
X307393Y313194D01*
X307859Y313944D01*
X307953Y314694D01*
X307766Y315569D01*
X307113Y316194D01*
X306459Y316444D01*
X305619D01*
G01X306459D02*
X307019Y316819D01*
X307486Y317444D01*
X307673Y318194D01*
X307486Y318944D01*
X307019Y319569D01*
X306179Y319944D01*
X305339Y319819D01*
X304499Y319319D01*
G01X312186Y319944D02*
X314426D01*
G01X313306D02*
Y312444D01*
G01X312186D02*
X314426D01*
G01X322859Y319319D02*
X322299Y319694D01*
X321646Y319944D01*
X320899D01*
X320059Y319569D01*
X319406Y318944D01*
X318939Y318194D01*
X318566Y316944D01*
X318473Y315819D01*
X318659Y314694D01*
X318939Y313944D01*
X319499Y313194D01*
X320153Y312694D01*
X320806Y312444D01*
X321459D01*
X322113Y312694D01*
X322673Y313069D01*
X323139Y313569D01*
G01X328306Y319944D02*
X327559Y319694D01*
X326999Y319069D01*
X326626Y318319D01*
X326346Y317319D01*
X326253Y316194D01*
X326346Y315069D01*
X326626Y314069D01*
X326999Y313319D01*
X327559Y312694D01*
X328306Y312444D01*
X329053Y312694D01*
X329613Y313319D01*
X329986Y314069D01*
X330266Y315069D01*
X330359Y316194D01*
X330266Y317319D01*
X329986Y318319D01*
X329613Y319069D01*
X329053Y319694D01*
X328306Y319944D01*
G01X230275Y568709D02*
Y562509D01*
G01D02*
X227075D01*
G01D02*
Y568709D01*
G01X227533Y572729D02*
X233733D01*
G01Y569529D02*
X227533D01*
G01D02*
Y572729D01*
G01X227075Y568709D02*
X230275D01*
G01X216171Y574329D02*
X256371D01*
G01X216171Y587008D02*
Y574329D01*
G01Y614487D02*
Y601808D01*
G01X220468Y616730D02*
X223468Y619730D01*
G01D02*
Y623857D01*
G01X256371Y614487D02*
X216171D01*
G01X223468Y631257D02*
Y635384D01*
G01D02*
X220468Y638384D01*
G01X228942Y671160D02*
Y674260D01*
X229862D01*
X230169Y674105D01*
X230399Y673743D01*
X230476Y673330D01*
X230399Y672917D01*
X230207Y672607D01*
X229862Y672452D01*
X228942D01*
G01X232042Y674260D02*
Y671160D01*
X233576D01*
G01X235181Y673743D02*
X235411Y674053D01*
X235679Y674208D01*
X235986Y674260D01*
X236369Y674157D01*
X236637Y673898D01*
X236714Y673588D01*
X236676Y673278D01*
X236522Y673020D01*
X235756Y672503D01*
X235411Y672142D01*
X235181Y671625D01*
X235104Y671160D01*
X236714D01*
G01X238932D02*
X239009Y671832D01*
X239124Y672400D01*
X239277Y672917D01*
X239469Y673485D01*
X239776Y674260D01*
X238242D01*
G01X220150Y711600D02*
Y708500D01*
G01X219268Y711600D02*
X221032D01*
G01X222483Y708500D02*
Y711600D01*
X223403D01*
X223710Y711445D01*
X223940Y711083D01*
X224017Y710670D01*
X223940Y710257D01*
X223748Y709947D01*
X223403Y709792D01*
X222483D01*
G01X226350Y708500D02*
Y711600D01*
X225890Y710980D01*
G01Y708500D02*
X226810D01*
G01X229373D02*
X229450Y709172D01*
X229565Y709740D01*
X229718Y710257D01*
X229910Y710825D01*
X230217Y711600D01*
X228683D01*
G01X228601Y1306708D02*
Y1350016D01*
G01X233942Y1306708D02*
X228601D01*
G01X225529D02*
Y1350016D01*
G01X220188Y1306708D02*
X225529D01*
G01X225958Y1354816D02*
X232158D01*
G01X225958Y1351616D02*
Y1354816D01*
G01X232158Y1351616D02*
X225958D01*
G01X230724Y1355116D02*
X227524D01*
G01X230724Y1361316D02*
Y1355116D01*
G01X227524D02*
Y1361316D01*
G01X220644Y1353233D02*
X219851D01*
G01X220644Y1355833D02*
Y1353233D01*
G01X228601Y1350016D02*
X233942D01*
G01X225529D02*
X220188D01*
G01X223510Y1368735D02*
X226710D01*
G01X223510Y1362535D02*
Y1368735D01*
G01X226710Y1362535D02*
X223510D01*
G01X226710Y1368735D02*
Y1362535D01*
G01X230701Y1372437D02*
X227501D01*
G01D02*
Y1378637D01*
G01X230701Y1374700D02*
Y1372437D01*
G01X227501Y1368137D02*
X230701D01*
G01X227501Y1361937D02*
Y1368137D01*
G01X230701Y1361937D02*
X227501D01*
G01X230701Y1368137D02*
Y1361937D01*
G01X227524Y1361316D02*
X230724D01*
G01X216232Y1386458D02*
X219432D01*
G01X216232Y1380258D02*
Y1386458D01*
G01X219432Y1380258D02*
X216232D01*
G01X219432Y1386458D02*
Y1380258D01*
G01X230701Y1378637D02*
Y1377100D01*
G01X227501Y1378637D02*
X230701D01*
G01X224217Y1380705D02*
Y1383905D01*
G01X230417Y1380705D02*
X224217D01*
G01X230417Y1383905D02*
Y1380705D01*
G01X224217Y1383905D02*
X230417D01*
G01X220644Y1376855D02*
Y1374664D01*
G01X219911Y1376855D02*
X220644D01*
G01X216012Y1450259D02*
Y1416759D01*
G01D02*
X306012D01*
G01X216012Y1430259D02*
X231012D01*
G01X223055Y1437302D02*
X222680Y1437675D01*
X222055Y1437955D01*
X221180Y1438142D01*
X220430Y1437955D01*
X219930Y1437582D01*
X219555Y1436928D01*
Y1434408D01*
X227055D01*
Y1437488D01*
X226555Y1438142D01*
X225805Y1438515D01*
X224930Y1438702D01*
X224055Y1438515D01*
X223305Y1437955D01*
X223055Y1437302D01*
Y1434408D01*
G01X225930Y1442002D02*
X226555Y1442562D01*
X226930Y1443215D01*
X227055Y1444055D01*
X226805Y1444895D01*
X226305Y1445548D01*
X225430Y1446015D01*
X224430Y1446108D01*
X223430Y1445922D01*
X222805Y1445455D01*
X222305Y1444802D01*
X222180Y1444148D01*
X222305Y1443495D01*
X222805Y1442655D01*
X219555Y1442935D01*
Y1445455D01*
G01X231012Y1450259D02*
X216012D01*
G01X231074Y1567223D02*
X230514Y1567598D01*
X229861Y1567848D01*
X229114D01*
X228274Y1567473D01*
X227621Y1566848D01*
X227154Y1566098D01*
X226781Y1564848D01*
X226688Y1563723D01*
X226874Y1562598D01*
X227154Y1561848D01*
X227714Y1561098D01*
X228368Y1560598D01*
X229021Y1560348D01*
X229674D01*
X230328Y1560598D01*
X230888Y1560973D01*
X231354Y1561473D01*
G01X234654Y1560348D02*
Y1567848D01*
X236894D01*
X237641Y1567473D01*
X238201Y1566598D01*
X238388Y1565598D01*
X238201Y1564598D01*
X237734Y1563848D01*
X236894Y1563473D01*
X234654D01*
G01X241968Y1567848D02*
Y1562473D01*
X242341Y1561348D01*
X243088Y1560598D01*
X244021Y1560348D01*
X244954Y1560598D01*
X245701Y1561348D01*
X246074Y1562473D01*
Y1567848D01*
G01X251521Y1560348D02*
Y1567848D01*
X250401Y1566348D01*
G01Y1560348D02*
X252641D01*
G01X272154D02*
Y1567848D01*
X274394D01*
X275141Y1567473D01*
X275701Y1566598D01*
X275888Y1565598D01*
X275701Y1564598D01*
X275234Y1563848D01*
X274394Y1563473D01*
X272154D01*
G01X283574Y1567223D02*
X283014Y1567598D01*
X282361Y1567848D01*
X281614D01*
X280774Y1567473D01*
X280121Y1566848D01*
X279654Y1566098D01*
X279281Y1564848D01*
X279188Y1563723D01*
X279374Y1562598D01*
X279654Y1561848D01*
X280214Y1561098D01*
X280868Y1560598D01*
X281521Y1560348D01*
X282174D01*
X282828Y1560598D01*
X283388Y1560973D01*
X283854Y1561473D01*
G01X287901Y1567848D02*
X290141D01*
G01X289021D02*
Y1560348D01*
G01X287901D02*
X290141D01*
G01X295121Y1563723D02*
X298108D01*
X297828Y1564598D01*
X297361Y1565098D01*
X296708Y1565348D01*
X296054Y1565223D01*
X295494Y1564848D01*
X295121Y1563973D01*
X294934Y1563223D01*
Y1562473D01*
X295121Y1561723D01*
X295588Y1560973D01*
X296148Y1560473D01*
X296801Y1560348D01*
X297454Y1560598D01*
X298108Y1561348D01*
G01X230905Y1625425D02*
Y1628525D01*
X230445Y1627905D01*
G01Y1625425D02*
X231365D01*
G01X228400Y1617677D02*
X235600D01*
G01X225984Y1629488D02*
Y1736118D01*
G01X292519Y1629488D02*
X225984D01*
G01X222305Y1646132D02*
Y1643032D01*
G01X221423Y1646132D02*
X223187D01*
G01X222305Y1657205D02*
X221998Y1657257D01*
X221730Y1657463D01*
X221500Y1657773D01*
X221347Y1658135D01*
X221270Y1658548D01*
Y1658962D01*
X221347Y1659375D01*
X221500Y1659737D01*
X221730Y1660047D01*
X221998Y1660253D01*
X222305Y1660305D01*
X222612Y1660253D01*
X222880Y1660047D01*
X223110Y1659737D01*
X223263Y1659375D01*
X223340Y1658962D01*
Y1658548D01*
X223263Y1658135D01*
X223110Y1657773D01*
X222880Y1657463D01*
X222612Y1657257D01*
X222305Y1657205D01*
G01X222612Y1658032D02*
X223072Y1657205D01*
G01X221538Y1652480D02*
Y1655580D01*
X222497D01*
X222803Y1655425D01*
X222995Y1655218D01*
X223072Y1654805D01*
X222995Y1654392D01*
X222765Y1654133D01*
X222497Y1653978D01*
X221538D01*
G01X222497D02*
X223072Y1652480D01*
G01X221500Y1648169D02*
X221807Y1647911D01*
X222152Y1647756D01*
X222458D01*
X222765Y1647911D01*
X222995Y1648169D01*
X223110Y1648531D01*
X223033Y1648893D01*
X222842Y1649203D01*
X222497Y1649409D01*
X222037Y1649513D01*
X221768Y1649719D01*
X221653Y1650081D01*
X221730Y1650443D01*
X221922Y1650701D01*
X222190Y1650856D01*
X222458D01*
X222727Y1650753D01*
X222957Y1650494D01*
G01X221423Y1671378D02*
Y1674478D01*
X223187Y1671378D01*
Y1674478D01*
G01X222305Y1666654D02*
X221998Y1666706D01*
X221730Y1666912D01*
X221500Y1667222D01*
X221347Y1667584D01*
X221270Y1667997D01*
Y1668411D01*
X221347Y1668824D01*
X221500Y1669186D01*
X221730Y1669496D01*
X221998Y1669702D01*
X222305Y1669754D01*
X222612Y1669702D01*
X222880Y1669496D01*
X223110Y1669186D01*
X223263Y1668824D01*
X223340Y1668411D01*
Y1667997D01*
X223263Y1667584D01*
X223110Y1667222D01*
X222880Y1666912D01*
X222612Y1666706D01*
X222305Y1666654D01*
G01X221538Y1661929D02*
Y1665029D01*
X222458D01*
X222765Y1664874D01*
X222995Y1664512D01*
X223072Y1664099D01*
X222995Y1663686D01*
X222803Y1663376D01*
X222458Y1663221D01*
X221538D01*
G01X221462Y1685551D02*
Y1688651D01*
G01X222918D02*
X221462Y1686739D01*
G01X223148Y1685551D02*
X222113Y1687618D01*
G01X221538Y1683927D02*
Y1680827D01*
X223072D01*
G01X221308Y1676102D02*
Y1679202D01*
X222305Y1676619D01*
X223302Y1679202D01*
Y1676102D01*
G01X221500Y1699724D02*
Y1702824D01*
G01X223110D02*
Y1699724D01*
G01Y1701274D02*
X221500D01*
G01X221845Y1698100D02*
X222765D01*
G01X222305D02*
Y1695000D01*
G01X221845D02*
X222765D01*
G01X221538Y1690896D02*
X221730Y1690586D01*
X221960Y1690379D01*
X222228Y1690276D01*
X222535Y1690379D01*
X222765Y1690586D01*
X222995Y1690896D01*
X223072Y1691309D01*
Y1693376D01*
G01X222535Y1705999D02*
X223302D01*
Y1705069D01*
X223072Y1704759D01*
X222803Y1704552D01*
X222420Y1704449D01*
X222037Y1704552D01*
X221768Y1704759D01*
X221538Y1705069D01*
X221385Y1705431D01*
X221308Y1705844D01*
Y1706206D01*
X221385Y1706516D01*
X221538Y1706877D01*
X221768Y1707187D01*
X221998Y1707394D01*
X222305Y1707549D01*
X222573D01*
X222880Y1707446D01*
X223110Y1707239D01*
G01X223072Y1713898D02*
X221538D01*
Y1716998D01*
X223072D01*
G01X222458Y1715500D02*
X221538D01*
G01X221577Y1709173D02*
Y1712273D01*
X223033D01*
G01X222497Y1710775D02*
X221577D01*
G01X221462Y1718622D02*
Y1721722D01*
X222228D01*
X222535Y1721567D01*
X222765Y1721360D01*
X222957Y1721050D01*
X223110Y1720689D01*
X223148Y1720172D01*
X223110Y1719655D01*
X222957Y1719294D01*
X222765Y1718984D01*
X222535Y1718777D01*
X222228Y1718622D01*
X221462D01*
G01X223148Y1726189D02*
X222918Y1726344D01*
X222650Y1726447D01*
X222343D01*
X221998Y1726292D01*
X221730Y1726034D01*
X221538Y1725724D01*
X221385Y1725207D01*
X221347Y1724742D01*
X221423Y1724277D01*
X221538Y1723967D01*
X221768Y1723657D01*
X222037Y1723450D01*
X222305Y1723347D01*
X222573D01*
X222842Y1723450D01*
X223072Y1723605D01*
X223263Y1723812D01*
G01X222612Y1729724D02*
X222765Y1729879D01*
X222880Y1730138D01*
X222957Y1730499D01*
X222880Y1730809D01*
X222727Y1731016D01*
X222458Y1731171D01*
X221423D01*
Y1728071D01*
X222688D01*
X222957Y1728278D01*
X223110Y1728588D01*
X223187Y1728949D01*
X223110Y1729311D01*
X222880Y1729621D01*
X222612Y1729724D01*
X221423D01*
G01X225984Y1740118D02*
X292519D01*
G01X234666Y60762D02*
Y66962D01*
G01X237866Y60762D02*
X234666D01*
G01X237866Y66962D02*
Y60762D01*
G01X238666D02*
Y66962D01*
G01X241866Y60762D02*
X238666D01*
G01X241866Y66962D02*
Y60762D01*
G01X242666D02*
Y66962D01*
G01X245866Y60762D02*
X242666D01*
G01X278000Y51142D02*
X231000D01*
G01X240620Y74262D02*
Y77462D01*
G01X246820Y74262D02*
X240620D01*
G01Y70262D02*
Y73462D01*
G01X246820Y70262D02*
X240620D01*
G01Y73462D02*
X246820D01*
G01X234666Y66962D02*
X237866D01*
G01X238666D02*
X241866D01*
G01X242666D02*
X245866D01*
G01X240620Y77462D02*
X246820D01*
G01X241887Y103160D02*
Y109360D01*
G01X245087D02*
Y103160D01*
G01D02*
X241887D01*
G01X245194Y101703D02*
X247694D01*
X247194Y102023D01*
G01X245194D02*
Y101383D01*
G01Y99503D02*
X247694D01*
X247194Y99823D01*
G01X245194D02*
Y99183D01*
G01X241887Y109360D02*
X245087D01*
G01X251897Y114143D02*
X245697D01*
G01D02*
Y117343D01*
G01D02*
X251897D01*
G01X245697Y113343D02*
X251897D01*
G01Y110143D02*
X245697D01*
G01D02*
Y113343D01*
G01X244697Y122443D02*
Y128643D01*
G01D02*
X247897D01*
G01Y122443D02*
X244697D01*
G01X240697D02*
Y128643D01*
G01D02*
X243897D01*
G01D02*
Y122443D01*
G01D02*
X240697D01*
G01X239822Y125518D02*
X233622D01*
Y128718D01*
X239822D01*
Y125518D01*
G01X239897Y128643D02*
Y122443D01*
X236697D01*
Y128643D01*
X239897D01*
G01X231995Y150471D02*
Y156671D01*
G01X235195D02*
Y150471D01*
G01D02*
X231995D01*
G01X238800Y140462D02*
X232600D01*
G01D02*
Y143662D01*
G01D02*
X238800D01*
G01D02*
Y140462D01*
G01X231116Y156659D02*
Y150459D01*
G01X242775Y137748D02*
X242468Y137800D01*
X242200Y138006D01*
X241970Y138316D01*
X241817Y138678D01*
X241740Y139091D01*
Y139505D01*
X241817Y139918D01*
X241970Y140280D01*
X242200Y140590D01*
X242468Y140796D01*
X242775Y140848D01*
X243082Y140796D01*
X243350Y140590D01*
X243580Y140280D01*
X243733Y139918D01*
X243810Y139505D01*
Y139091D01*
X243733Y138678D01*
X243580Y138316D01*
X243350Y138006D01*
X243082Y137800D01*
X242775Y137748D01*
G01X243082Y138575D02*
X243542Y137748D01*
G01X245875D02*
Y140848D01*
X245415Y140228D01*
G01Y137748D02*
X246335D01*
G01X248975D02*
Y140848D01*
X248515Y140228D01*
G01Y137748D02*
X249435D01*
G01X252075D02*
X252343Y137800D01*
X252650Y137955D01*
X252842Y138213D01*
X252918Y138575D01*
X252842Y138936D01*
X252612Y139246D01*
X252267Y139401D01*
X251883D01*
X251653Y139505D01*
X251462Y139763D01*
X251385Y140125D01*
X251500Y140486D01*
X251768Y140745D01*
X252075Y140848D01*
X252382Y140745D01*
X252650Y140486D01*
X252765Y140125D01*
X252688Y139763D01*
X252497Y139505D01*
X252267Y139401D01*
X251883D01*
X251538Y139246D01*
X251308Y138936D01*
X251232Y138575D01*
X251308Y138213D01*
X251500Y137955D01*
X251807Y137800D01*
X252075Y137748D01*
G01X245955Y144748D02*
X244055Y142548D01*
G01D02*
X240708D01*
G01D02*
Y151210D01*
G01X231995Y156671D02*
X235195D01*
G01X235120Y160671D02*
Y157471D01*
G01X240708Y151210D02*
X251202D01*
G01X241537Y164618D02*
X241230Y164670D01*
X240962Y164876D01*
X240732Y165186D01*
X240579Y165548D01*
X240502Y165961D01*
Y166375D01*
X240579Y166788D01*
X240732Y167150D01*
X240962Y167460D01*
X241230Y167666D01*
X241537Y167718D01*
X241844Y167666D01*
X242112Y167460D01*
X242342Y167150D01*
X242495Y166788D01*
X242572Y166375D01*
Y165961D01*
X242495Y165548D01*
X242342Y165186D01*
X242112Y164876D01*
X241844Y164670D01*
X241537Y164618D01*
G01X241844Y165445D02*
X242304Y164618D01*
G01X244637D02*
Y167718D01*
X244177Y167098D01*
G01Y164618D02*
X245097D01*
G01X247737D02*
Y167718D01*
X247277Y167098D01*
G01Y164618D02*
X248197D01*
G01X250185Y164980D02*
X250454Y164721D01*
X250760Y164618D01*
X251067Y164721D01*
X251335Y165031D01*
X251527Y165496D01*
X251604Y165961D01*
Y166530D01*
X251527Y166995D01*
X251335Y167408D01*
X251105Y167615D01*
X250837Y167718D01*
X250530Y167615D01*
X250300Y167408D01*
X250147Y167098D01*
X250070Y166685D01*
X250147Y166323D01*
X250339Y165961D01*
X250569Y165755D01*
X250837Y165703D01*
X251144Y165806D01*
X251374Y166065D01*
X251604Y166530D01*
G01X240748Y161934D02*
X244095D01*
G01D02*
X245995Y159734D01*
G01X251242Y153272D02*
X240748D01*
G01D02*
Y161934D01*
G01X245432Y214891D02*
X242830Y217493D01*
X238608D01*
Y205289D01*
X252256D01*
Y217493D01*
X248034D01*
X245432Y214891D01*
G01X244502Y271954D02*
Y269454D01*
X245202Y269504D01*
G01X242802Y271054D02*
X242652Y271104D01*
X242452Y271154D01*
X242302D01*
X242102Y271104D01*
X242002Y271054D01*
X241852Y270954D01*
X241752Y270854D01*
X241652Y270704D01*
X241602Y270604D01*
X241552Y270354D01*
Y270204D01*
X241602Y270004D01*
X241652Y269904D01*
X241752Y269754D01*
X241852Y269654D01*
X242002Y269554D01*
X242102Y269504D01*
X242352Y269454D01*
X242552D01*
X242802Y269554D01*
G01X240102Y271954D02*
Y269454D01*
X240802Y269504D01*
G01X237452Y271154D02*
Y269454D01*
G01Y270654D02*
X237552Y270854D01*
X237652Y271004D01*
X237752Y271104D01*
X237952Y271154D01*
X238102D01*
X238302Y271104D01*
X238452Y270904D01*
X238552Y270704D01*
Y269454D01*
G01X235702Y271204D02*
Y269454D01*
G01X232802Y272054D02*
Y269454D01*
G01X232452Y267804D02*
G02X239152Y262604I585J-6163D01*
G01D02*
G02X232352Y257604I-6035J1083D01*
G01X244052Y271104D02*
X244952D01*
G01X239652D02*
X240552D01*
G01X235702Y272454D02*
X235602Y272354D01*
Y272254D01*
X235702Y272154D01*
X235802Y272254D01*
Y272354D01*
X235702Y272454D01*
G01X234417Y568677D02*
Y562477D01*
G01D02*
X231217D01*
G01D02*
Y568677D01*
G01X243964Y567514D02*
Y570614D01*
X244884D01*
X245191Y570459D01*
X245421Y570097D01*
X245498Y569684D01*
X245421Y569271D01*
X245229Y568961D01*
X244884Y568806D01*
X243964D01*
G01X247064Y570614D02*
Y567514D01*
X248598D01*
G01X250088Y567979D02*
X250318Y567721D01*
X250586Y567566D01*
X250931Y567514D01*
X251276Y567617D01*
X251544Y567824D01*
X251736Y568186D01*
X251774Y568599D01*
X251698Y569012D01*
X251506Y569271D01*
X251238Y569477D01*
X250969Y569529D01*
X250701Y569477D01*
X250356Y569271D01*
X250471Y570614D01*
X251506D01*
G01X253954Y567514D02*
X254031Y568186D01*
X254146Y568754D01*
X254299Y569271D01*
X254491Y569839D01*
X254798Y570614D01*
X253264D01*
G01X233733Y572729D02*
Y569529D01*
G01X231217Y568677D02*
X234417D01*
G01X242525Y661638D02*
Y667838D01*
G01D02*
X245725D01*
G01Y661638D02*
X242525D01*
G01X240752Y705014D02*
Y679424D01*
G01D02*
X236757D01*
G01X243227Y723409D02*
Y680101D01*
G01D02*
X248568D01*
G01X241443Y716848D02*
Y710648D01*
G01D02*
X238243D01*
G01D02*
Y716848D01*
G01D02*
X241443D01*
G01X237343Y714223D02*
X231143D01*
G01D02*
Y717423D01*
G01X237343D02*
Y714223D01*
G01X231186Y713202D02*
X237386D01*
G01D02*
Y710002D01*
G01D02*
X231186D01*
G01D02*
Y713202D01*
G01X236757Y705014D02*
X240752D01*
G01X231143Y717423D02*
X237343D01*
G01X238693Y775500D02*
Y719000D01*
G01X245000Y724883D02*
X241900D01*
Y725803D01*
X242055Y726110D01*
X242417Y726340D01*
X242830Y726417D01*
X243243Y726340D01*
X243553Y726148D01*
X243708Y725803D01*
Y724883D01*
G01X241900Y727983D02*
X245000D01*
Y729517D01*
G01Y731850D02*
X244948Y732118D01*
X244793Y732425D01*
X244535Y732617D01*
X244173Y732693D01*
X243812Y732617D01*
X243502Y732387D01*
X243347Y732042D01*
Y731658D01*
X243243Y731428D01*
X242985Y731237D01*
X242623Y731160D01*
X242262Y731275D01*
X242003Y731543D01*
X241900Y731850D01*
X242003Y732157D01*
X242262Y732425D01*
X242623Y732540D01*
X242985Y732463D01*
X243243Y732272D01*
X243347Y732042D01*
Y731658D01*
X243502Y731313D01*
X243812Y731083D01*
X244173Y731007D01*
X244535Y731083D01*
X244793Y731275D01*
X244948Y731582D01*
X245000Y731850D01*
G01X248568Y723409D02*
X243227D01*
G01X238693Y1025000D02*
Y1010500D01*
G01Y1303000D02*
Y1252000D01*
G01X232158Y1354816D02*
Y1351616D01*
G01X233758Y1353233D02*
Y1355833D01*
G01X234551Y1353233D02*
X233758D01*
G01Y1362444D02*
Y1364142D01*
G01X234595Y1381068D02*
X231395D01*
G01X234595Y1387268D02*
Y1381068D01*
G01X231395Y1387268D02*
X234595D01*
G01X231395Y1381068D02*
Y1387268D01*
G01X235365Y1383962D02*
Y1387162D01*
G01X241565Y1383962D02*
X235365D01*
G01X241565Y1387162D02*
Y1383962D01*
G01X235365Y1387162D02*
X241565D01*
G01X248190Y1380258D02*
X244990D01*
G01Y1386458D02*
X248190D01*
G01X244990Y1380258D02*
Y1386458D01*
G01X233758Y1376855D02*
X234766D01*
G01X233758Y1375001D02*
Y1376855D01*
G01X231484Y1388516D02*
Y1391616D01*
X232404D01*
X232711Y1391461D01*
X232941Y1391099D01*
X233018Y1390686D01*
X232941Y1390273D01*
X232749Y1389963D01*
X232404Y1389808D01*
X231484D01*
G01X234584Y1391616D02*
Y1388516D01*
X236118D01*
G01X238911D02*
Y1391616D01*
X237493Y1389394D01*
X239409D01*
G01X240708Y1389136D02*
X240938Y1388774D01*
X241244Y1388568D01*
X241589Y1388516D01*
X241896Y1388568D01*
X242203Y1388826D01*
X242394Y1389136D01*
X242433Y1389446D01*
X242356Y1389808D01*
X242088Y1390066D01*
X241819Y1390169D01*
X241474D01*
G01X241819D02*
X242049Y1390324D01*
X242241Y1390583D01*
X242318Y1390893D01*
X242241Y1391203D01*
X242049Y1391461D01*
X241704Y1391616D01*
X241359Y1391564D01*
X241014Y1391358D01*
G01X231383Y1393000D02*
Y1396100D01*
X232303D01*
X232610Y1395945D01*
X232840Y1395583D01*
X232917Y1395170D01*
X232840Y1394757D01*
X232648Y1394447D01*
X232303Y1394292D01*
X231383D01*
G01X234407Y1396100D02*
Y1393878D01*
X234560Y1393413D01*
X234867Y1393103D01*
X235250Y1393000D01*
X235633Y1393103D01*
X235940Y1393413D01*
X236093Y1393878D01*
Y1396100D01*
G01X237507Y1393620D02*
X237737Y1393258D01*
X238043Y1393052D01*
X238388Y1393000D01*
X238695Y1393052D01*
X239002Y1393310D01*
X239193Y1393620D01*
X239232Y1393930D01*
X239155Y1394292D01*
X238887Y1394550D01*
X238618Y1394653D01*
X238273D01*
G01X238618D02*
X238848Y1394808D01*
X239040Y1395067D01*
X239117Y1395377D01*
X239040Y1395687D01*
X238848Y1395945D01*
X238503Y1396100D01*
X238158Y1396048D01*
X237813Y1395842D01*
G01X240722Y1394292D02*
X240990Y1394653D01*
X241220Y1394860D01*
X241527Y1394963D01*
X241795Y1394860D01*
X241987Y1394653D01*
X242140Y1394343D01*
X242178Y1393982D01*
X242140Y1393672D01*
X241987Y1393362D01*
X241757Y1393103D01*
X241488Y1393000D01*
X241182Y1393103D01*
X240913Y1393413D01*
X240760Y1393878D01*
X240722Y1394395D01*
X240798Y1395067D01*
X240913Y1395428D01*
X241105Y1395790D01*
X241373Y1396048D01*
X241642Y1396100D01*
X241910Y1395997D01*
X242102Y1395738D01*
G01X231012Y1430259D02*
Y1450259D01*
G01Y1430259D02*
Y1450259D01*
G01X246012Y1430259D02*
X231012D01*
G01X238055Y1437302D02*
X237680Y1437675D01*
X237055Y1437955D01*
X236180Y1438142D01*
X235430Y1437955D01*
X234930Y1437582D01*
X234555Y1436928D01*
Y1434408D01*
X242055D01*
Y1437488D01*
X241555Y1438142D01*
X240805Y1438515D01*
X239930Y1438702D01*
X239055Y1438515D01*
X238305Y1437955D01*
X238055Y1437302D01*
Y1434408D01*
G01X242055Y1445175D02*
X234555D01*
X239930Y1441722D01*
Y1446388D01*
G01X231012Y1450259D02*
X246012D01*
G01X241688Y1587745D02*
X244114D01*
G01X245810Y1626045D02*
X246040Y1625683D01*
X246346Y1625477D01*
X246691Y1625425D01*
X246998Y1625477D01*
X247305Y1625735D01*
X247496Y1626045D01*
X247535Y1626355D01*
X247458Y1626717D01*
X247190Y1626975D01*
X246921Y1627078D01*
X246576D01*
G01X246921D02*
X247151Y1627233D01*
X247343Y1627492D01*
X247420Y1627802D01*
X247343Y1628112D01*
X247151Y1628370D01*
X246806Y1628525D01*
X246461Y1628473D01*
X246116Y1628267D01*
G01X238051Y1627941D02*
X238281Y1628251D01*
X238549Y1628406D01*
X238856Y1628458D01*
X239239Y1628355D01*
X239507Y1628096D01*
X239584Y1627786D01*
X239546Y1627476D01*
X239392Y1627218D01*
X238626Y1626701D01*
X238281Y1626340D01*
X238051Y1625823D01*
X237974Y1625358D01*
X239584D01*
G01X240600Y1617677D02*
X247500D01*
G01X242238Y1736579D02*
X241172D01*
Y1739079D01*
X242238D01*
G01X241812Y1737871D02*
X241172D01*
G01X243318Y1736579D02*
Y1739079D01*
X243852D01*
X244065Y1738954D01*
X244225Y1738787D01*
X244358Y1738537D01*
X244465Y1738246D01*
X244492Y1737829D01*
X244465Y1737412D01*
X244358Y1737121D01*
X244225Y1736871D01*
X244065Y1736704D01*
X243852Y1736579D01*
X243318D01*
G01X246265Y1737829D02*
X246798D01*
Y1737079D01*
X246638Y1736829D01*
X246452Y1736662D01*
X246185Y1736579D01*
X245918Y1736662D01*
X245732Y1736829D01*
X245572Y1737079D01*
X245465Y1737371D01*
X245412Y1737704D01*
Y1737996D01*
X245465Y1738246D01*
X245572Y1738537D01*
X245732Y1738787D01*
X245892Y1738954D01*
X246105Y1739079D01*
X246292D01*
X246505Y1738996D01*
X246665Y1738829D01*
G01X248838Y1736579D02*
X247772D01*
Y1739079D01*
X248838D01*
G01X248412Y1737871D02*
X247772D01*
G01X252705Y1736579D02*
X252492Y1736621D01*
X252305Y1736787D01*
X252145Y1737037D01*
X252038Y1737329D01*
X251985Y1737662D01*
Y1737996D01*
X252038Y1738329D01*
X252145Y1738621D01*
X252305Y1738871D01*
X252492Y1739037D01*
X252705Y1739079D01*
X252918Y1739037D01*
X253105Y1738871D01*
X253265Y1738621D01*
X253372Y1738329D01*
X253425Y1737996D01*
Y1737662D01*
X253372Y1737329D01*
X253265Y1737037D01*
X253105Y1736787D01*
X252918Y1736621D01*
X252705Y1736579D01*
G01X254398D02*
Y1739079D01*
X255412D01*
G01X255038Y1737871D02*
X254398D01*
G01X258718Y1736579D02*
Y1739079D01*
X259252D01*
X259465Y1738954D01*
X259625Y1738787D01*
X259758Y1738537D01*
X259865Y1738246D01*
X259892Y1737829D01*
X259865Y1737412D01*
X259758Y1737121D01*
X259625Y1736871D01*
X259465Y1736704D01*
X259252Y1736579D01*
X258718D01*
G01X260838D02*
X261505Y1739079D01*
X262172Y1736579D01*
G01X261932Y1737454D02*
X261078D01*
G01X263118Y1739079D02*
Y1737287D01*
X263225Y1736912D01*
X263438Y1736662D01*
X263705Y1736579D01*
X263972Y1736662D01*
X264185Y1736912D01*
X264292Y1737287D01*
Y1739079D01*
G01X266065Y1737829D02*
X266598D01*
Y1737079D01*
X266438Y1736829D01*
X266252Y1736662D01*
X265985Y1736579D01*
X265718Y1736662D01*
X265532Y1736829D01*
X265372Y1737079D01*
X265265Y1737371D01*
X265212Y1737704D01*
Y1737996D01*
X265265Y1738246D01*
X265372Y1738537D01*
X265532Y1738787D01*
X265692Y1738954D01*
X265905Y1739079D01*
X266092D01*
X266305Y1738996D01*
X266465Y1738829D01*
G01X267545Y1736579D02*
Y1739079D01*
G01X268665D02*
Y1736579D01*
G01Y1737829D02*
X267545D01*
G01X270305Y1739079D02*
Y1736579D01*
G01X269692Y1739079D02*
X270918D01*
G01X273038Y1736579D02*
X271972D01*
Y1739079D01*
X273038D01*
G01X272612Y1737871D02*
X271972D01*
G01X274172Y1736579D02*
Y1739079D01*
X274838D01*
X275052Y1738954D01*
X275185Y1738787D01*
X275238Y1738454D01*
X275185Y1738121D01*
X275025Y1737912D01*
X274838Y1737787D01*
X274172D01*
G01X274838D02*
X275238Y1736579D01*
G01X277492Y1738871D02*
X277332Y1738996D01*
X277145Y1739079D01*
X276932D01*
X276692Y1738954D01*
X276505Y1738746D01*
X276372Y1738496D01*
X276265Y1738079D01*
X276238Y1737704D01*
X276292Y1737329D01*
X276372Y1737079D01*
X276532Y1736829D01*
X276718Y1736662D01*
X276905Y1736579D01*
X277092D01*
X277278Y1736662D01*
X277438Y1736787D01*
X277572Y1736954D01*
G01X278438Y1736579D02*
X279105Y1739079D01*
X279772Y1736579D01*
G01X279532Y1737454D02*
X278678D01*
G01X280772Y1736579D02*
Y1739079D01*
X281438D01*
X281652Y1738954D01*
X281785Y1738787D01*
X281838Y1738454D01*
X281785Y1738121D01*
X281625Y1737912D01*
X281438Y1737787D01*
X280772D01*
G01X281438D02*
X281838Y1736579D01*
G01X282918D02*
Y1739079D01*
X283452D01*
X283665Y1738954D01*
X283825Y1738787D01*
X283958Y1738537D01*
X284065Y1738246D01*
X284092Y1737829D01*
X284065Y1737412D01*
X283958Y1737121D01*
X283825Y1736871D01*
X283665Y1736704D01*
X283452Y1736579D01*
X282918D01*
G01X238855Y1736412D02*
X239755Y1737312D01*
G01X233855Y1736412D02*
X238855D01*
G01X233855Y1739812D02*
Y1736412D01*
G01X235855Y1737812D02*
X233855Y1739812D01*
G01X231855Y1737812D02*
X235855D01*
G01X233855Y1739812D02*
X231855Y1737812D01*
G01X275372Y43779D02*
X260572D01*
G01X254300Y60800D02*
Y64000D01*
G01X260500Y60800D02*
X254300D01*
G01X260500Y64000D02*
Y60800D01*
G01X254300Y56800D02*
Y60000D01*
G01X260500Y56800D02*
X254300D01*
G01Y60000D02*
X260500D01*
G01D02*
Y56800D01*
G01X254300Y56000D02*
X260500D01*
G01X254300Y52800D02*
Y56000D01*
G01X260500Y52800D02*
X254300D01*
G01X260500Y56000D02*
Y52800D01*
G01X246666Y60762D02*
Y66962D01*
G01X249866Y60762D02*
X246666D01*
G01X249866Y66962D02*
Y60762D01*
G01X245866Y66962D02*
Y60762D01*
G01X253200Y75000D02*
X259400D01*
G01X253200Y71800D02*
Y75000D01*
G01X259400Y71800D02*
X253200D01*
G01X259400Y75000D02*
Y71800D01*
G01X254300Y64000D02*
X260500D01*
G01X246820Y77462D02*
Y74262D01*
G01Y73462D02*
Y70262D01*
G01X246666Y66962D02*
X249866D01*
G01X261469Y75930D02*
X249469D01*
G01D02*
Y81930D01*
G01X262666Y64826D02*
X250666D01*
G01Y70826D02*
X262666D01*
G01X250666Y64826D02*
Y70826D01*
G01X256197Y89143D02*
X262397D01*
G01X256197Y85943D02*
Y89143D01*
G01X262397Y85943D02*
X256197D01*
G01X249287Y90433D02*
Y95033D01*
G01X259487Y90433D02*
X249287D01*
G01X259487Y95033D02*
Y90433D01*
G01X249469Y81930D02*
X261469D01*
G01X245887Y103160D02*
Y109360D01*
G01X249087D02*
Y103160D01*
G01D02*
X245887D01*
G01X253087Y109360D02*
Y103160D01*
G01D02*
X249887D01*
G01D02*
Y109360D01*
G01X249287Y95033D02*
X259487D01*
G01Y99933D02*
Y95333D01*
G01X249287Y99933D02*
X259487D01*
G01X249287Y95333D02*
Y99933D01*
G01X259487Y95333D02*
X249287D01*
G01X263327Y101236D02*
Y98736D01*
X263647Y99236D01*
G01Y101236D02*
X263007D01*
G01X261634Y99153D02*
X261474Y98903D01*
X261287Y98778D01*
X261074Y98736D01*
X260807Y98819D01*
X260620Y99028D01*
X260567Y99278D01*
X260594Y99528D01*
X260700Y99736D01*
X261234Y100153D01*
X261474Y100444D01*
X261634Y100861D01*
X261687Y101236D01*
X260567D01*
G01X256388Y106835D02*
Y103701D01*
G01D02*
X257553D01*
G01X245887Y109360D02*
X249087D01*
G01X251897Y117343D02*
Y114143D01*
G01X249887Y109360D02*
X253087D01*
G01X251897Y113343D02*
Y110143D01*
G01X258180Y120844D02*
X257994Y121053D01*
X257780Y121136D01*
X257567Y121053D01*
X257380Y120803D01*
X257247Y120428D01*
X257194Y120053D01*
Y119594D01*
X257247Y119219D01*
X257380Y118886D01*
X257540Y118719D01*
X257727Y118636D01*
X257940Y118719D01*
X258100Y118886D01*
X258207Y119136D01*
X258260Y119469D01*
X258207Y119761D01*
X258074Y120053D01*
X257914Y120219D01*
X257727Y120261D01*
X257514Y120178D01*
X257354Y119969D01*
X257194Y119594D01*
G01X252994Y118503D02*
X255494D01*
X254994Y118823D01*
G01X252994D02*
Y118183D01*
G01X255494Y116303D02*
X255411Y116516D01*
X255202Y116676D01*
X254952Y116783D01*
X254619Y116863D01*
X254244Y116890D01*
X253869Y116863D01*
X253536Y116783D01*
X253286Y116676D01*
X253077Y116516D01*
X252994Y116303D01*
X253077Y116090D01*
X253286Y115930D01*
X253536Y115823D01*
X253869Y115743D01*
X254244Y115716D01*
X254619Y115743D01*
X254952Y115823D01*
X255202Y115930D01*
X255411Y116090D01*
X255494Y116303D01*
G01X257553Y115905D02*
X256388D01*
G01D02*
Y112771D01*
G01Y110771D02*
Y108835D01*
G01X259697Y122443D02*
Y128643D01*
G01D02*
X262897D01*
G01Y122443D02*
X259697D01*
G01X252697D02*
Y128643D01*
G01D02*
X255897D01*
G01D02*
Y122443D01*
G01D02*
X252697D01*
G01X247897Y128643D02*
Y122443D01*
G01X248697D02*
Y128643D01*
G01D02*
X251897D01*
G01D02*
Y122443D01*
G01D02*
X248697D01*
G01X255061Y142482D02*
X261261D01*
G01Y139282D02*
X255061D01*
G01D02*
Y142482D01*
G01X258211Y146482D02*
X264411D01*
G01Y143282D02*
X258211D01*
G01D02*
Y146482D01*
G01X251202Y142548D02*
X247855D01*
G01D02*
X245955Y144748D01*
G01X251202Y151210D02*
Y142548D01*
G01X258500Y152362D02*
Y158562D01*
G01D02*
X261700D01*
G01Y152362D02*
X258500D01*
G01X253156Y155202D02*
Y161402D01*
G01D02*
X256356D01*
G01D02*
Y155202D01*
G01D02*
X253156D01*
G01X245995Y159734D02*
X247895Y161934D01*
G01D02*
X251242D01*
G01D02*
Y153272D01*
G01X258610Y209260D02*
X264810D01*
Y206060D01*
X258610D01*
Y209260D01*
G01X256870Y216570D02*
Y210370D01*
X253670D01*
Y216570D01*
X256870D01*
G01X260400Y219900D02*
Y223100D01*
G01X266600Y219900D02*
X260400D01*
G01Y223100D02*
X266600D01*
G01X260400Y219100D02*
X266600D01*
G01X260400Y215900D02*
Y219100D01*
G01X266600Y215900D02*
X260400D01*
G01X245940Y225970D02*
X252140D01*
Y222770D01*
X245940D01*
Y225970D01*
G01X265443Y582399D02*
X259243D01*
G01D02*
Y585599D01*
G01X256371Y574329D02*
Y587008D01*
G01X259243Y585599D02*
X265443D01*
G01X256371Y601808D02*
Y614487D01*
G01X246527Y642509D02*
X252727D01*
G01D02*
Y639309D01*
G01D02*
X246527D01*
G01D02*
Y642509D01*
G01X259346Y637502D02*
Y640602D01*
X260266D01*
X260573Y640447D01*
X260803Y640085D01*
X260880Y639672D01*
X260803Y639259D01*
X260611Y638949D01*
X260266Y638794D01*
X259346D01*
G01X262370Y640602D02*
Y638380D01*
X262523Y637915D01*
X262830Y637605D01*
X263213Y637502D01*
X263596Y637605D01*
X263903Y637915D01*
X264056Y638380D01*
Y640602D01*
G01X265585Y640085D02*
X265815Y640395D01*
X266083Y640550D01*
X266390Y640602D01*
X266773Y640499D01*
X267041Y640240D01*
X267118Y639930D01*
X267080Y639620D01*
X266926Y639362D01*
X266160Y638845D01*
X265815Y638484D01*
X265585Y637967D01*
X265508Y637502D01*
X267118D01*
G01X269873D02*
Y640602D01*
X268455Y638380D01*
X270371D01*
G01X249824Y643659D02*
Y649859D01*
G01D02*
X253024D01*
G01D02*
Y643659D01*
G01D02*
X249824D01*
G01X260491Y646155D02*
X266691D01*
G01Y642955D02*
X260491D01*
G01D02*
Y646155D01*
G01X257066Y649859D02*
Y643659D01*
G01D02*
X253866D01*
G01D02*
Y649859D01*
G01D02*
X257066D01*
G01X249345Y653262D02*
X248612D01*
G01D02*
Y655453D01*
G01X245725Y667838D02*
Y661638D01*
G01X248612Y674284D02*
Y676884D01*
G01D02*
X249405D01*
G01X256803Y781812D02*
Y804500D01*
G01X624519Y781812D02*
X256803D01*
G01Y818100D02*
Y834300D01*
G01Y850700D02*
Y867400D01*
G01Y906300D02*
Y919100D01*
G01Y936400D02*
Y954500D01*
G01Y973200D02*
Y1005500D01*
G01Y1011600D02*
Y1064400D01*
G01Y1080700D02*
Y1097200D01*
G01Y1113700D02*
Y1129200D01*
G01Y1155700D02*
Y1175400D01*
G01Y1190100D02*
Y1213300D01*
G01Y1223700D02*
Y1305430D01*
G01Y1256025D02*
X466000D01*
G01X259558Y1308670D02*
X265758D01*
G01X259558Y1305470D02*
Y1308670D01*
G01X265758Y1305470D02*
X259558D01*
G01X258129Y1306708D02*
Y1350016D01*
G01X252788Y1306708D02*
X258129D01*
G01X253444Y1353233D02*
X252651D01*
G01X253444Y1355833D02*
Y1353233D01*
G01X258129Y1350016D02*
X252788D01*
G01X256803Y1351280D02*
Y1361440D01*
G01X260178Y1368725D02*
X263378D01*
G01X260178Y1362525D02*
Y1368725D01*
G01X263378Y1362525D02*
X260178D01*
G01X256310Y1368735D02*
X259510D01*
G01X256310Y1362535D02*
Y1368735D01*
G01X259510Y1362535D02*
X256310D01*
G01X259510Y1368735D02*
Y1362535D01*
G01X256803Y1369950D02*
Y1393820D01*
G01X249032Y1386458D02*
X252232D01*
G01X249032Y1380258D02*
Y1386458D01*
G01X252232Y1380258D02*
X249032D01*
G01X252232Y1386458D02*
Y1380258D01*
G01X248190Y1386458D02*
Y1380258D01*
G01X253444Y1376855D02*
Y1374664D01*
G01X252711Y1376855D02*
X253444D01*
G01X256803Y1393820D02*
X283910D01*
G01X247255Y1419616D02*
Y1427116D01*
X249121D01*
X249868Y1426741D01*
X250428Y1426241D01*
X250895Y1425491D01*
X251268Y1424616D01*
X251361Y1423366D01*
X251268Y1422116D01*
X250895Y1421241D01*
X250428Y1420491D01*
X249868Y1419991D01*
X249121Y1419616D01*
X247255D01*
G01X255688Y1427116D02*
X257928D01*
G01X256808D02*
Y1419616D01*
G01X255688D02*
X257928D01*
G01X261881D02*
Y1427116D01*
X264308Y1420866D01*
X266735Y1427116D01*
Y1419616D01*
G01X269381D02*
Y1427116D01*
X271808Y1420866D01*
X274235Y1427116D01*
Y1419616D01*
G01X246012Y1450259D02*
Y1430259D01*
G01D02*
Y1450259D01*
G01X261012Y1430259D02*
X246012D01*
G01X253055Y1437302D02*
X252680Y1437675D01*
X252055Y1437955D01*
X251180Y1438142D01*
X250430Y1437955D01*
X249930Y1437582D01*
X249555Y1436928D01*
Y1434408D01*
X257055D01*
Y1437488D01*
X256555Y1438142D01*
X255805Y1438515D01*
X254930Y1438702D01*
X254055Y1438515D01*
X253305Y1437955D01*
X253055Y1437302D01*
Y1434408D01*
G01X255555Y1442002D02*
X256430Y1442562D01*
X256930Y1443308D01*
X257055Y1444148D01*
X256930Y1444895D01*
X256305Y1445642D01*
X255555Y1446108D01*
X254805Y1446202D01*
X253930Y1446015D01*
X253305Y1445362D01*
X253055Y1444708D01*
Y1443868D01*
G01Y1444708D02*
X252680Y1445268D01*
X252055Y1445735D01*
X251305Y1445922D01*
X250555Y1445735D01*
X249930Y1445268D01*
X249555Y1444428D01*
X249680Y1443588D01*
X250180Y1442748D01*
G01X246012Y1450259D02*
X261012D01*
G01X267197Y1507451D02*
X260000D01*
G01X260100Y1542491D02*
X267197D01*
G01X283185Y1569365D02*
X247445D01*
Y1586295D01*
X283185D01*
Y1569365D01*
G01X252847Y1587643D02*
X250421D01*
G01X254987Y1625358D02*
Y1628458D01*
X253569Y1626236D01*
X255485D01*
G01X252700Y1617677D02*
X259700D01*
G01X268342Y52954D02*
X268534Y52644D01*
X268764Y52437D01*
X269032Y52334D01*
X269339Y52437D01*
X269569Y52644D01*
X269799Y52954D01*
X269876Y53367D01*
Y55434D01*
G01X271366Y52954D02*
X271596Y52592D01*
X271902Y52386D01*
X272247Y52334D01*
X272554Y52386D01*
X272861Y52644D01*
X273052Y52954D01*
X273091Y53264D01*
X273014Y53626D01*
X272746Y53884D01*
X272477Y53987D01*
X272132D01*
G01X272477D02*
X272707Y54142D01*
X272899Y54401D01*
X272976Y54711D01*
X272899Y55021D01*
X272707Y55279D01*
X272362Y55434D01*
X272017Y55382D01*
X271672Y55176D01*
G01X274466Y52799D02*
X274696Y52541D01*
X274964Y52386D01*
X275309Y52334D01*
X275654Y52437D01*
X275922Y52644D01*
X276114Y53006D01*
X276152Y53419D01*
X276076Y53832D01*
X275884Y54091D01*
X275616Y54297D01*
X275347Y54349D01*
X275079Y54297D01*
X274734Y54091D01*
X274849Y55434D01*
X275884D01*
G01X264164Y56836D02*
X295168D01*
G01X264164Y71636D02*
Y56836D01*
G01X270356Y72936D02*
Y76136D01*
G01X276556Y72936D02*
X270356D01*
G01X261469Y81930D02*
Y75930D01*
G01X262666Y70826D02*
Y64826D01*
G01X295168Y71636D02*
X264164D01*
G01X273856Y80061D02*
X280056D01*
G01X273856Y76861D02*
Y80061D01*
G01X280056Y76861D02*
X273856D01*
G01X270356Y76136D02*
X276556D01*
G01X262397Y89143D02*
Y85943D01*
G01X261911Y91323D02*
Y94423D01*
X262831D01*
X263138Y94268D01*
X263368Y93906D01*
X263445Y93493D01*
X263368Y93080D01*
X263176Y92770D01*
X262831Y92615D01*
X261911D01*
G01X264935Y94423D02*
Y92201D01*
X265088Y91736D01*
X265395Y91426D01*
X265778Y91323D01*
X266161Y91426D01*
X266468Y91736D01*
X266621Y92201D01*
Y94423D01*
G01X268150Y93906D02*
X268380Y94216D01*
X268648Y94371D01*
X268955Y94423D01*
X269338Y94320D01*
X269606Y94061D01*
X269683Y93751D01*
X269645Y93441D01*
X269491Y93183D01*
X268725Y92666D01*
X268380Y92305D01*
X268150Y91788D01*
X268073Y91323D01*
X269683D01*
G01X271978Y94423D02*
X271671Y94320D01*
X271441Y94061D01*
X271288Y93751D01*
X271173Y93338D01*
X271135Y92873D01*
X271173Y92408D01*
X271288Y91995D01*
X271441Y91685D01*
X271671Y91426D01*
X271978Y91323D01*
X272285Y91426D01*
X272515Y91685D01*
X272668Y91995D01*
X272783Y92408D01*
X272821Y92873D01*
X272783Y93338D01*
X272668Y93751D01*
X272515Y94061D01*
X272285Y94320D01*
X271978Y94423D01*
G01X274350Y92615D02*
X274618Y92976D01*
X274848Y93183D01*
X275155Y93286D01*
X275423Y93183D01*
X275615Y92976D01*
X275768Y92666D01*
X275806Y92305D01*
X275768Y91995D01*
X275615Y91685D01*
X275385Y91426D01*
X275116Y91323D01*
X274810Y91426D01*
X274541Y91736D01*
X274388Y92201D01*
X274350Y92718D01*
X274426Y93390D01*
X274541Y93751D01*
X274733Y94113D01*
X275001Y94371D01*
X275270Y94423D01*
X275538Y94320D01*
X275730Y94061D01*
G01X272167Y97583D02*
Y100783D01*
G01X278367Y97583D02*
X272167D01*
G01Y100783D02*
X278367D01*
G01X275301Y103701D02*
X276466D01*
G01Y115905D02*
X275293D01*
G01X270197Y122443D02*
Y128643D01*
G01D02*
X273397D01*
G01D02*
Y122443D01*
G01D02*
X270197D01*
G01X262897Y128643D02*
Y122443D01*
G01X277397D02*
X274197D01*
G01D02*
Y128643D01*
G01D02*
X277397D01*
G01X266697Y125943D02*
Y132143D01*
G01D02*
X269897D01*
G01D02*
Y125943D01*
G01D02*
X266697D01*
G01X275300Y135362D02*
Y138562D01*
G01X281500Y135362D02*
X275300D01*
G01X261261Y142482D02*
Y139282D01*
G01X275300Y138562D02*
X281500D01*
G01X265450Y141292D02*
Y144492D01*
G01X271650Y141292D02*
X265450D01*
G01X271650Y144492D02*
Y141292D01*
G01X265450Y144492D02*
X271650D01*
G01X271653Y152803D02*
Y149603D01*
G01X265453D02*
Y152803D01*
G01X271653Y149603D02*
X265453D01*
G01Y148803D02*
X271653D01*
G01D02*
Y145603D01*
G01X265453D02*
Y148803D01*
G01X271653Y145603D02*
X265453D01*
G01X264411Y146482D02*
Y143282D01*
G01X271703Y138902D02*
Y135702D01*
G01X265503Y138902D02*
X271703D01*
G01X265503Y135702D02*
Y138902D01*
G01X271703Y135702D02*
X265503D01*
G01X261700Y158562D02*
Y152362D01*
G01X265453Y157603D02*
Y160803D01*
G01X271653Y157603D02*
X265453D01*
G01X271653Y160803D02*
Y157603D01*
G01X265453Y160803D02*
X271653D01*
G01X265453Y153603D02*
Y156803D01*
G01X271653Y153603D02*
X265453D01*
G01X271653Y156803D02*
Y153603D01*
G01X265453Y156803D02*
X271653D01*
G01X265453Y152803D02*
X271653D01*
G01X275400Y205400D02*
Y208600D01*
G01X281600Y205400D02*
X275400D01*
G01Y208600D02*
X281600D01*
G01X275400Y209400D02*
Y212600D01*
G01X281600Y209400D02*
X275400D01*
G01X274600Y212600D02*
Y209400D01*
G01X268400D02*
Y212600D01*
G01X274600Y209400D02*
X268400D01*
G01X275400Y212600D02*
X281600D01*
G01X275400Y216600D02*
X281600D01*
G01X275400Y213400D02*
Y216600D01*
G01X281600Y213400D02*
X275400D01*
G01X268400Y212600D02*
X274600D01*
G01X268400Y213400D02*
Y216600D01*
G01X274600Y213400D02*
X268400D01*
G01X274600Y216600D02*
Y213400D01*
G01X268400Y216600D02*
X274600D01*
G01X266600Y223100D02*
Y219900D01*
G01Y219100D02*
Y215900D01*
G01X269100Y218669D02*
Y227331D01*
G01X280900Y218669D02*
X269100D01*
G01X277100Y229400D02*
X273900D01*
G01Y235600D02*
X277100D01*
G01X273900Y229400D02*
Y235600D01*
G01X263405Y234801D02*
Y232579D01*
X263558Y232114D01*
X263865Y231804D01*
X264248Y231701D01*
X264631Y231804D01*
X264938Y232114D01*
X265091Y232579D01*
Y234801D01*
G01X266505Y232321D02*
X266735Y231959D01*
X267041Y231753D01*
X267386Y231701D01*
X267693Y231753D01*
X268000Y232011D01*
X268191Y232321D01*
X268230Y232631D01*
X268153Y232993D01*
X267885Y233251D01*
X267616Y233354D01*
X267271D01*
G01X267616D02*
X267846Y233509D01*
X268038Y233768D01*
X268115Y234078D01*
X268038Y234388D01*
X267846Y234646D01*
X267501Y234801D01*
X267156Y234749D01*
X266811Y234543D01*
G01X270371Y231701D02*
X270448Y232373D01*
X270563Y232941D01*
X270716Y233458D01*
X270908Y234026D01*
X271215Y234801D01*
X269681D01*
G01X269100Y227331D02*
X280900D01*
G01X278401Y576978D02*
X275201D01*
G01D02*
Y583178D01*
G01X265443Y585599D02*
Y582399D01*
G01X274669Y586670D02*
Y580470D01*
G01X271469D02*
Y586670D01*
G01X274669Y580470D02*
X271469D01*
G01X281526Y568798D02*
X275326D01*
G01D02*
Y571998D01*
G01D02*
X281526D01*
G01X271005Y586635D02*
Y580435D01*
G01D02*
X267805D01*
G01D02*
Y586635D01*
G01X275201Y583178D02*
X278401D01*
G01X264066Y599753D02*
Y593553D01*
G01D02*
X260866D01*
G01D02*
Y599753D01*
G01X275301Y586778D02*
X281501D01*
G01Y583578D02*
X275301D01*
G01D02*
Y586778D01*
G01X271469Y586670D02*
X274669D01*
G01X267805Y586635D02*
X271005D01*
G01X262266Y592554D02*
X265466D01*
G01X262266Y586354D02*
Y592554D01*
G01X265466Y586354D02*
X262266D01*
G01X265466Y592554D02*
Y586354D01*
G01X266934Y597435D02*
Y593633D01*
G01D02*
X267205D01*
G01X260866Y599753D02*
X264066D01*
G01X272519Y612772D02*
Y609572D01*
G01D02*
X266319D01*
G01D02*
Y612772D01*
G01X267205Y605837D02*
X266934D01*
G01D02*
Y602035D01*
G01X266319Y612772D02*
X272519D01*
G01X267947Y616224D02*
Y619324D01*
X268867D01*
X269174Y619169D01*
X269404Y618807D01*
X269481Y618394D01*
X269404Y617981D01*
X269212Y617671D01*
X268867Y617516D01*
X267947D01*
G01X270971Y619324D02*
Y617102D01*
X271124Y616637D01*
X271431Y616327D01*
X271814Y616224D01*
X272197Y616327D01*
X272504Y616637D01*
X272657Y617102D01*
Y619324D01*
G01X274071Y616844D02*
X274301Y616482D01*
X274607Y616276D01*
X274952Y616224D01*
X275259Y616276D01*
X275566Y616534D01*
X275757Y616844D01*
X275796Y617154D01*
X275719Y617516D01*
X275451Y617774D01*
X275182Y617877D01*
X274837D01*
G01X275182D02*
X275412Y618032D01*
X275604Y618291D01*
X275681Y618601D01*
X275604Y618911D01*
X275412Y619169D01*
X275067Y619324D01*
X274722Y619272D01*
X274377Y619066D01*
G01X270661Y649049D02*
Y642849D01*
G01D02*
X267461D01*
G01D02*
Y649049D01*
G01D02*
X270661D01*
G01X274555Y657680D02*
Y651480D01*
G01D02*
X271355D01*
G01D02*
Y652600D01*
G01Y656000D02*
Y657680D01*
G01X266691Y646155D02*
Y642955D01*
G01X268298Y655116D02*
Y653262D01*
G01D02*
X267290D01*
G01X271355Y657680D02*
X274555D01*
G01X271355Y661980D02*
Y668180D01*
G01D02*
X274555D01*
G01D02*
Y661980D01*
G01D02*
X271355D01*
G01X274532Y675001D02*
Y668801D01*
G01D02*
X271332D01*
G01D02*
Y675001D01*
G01X268298Y667673D02*
Y665975D01*
G01X269898Y678501D02*
X276098D01*
G01Y675301D02*
X269898D01*
G01D02*
Y678501D01*
G01X271332Y675001D02*
X274532D01*
G01X267505Y676884D02*
X268298D01*
G01D02*
Y674284D01*
G01X272755Y723409D02*
Y680101D01*
G01D02*
X267414D01*
G01X275255Y695879D02*
Y702079D01*
G01D02*
X278455D01*
G01Y695879D02*
X275255D01*
G01X267414Y723409D02*
X272755D01*
G01X273302Y744908D02*
X270202D01*
Y745828D01*
X270357Y746135D01*
X270719Y746365D01*
X271132Y746442D01*
X271545Y746365D01*
X271855Y746173D01*
X272010Y745828D01*
Y744908D01*
G01X270202Y748008D02*
X273302D01*
Y749542D01*
G01X272682Y751032D02*
X273044Y751262D01*
X273250Y751568D01*
X273302Y751913D01*
X273250Y752220D01*
X272992Y752527D01*
X272682Y752718D01*
X272372Y752757D01*
X272010Y752680D01*
X271752Y752412D01*
X271649Y752143D01*
Y751798D01*
G01Y752143D02*
X271494Y752373D01*
X271235Y752565D01*
X270925Y752642D01*
X270615Y752565D01*
X270357Y752373D01*
X270202Y752028D01*
X270254Y751683D01*
X270460Y751338D01*
G01X272682Y754132D02*
X273044Y754362D01*
X273250Y754668D01*
X273302Y755013D01*
X273250Y755320D01*
X272992Y755627D01*
X272682Y755818D01*
X272372Y755857D01*
X272010Y755780D01*
X271752Y755512D01*
X271649Y755243D01*
Y754898D01*
G01Y755243D02*
X271494Y755473D01*
X271235Y755665D01*
X270925Y755742D01*
X270615Y755665D01*
X270357Y755473D01*
X270202Y755128D01*
X270254Y754783D01*
X270460Y754438D01*
G01X262901Y1260562D02*
Y1303870D01*
G01X268242Y1260562D02*
X262901D01*
G01X265758Y1308670D02*
Y1305470D01*
G01X264324Y1308970D02*
X261124D01*
G01X264324Y1315170D02*
Y1308970D01*
G01X261124D02*
Y1315170D01*
G01X267358Y1307087D02*
Y1309687D01*
G01X268151Y1307087D02*
X267358D01*
G01X262901Y1303870D02*
X268242D01*
G01X264301Y1326291D02*
X261101D01*
G01D02*
Y1332491D01*
G01X264301Y1328500D02*
Y1326291D01*
G01X261101Y1321991D02*
X264301D01*
G01X261101Y1315791D02*
Y1321991D01*
G01X264301Y1315791D02*
X261101D01*
G01X264301Y1321991D02*
Y1315791D01*
G01X261124Y1315170D02*
X264324D01*
G01X267358Y1316298D02*
Y1317996D01*
G01X268195Y1334922D02*
X264995D01*
G01X268195Y1341122D02*
Y1334922D01*
G01X264995Y1341122D02*
X268195D01*
G01X264995Y1334922D02*
Y1341122D01*
G01X264301Y1332491D02*
Y1331000D01*
G01X261101Y1332491D02*
X264301D01*
G01X268965Y1337816D02*
Y1341016D01*
G01X275165Y1337816D02*
X268965D01*
G01X275165Y1341016D02*
Y1337816D01*
G01X268965Y1341016D02*
X275165D01*
G01X267358Y1330709D02*
X268366D01*
G01X267358Y1328855D02*
Y1330709D01*
G01X263378Y1368725D02*
Y1362525D01*
G01X266385Y1372239D02*
Y1375339D01*
G01X267995D02*
Y1372239D01*
G01Y1373789D02*
X266385D01*
G01X270290Y1372239D02*
Y1375339D01*
X269830Y1374719D01*
G01Y1372239D02*
X270750D01*
G01X272547Y1372859D02*
X272777Y1372497D01*
X273083Y1372291D01*
X273428Y1372239D01*
X273735Y1372291D01*
X274042Y1372549D01*
X274233Y1372859D01*
X274272Y1373169D01*
X274195Y1373531D01*
X273927Y1373789D01*
X273658Y1373892D01*
X273313D01*
G01X273658D02*
X273888Y1374047D01*
X274080Y1374306D01*
X274157Y1374616D01*
X274080Y1374926D01*
X273888Y1375184D01*
X273543Y1375339D01*
X273198Y1375287D01*
X272853Y1375081D01*
G01X261012Y1450259D02*
Y1430259D01*
G01D02*
Y1450259D01*
G01X276012Y1430259D02*
X261012D01*
G01X268055Y1437302D02*
X267680Y1437675D01*
X267055Y1437955D01*
X266180Y1438142D01*
X265430Y1437955D01*
X264930Y1437582D01*
X264555Y1436928D01*
Y1434408D01*
X272055D01*
Y1437488D01*
X271555Y1438142D01*
X270805Y1438515D01*
X269930Y1438702D01*
X269055Y1438515D01*
X268305Y1437955D01*
X268055Y1437302D01*
Y1434408D01*
G01X265805Y1442282D02*
X265055Y1442842D01*
X264680Y1443495D01*
X264555Y1444242D01*
X264805Y1445175D01*
X265430Y1445828D01*
X266180Y1446015D01*
X266930Y1445922D01*
X267555Y1445548D01*
X268805Y1443682D01*
X269680Y1442842D01*
X270930Y1442282D01*
X272055Y1442095D01*
Y1446015D01*
G01X261012Y1450259D02*
X276012D01*
G01X267197Y1542491D02*
Y1507451D01*
G01X275199Y1517620D02*
X281199D01*
Y1514620D01*
X275199D01*
Y1517620D01*
G01X271997Y1518320D02*
Y1524520D01*
X275197D01*
Y1518320D01*
X271997D01*
G01X278149Y1510620D02*
X271949D01*
Y1513820D01*
X278149D01*
Y1510620D01*
G01Y1514520D02*
X271949D01*
Y1517720D01*
X278149D01*
Y1514520D01*
G01X281299Y1510620D02*
X275099D01*
Y1513820D01*
X281299D01*
Y1510620D01*
G01X261558Y1625890D02*
X261788Y1625632D01*
X262056Y1625477D01*
X262401Y1625425D01*
X262746Y1625528D01*
X263014Y1625735D01*
X263206Y1626097D01*
X263244Y1626510D01*
X263168Y1626923D01*
X262976Y1627182D01*
X262708Y1627388D01*
X262439Y1627440D01*
X262171Y1627388D01*
X261826Y1627182D01*
X261941Y1628525D01*
X262976D01*
G01X269547Y1626650D02*
X269815Y1627011D01*
X270045Y1627218D01*
X270352Y1627321D01*
X270620Y1627218D01*
X270812Y1627011D01*
X270965Y1626701D01*
X271003Y1626340D01*
X270965Y1626030D01*
X270812Y1625720D01*
X270582Y1625461D01*
X270313Y1625358D01*
X270007Y1625461D01*
X269738Y1625771D01*
X269585Y1626236D01*
X269547Y1626753D01*
X269623Y1627425D01*
X269738Y1627786D01*
X269930Y1628148D01*
X270198Y1628406D01*
X270467Y1628458D01*
X270735Y1628355D01*
X270927Y1628096D01*
G01X264800Y1617677D02*
X271900D01*
G01X321898Y51142D02*
X286500D01*
G01X283556Y76136D02*
Y72936D01*
G01X277356D02*
Y76136D01*
G01X283556Y72936D02*
X277356D01*
G01X276556Y76136D02*
Y72936D01*
G01X288500Y73383D02*
X285400D01*
Y74342D01*
X285555Y74648D01*
X285762Y74840D01*
X286175Y74917D01*
X286588Y74840D01*
X286847Y74610D01*
X287002Y74342D01*
Y73383D01*
G01Y74342D02*
X288500Y74917D01*
G01Y77250D02*
X285400D01*
X286020Y76790D01*
G01X288500D02*
Y77710D01*
G01X287880Y79507D02*
X288242Y79737D01*
X288448Y80043D01*
X288500Y80388D01*
X288448Y80695D01*
X288190Y81002D01*
X287880Y81193D01*
X287570Y81232D01*
X287208Y81155D01*
X286950Y80887D01*
X286847Y80618D01*
Y80273D01*
G01Y80618D02*
X286692Y80848D01*
X286433Y81040D01*
X286123Y81117D01*
X285813Y81040D01*
X285555Y80848D01*
X285400Y80503D01*
X285452Y80158D01*
X285658Y79813D01*
G01X285917Y82722D02*
X285607Y82952D01*
X285452Y83220D01*
X285400Y83527D01*
X285503Y83910D01*
X285762Y84178D01*
X286072Y84255D01*
X286382Y84217D01*
X286640Y84063D01*
X287157Y83297D01*
X287518Y82952D01*
X288035Y82722D01*
X288500Y82645D01*
Y84255D01*
G01X288035Y85707D02*
X288293Y85937D01*
X288448Y86205D01*
X288500Y86550D01*
X288397Y86895D01*
X288190Y87163D01*
X287828Y87355D01*
X287415Y87393D01*
X287002Y87317D01*
X286743Y87125D01*
X286537Y86857D01*
X286485Y86588D01*
X286537Y86320D01*
X286743Y85975D01*
X285400Y86090D01*
Y87125D01*
G01X280056Y80061D02*
Y76861D01*
G01X277356Y76136D02*
X283556D01*
G01X278367Y100783D02*
Y97583D01*
G01X280777Y115010D02*
X281027Y114850D01*
X281152Y114663D01*
X281194Y114450D01*
X281111Y114183D01*
X280902Y113996D01*
X280652Y113943D01*
X280402Y113970D01*
X280194Y114076D01*
X279777Y114610D01*
X279486Y114850D01*
X279069Y115010D01*
X278694Y115063D01*
Y113943D01*
G01Y112303D02*
X281194D01*
X280694Y112623D01*
G01X278694D02*
Y111983D01*
G01X277861Y110903D02*
Y109303D01*
G01X280777Y108410D02*
X281027Y108250D01*
X281152Y108063D01*
X281194Y107850D01*
X281111Y107583D01*
X280902Y107396D01*
X280652Y107343D01*
X280402Y107370D01*
X280194Y107476D01*
X279777Y108010D01*
X279486Y108250D01*
X279069Y108410D01*
X278694Y108463D01*
Y107343D01*
G01X280777Y106210D02*
X281027Y106050D01*
X281152Y105863D01*
X281194Y105650D01*
X281111Y105383D01*
X280902Y105196D01*
X280652Y105143D01*
X280402Y105170D01*
X280194Y105276D01*
X279777Y105810D01*
X279486Y106050D01*
X279069Y106210D01*
X278694Y106263D01*
Y105143D01*
G01X281934Y94253D02*
X281774Y94003D01*
X281587Y93878D01*
X281374Y93836D01*
X281107Y93919D01*
X280920Y94128D01*
X280867Y94378D01*
X280894Y94628D01*
X281000Y94836D01*
X281534Y95253D01*
X281774Y95544D01*
X281934Y95961D01*
X281987Y96336D01*
X280867D01*
G01X279227Y93836D02*
X279440Y93919D01*
X279600Y94128D01*
X279707Y94378D01*
X279787Y94711D01*
X279814Y95086D01*
X279787Y95461D01*
X279707Y95794D01*
X279600Y96044D01*
X279440Y96253D01*
X279227Y96336D01*
X279014Y96253D01*
X278854Y96044D01*
X278747Y95794D01*
X278667Y95461D01*
X278640Y95086D01*
X278667Y94711D01*
X278747Y94378D01*
X278854Y94128D01*
X279014Y93919D01*
X279227Y93836D01*
G01X276466Y103701D02*
Y106842D01*
G01X287757Y114403D02*
Y120603D01*
G01D02*
X290957D01*
G01Y114403D02*
X287757D01*
G01X276466Y112764D02*
Y115905D01*
G01Y108853D02*
Y110753D01*
G01X277397Y128643D02*
Y122443D01*
G01X281500Y138562D02*
Y135362D01*
G01X288400Y138562D02*
Y135362D01*
G01X282200D02*
Y138562D01*
G01X288400Y135362D02*
X282200D01*
G01X278183Y128668D02*
X281383D01*
G01X278183Y122468D02*
Y128668D01*
G01X281383Y122468D02*
X278183D01*
G01X281383Y128668D02*
Y122468D01*
G01X282200Y138562D02*
X288400D01*
G01X292159Y150850D02*
Y148897D01*
X290206D01*
G01X282300D02*
X280347D01*
Y150850D01*
G01Y158756D02*
Y160709D01*
G01X290206D02*
X292159D01*
Y158756D01*
G01X280347Y160709D02*
X282300D01*
G01X281600Y208600D02*
Y205400D01*
G01Y212600D02*
Y209400D01*
G01X286997Y220119D02*
X290197D01*
G01X286997Y213919D02*
Y220119D01*
G01X290197Y213919D02*
X286997D01*
G01X290197Y220119D02*
Y213919D01*
G01X281600Y216600D02*
Y213400D01*
G01X280900Y227331D02*
Y218669D01*
G01X277100Y235600D02*
Y229400D01*
G01X282898Y225676D02*
X295102D01*
G01X282898Y239324D02*
Y225676D01*
G01X295102Y239324D02*
X282898D01*
G01X287349Y251011D02*
X290549D01*
G01X287349Y244811D02*
Y251011D01*
G01X290549Y244811D02*
X287349D01*
G01X278401Y583178D02*
Y576978D01*
G01X288391Y579298D02*
Y576098D01*
G01X282191Y579298D02*
X288391D01*
G01Y576098D02*
X282191D01*
G01D02*
Y579298D01*
G01X285241Y572422D02*
X279041D01*
G01D02*
Y575622D01*
G01D02*
X285241D01*
G01D02*
Y572422D01*
G01X281526Y571998D02*
Y568798D01*
G01X288391Y571998D02*
Y568798D01*
G01X282191Y571998D02*
X288391D01*
G01Y568798D02*
X282191D01*
G01D02*
Y571998D01*
G01X288391Y582898D02*
Y579698D01*
G01D02*
X282191D01*
G01D02*
Y582898D01*
G01D02*
X288391D01*
G01X281501Y586778D02*
Y583578D01*
G01X288403Y586775D02*
X288399Y583575D01*
G01D02*
X282199Y583581D01*
G01D02*
X282203Y586781D01*
G01D02*
X288403Y586775D01*
G01X283076Y593633D02*
Y597435D01*
G01X282805Y593633D02*
X283076D01*
G01X292239Y596326D02*
X286239D01*
G01D02*
Y608326D01*
G01X283076Y599735D02*
Y605837D01*
G01X286239Y608326D02*
X292239D01*
G01X280757Y675750D02*
X286957D01*
G01D02*
Y672550D01*
G01D02*
X280757D01*
G01D02*
Y675750D01*
G01X282554Y677900D02*
Y684100D01*
G01D02*
X285754D01*
G01D02*
Y677900D01*
G01D02*
X282554D01*
G01X276098Y678501D02*
Y675301D01*
G01X289796Y684100D02*
Y677900D01*
G01D02*
X286596D01*
G01D02*
Y684100D01*
G01D02*
X289796D01*
G01X278455Y702079D02*
Y695879D01*
G01X282075Y687503D02*
X281342D01*
G01D02*
Y689694D01*
G01Y708525D02*
Y711125D01*
G01D02*
X282135D01*
G01X275957Y757650D02*
Y714342D01*
G01D02*
X281298D01*
G01Y757650D02*
X275957D01*
G01X288862Y860722D02*
Y928100D01*
G01X391500Y860722D02*
X288862D01*
G01Y937900D02*
Y951200D01*
G01Y958100D02*
Y968900D01*
G01Y977300D02*
Y1008300D01*
G01Y1014500D02*
Y1059300D01*
G01Y1069100D02*
Y1082600D01*
G01Y1090700D02*
Y1102300D01*
G01Y1109500D02*
Y1124200D01*
G01Y1136500D02*
Y1175700D01*
G01X287088Y1260562D02*
X292429D01*
G01X287044Y1307087D02*
X286251D01*
G01X287044Y1309687D02*
Y1307087D01*
G01X292429Y1303870D02*
X287088D01*
G01X289910Y1322389D02*
X293110D01*
G01X289910Y1316189D02*
Y1322389D01*
G01X293110Y1316189D02*
X289910D01*
G01X282632Y1340312D02*
X285832D01*
G01X282632Y1334112D02*
Y1340312D01*
G01X285832Y1334112D02*
X282632D01*
G01X285832Y1340312D02*
Y1334112D01*
G01X289067Y1344305D02*
Y1341105D01*
G01X282867D02*
Y1344305D01*
G01X289067Y1341105D02*
X282867D01*
G01X281790Y1334112D02*
X278590D01*
G01X281790Y1340312D02*
Y1334112D01*
G01X278590Y1340312D02*
X281790D01*
G01X278590Y1334112D02*
Y1340312D01*
G01X287044Y1330709D02*
Y1328518D01*
G01X286311Y1330709D02*
X287044D01*
G01X282867Y1344305D02*
X289067D01*
G01X289383Y1351000D02*
Y1354100D01*
X290303D01*
X290610Y1353945D01*
X290840Y1353583D01*
X290917Y1353170D01*
X290840Y1352757D01*
X290648Y1352447D01*
X290303Y1352292D01*
X289383D01*
G01X292407Y1354100D02*
Y1351878D01*
X292560Y1351413D01*
X292867Y1351103D01*
X293250Y1351000D01*
X293633Y1351103D01*
X293940Y1351413D01*
X294093Y1351878D01*
Y1354100D01*
G01X295507Y1351620D02*
X295737Y1351258D01*
X296043Y1351052D01*
X296388Y1351000D01*
X296695Y1351052D01*
X297002Y1351310D01*
X297193Y1351620D01*
X297232Y1351930D01*
X297155Y1352292D01*
X296887Y1352550D01*
X296618Y1352653D01*
X296273D01*
G01X296618D02*
X296848Y1352808D01*
X297040Y1353067D01*
X297117Y1353377D01*
X297040Y1353687D01*
X296848Y1353945D01*
X296503Y1354100D01*
X296158Y1354048D01*
X295813Y1353842D01*
G01X299373Y1351000D02*
X299450Y1351672D01*
X299565Y1352240D01*
X299718Y1352757D01*
X299910Y1353325D01*
X300217Y1354100D01*
X298683D01*
G01X289284Y1346370D02*
Y1349470D01*
X290204D01*
X290511Y1349315D01*
X290741Y1348953D01*
X290818Y1348540D01*
X290741Y1348127D01*
X290549Y1347817D01*
X290204Y1347662D01*
X289284D01*
G01X292384Y1349470D02*
Y1346370D01*
X293918D01*
G01X296711D02*
Y1349470D01*
X295293Y1347248D01*
X297209D01*
G01X299811Y1346370D02*
Y1349470D01*
X298393Y1347248D01*
X300309D01*
G01X286658Y1389222D02*
X291595Y1384285D01*
G01X286658Y1411057D02*
Y1389222D01*
G01X296344Y1411057D02*
X286658D01*
G01X276012Y1450259D02*
Y1430259D01*
G01D02*
Y1450259D01*
G01X291012Y1430259D02*
X276012D01*
G01X283055Y1437302D02*
X282680Y1437675D01*
X282055Y1437955D01*
X281180Y1438142D01*
X280430Y1437955D01*
X279930Y1437582D01*
X279555Y1436928D01*
Y1434408D01*
X287055D01*
Y1437488D01*
X286555Y1438142D01*
X285805Y1438515D01*
X284930Y1438702D01*
X284055Y1438515D01*
X283305Y1437955D01*
X283055Y1437302D01*
Y1434408D01*
G01X287055Y1444055D02*
X279555D01*
X281055Y1442935D01*
G01X287055D02*
Y1445175D01*
G01X276012Y1450259D02*
X291012D01*
G01X277899Y1518320D02*
Y1524520D01*
X281099D01*
Y1518320D01*
X277899D01*
G01X279137Y1536503D02*
Y1539911D01*
G01X296853Y1536503D02*
X279137D01*
G01Y1550811D02*
Y1554219D01*
G01X278978Y1558758D02*
Y1555658D01*
X280512D01*
G01X282117Y1556950D02*
X282385Y1557311D01*
X282615Y1557518D01*
X282922Y1557621D01*
X283190Y1557518D01*
X283382Y1557311D01*
X283535Y1557001D01*
X283573Y1556640D01*
X283535Y1556330D01*
X283382Y1556020D01*
X283152Y1555761D01*
X282883Y1555658D01*
X282577Y1555761D01*
X282308Y1556071D01*
X282155Y1556536D01*
X282117Y1557053D01*
X282193Y1557725D01*
X282308Y1558086D01*
X282500Y1558448D01*
X282768Y1558706D01*
X283037Y1558758D01*
X283305Y1558655D01*
X283497Y1558396D01*
G01X279137Y1554219D02*
X296853D01*
G01X289747Y1588222D02*
X295747D01*
Y1576222D01*
X289747D01*
Y1588222D01*
G01X285721Y1571178D02*
X285566Y1570948D01*
X285463Y1570680D01*
Y1570373D01*
X285618Y1570028D01*
X285876Y1569760D01*
X286186Y1569568D01*
X286703Y1569415D01*
X287168Y1569377D01*
X287633Y1569453D01*
X287943Y1569568D01*
X288253Y1569798D01*
X288460Y1570067D01*
X288563Y1570335D01*
Y1570603D01*
X288460Y1570872D01*
X288305Y1571102D01*
X288098Y1571293D01*
G01X288563Y1573358D02*
X287891Y1573435D01*
X287323Y1573550D01*
X286806Y1573703D01*
X286238Y1573895D01*
X285463Y1574202D01*
Y1572668D01*
G01Y1576535D02*
X285566Y1576228D01*
X285825Y1575998D01*
X286135Y1575845D01*
X286548Y1575730D01*
X287013Y1575692D01*
X287478Y1575730D01*
X287891Y1575845D01*
X288201Y1575998D01*
X288460Y1576228D01*
X288563Y1576535D01*
X288460Y1576842D01*
X288201Y1577072D01*
X287891Y1577225D01*
X287478Y1577340D01*
X287013Y1577378D01*
X286548Y1577340D01*
X286135Y1577225D01*
X285825Y1577072D01*
X285566Y1576842D01*
X285463Y1576535D01*
G01Y1579635D02*
X285566Y1579328D01*
X285825Y1579098D01*
X286135Y1578945D01*
X286548Y1578830D01*
X287013Y1578792D01*
X287478Y1578830D01*
X287891Y1578945D01*
X288201Y1579098D01*
X288460Y1579328D01*
X288563Y1579635D01*
X288460Y1579942D01*
X288201Y1580172D01*
X287891Y1580325D01*
X287478Y1580440D01*
X287013Y1580478D01*
X286548Y1580440D01*
X286135Y1580325D01*
X285825Y1580172D01*
X285566Y1579942D01*
X285463Y1579635D01*
G01X288563Y1583195D02*
X285463D01*
X287685Y1581777D01*
Y1583693D01*
G01X284385Y1569363D02*
X283185D01*
G01X284385D02*
X284379Y1586346D01*
G01X283785Y1569363D02*
X283789Y1586338D01*
G01X283185Y1569363D02*
X283188Y1586303D01*
G01X281470Y1589098D02*
X279230D01*
G01X280443Y1587473D02*
Y1590723D01*
G01X284335Y1586296D02*
X282826Y1586292D01*
G01X278072Y1625425D02*
X278149Y1626097D01*
X278264Y1626665D01*
X278417Y1627182D01*
X278609Y1627750D01*
X278916Y1628525D01*
X277382D01*
G01X286023Y1625358D02*
X286291Y1625410D01*
X286598Y1625565D01*
X286790Y1625823D01*
X286866Y1626185D01*
X286790Y1626546D01*
X286560Y1626856D01*
X286215Y1627011D01*
X285831D01*
X285601Y1627115D01*
X285410Y1627373D01*
X285333Y1627735D01*
X285448Y1628096D01*
X285716Y1628355D01*
X286023Y1628458D01*
X286330Y1628355D01*
X286598Y1628096D01*
X286713Y1627735D01*
X286636Y1627373D01*
X286445Y1627115D01*
X286215Y1627011D01*
X285831D01*
X285486Y1626856D01*
X285256Y1626546D01*
X285180Y1626185D01*
X285256Y1625823D01*
X285448Y1625565D01*
X285755Y1625410D01*
X286023Y1625358D01*
G01X276900Y1617677D02*
X284000D01*
G01X288800D02*
X296100D01*
G01X300854Y60053D02*
X303280D01*
G01X333953Y54005D02*
X304394D01*
G01D02*
Y65501D01*
G01X295168Y56836D02*
Y71636D01*
G01X300047Y77273D02*
Y74073D01*
G01D02*
X293847D01*
G01D02*
Y77273D01*
G01X302766Y68728D02*
Y65528D01*
G01X296566Y68728D02*
X302766D01*
G01X296566Y65528D02*
Y68728D01*
G01X302766Y65528D02*
X296566D01*
G01X303666Y72707D02*
X306866D01*
G01X303666Y66507D02*
Y72707D01*
G01X306866Y66507D02*
X303666D01*
G01X296566Y69528D02*
Y72728D01*
G01X302766Y69528D02*
X296566D01*
G01X302766Y72728D02*
Y69528D01*
G01X296566Y72728D02*
X302766D01*
G01X304394Y65501D02*
X333953D01*
G01X306757Y90167D02*
X300557D01*
G01D02*
Y93367D01*
G01X293847Y77273D02*
X300047D01*
G01X300527Y84383D02*
X294327D01*
G01D02*
Y87583D01*
G01D02*
X300527D01*
G01D02*
Y84383D01*
G01Y80883D02*
X294327D01*
G01D02*
Y84083D01*
G01D02*
X300527D01*
G01D02*
Y80883D01*
G01X300557Y93367D02*
X306757D01*
G01X302915Y100399D02*
Y94199D01*
G01D02*
X299715D01*
G01D02*
Y100399D01*
G01D02*
X302915D01*
G01X306915Y94199D02*
X303715D01*
G01D02*
Y100399D01*
G01D02*
X306915D01*
G01X306753Y107366D02*
Y104940D01*
G01X290957Y120603D02*
Y114403D01*
G01X302816Y127412D02*
Y108194D01*
G01D02*
X310690D01*
G01X306274Y131937D02*
Y129697D01*
G01X307899Y130910D02*
X304649D01*
G01X310690Y127412D02*
X302816D01*
G01X294953Y150103D02*
Y153303D01*
G01X301153Y150103D02*
X294953D01*
G01X301153Y153303D02*
Y150103D01*
G01X294953Y154603D02*
Y157803D01*
G01X301153Y154603D02*
X294953D01*
G01X301153Y157803D02*
Y154603D01*
G01X294953Y157803D02*
X301153D01*
G01X294953Y153303D02*
X301153D01*
G01X293400Y163450D02*
Y161228D01*
X293553Y160763D01*
X293860Y160453D01*
X294243Y160350D01*
X294626Y160453D01*
X294933Y160763D01*
X295086Y161228D01*
Y163450D01*
G01X296615Y162933D02*
X296845Y163243D01*
X297113Y163398D01*
X297420Y163450D01*
X297803Y163347D01*
X298071Y163088D01*
X298148Y162778D01*
X298110Y162468D01*
X297956Y162210D01*
X297190Y161693D01*
X296845Y161332D01*
X296615Y160815D01*
X296538Y160350D01*
X298148D01*
G01X299715Y161642D02*
X299983Y162003D01*
X300213Y162210D01*
X300520Y162313D01*
X300788Y162210D01*
X300980Y162003D01*
X301133Y161693D01*
X301171Y161332D01*
X301133Y161022D01*
X300980Y160712D01*
X300750Y160453D01*
X300481Y160350D01*
X300175Y160453D01*
X299906Y160763D01*
X299753Y161228D01*
X299715Y161745D01*
X299791Y162417D01*
X299906Y162778D01*
X300098Y163140D01*
X300366Y163398D01*
X300635Y163450D01*
X300903Y163347D01*
X301095Y163088D01*
G01X302700Y160970D02*
X302930Y160608D01*
X303236Y160402D01*
X303581Y160350D01*
X303888Y160402D01*
X304195Y160660D01*
X304386Y160970D01*
X304425Y161280D01*
X304348Y161642D01*
X304080Y161900D01*
X303811Y162003D01*
X303466D01*
G01X303811D02*
X304041Y162158D01*
X304233Y162417D01*
X304310Y162727D01*
X304233Y163037D01*
X304041Y163295D01*
X303696Y163450D01*
X303351Y163398D01*
X303006Y163192D01*
G01X291400Y224100D02*
X294600D01*
G01X291400Y217900D02*
Y224100D01*
G01X294600Y217900D02*
X291400D01*
G01X294600Y224100D02*
Y217900D01*
G01X298337Y229094D02*
X300559D01*
X301024Y229247D01*
X301334Y229554D01*
X301437Y229937D01*
X301334Y230320D01*
X301024Y230627D01*
X300559Y230780D01*
X298337D01*
G01X300817Y232194D02*
X301179Y232424D01*
X301385Y232730D01*
X301437Y233075D01*
X301385Y233382D01*
X301127Y233689D01*
X300817Y233880D01*
X300507Y233919D01*
X300145Y233842D01*
X299887Y233574D01*
X299784Y233305D01*
Y232960D01*
G01Y233305D02*
X299629Y233535D01*
X299370Y233727D01*
X299060Y233804D01*
X298750Y233727D01*
X298492Y233535D01*
X298337Y233190D01*
X298389Y232845D01*
X298595Y232500D01*
G01X300972Y235294D02*
X301230Y235524D01*
X301385Y235792D01*
X301437Y236137D01*
X301334Y236482D01*
X301127Y236750D01*
X300765Y236942D01*
X300352Y236980D01*
X299939Y236904D01*
X299680Y236712D01*
X299474Y236444D01*
X299422Y236175D01*
X299474Y235907D01*
X299680Y235562D01*
X298337Y235677D01*
Y236712D01*
G01X295102Y229898D02*
X292500Y232500D01*
G01X295102Y225676D02*
Y229898D01*
G01Y235102D02*
Y239324D01*
G01X292500Y232500D02*
X295102Y235102D01*
G01X304100Y248900D02*
X300900D01*
G01X304100Y255100D02*
Y248900D01*
G01X300900D02*
Y255100D01*
G01X291349Y251011D02*
X294549D01*
G01X291349Y244811D02*
Y251011D01*
G01X294549Y244811D02*
X291349D01*
G01X294549Y251011D02*
Y244811D01*
G01X290549Y251011D02*
Y244811D01*
G01X300900Y255100D02*
X304100D01*
G01X294305Y587554D02*
Y581354D01*
G01D02*
X291105D01*
G01D02*
Y587554D01*
G01X296215Y581354D02*
Y587554D01*
G01X299415D02*
Y581354D01*
G01D02*
X296215D01*
G01X291105Y587554D02*
X294305D01*
G01X296215D02*
X299415D01*
G01X299139Y608326D02*
Y596326D01*
G01D02*
X293139D01*
G01D02*
Y608326D01*
G01X292239D02*
Y596326D01*
G01X306039D02*
X300039D01*
G01D02*
Y608326D01*
G01X293139D02*
X299139D01*
G01X300039D02*
X306039D01*
G01X293338Y671446D02*
Y674546D01*
X294258D01*
X294565Y674391D01*
X294795Y674029D01*
X294872Y673616D01*
X294795Y673203D01*
X294603Y672893D01*
X294258Y672738D01*
X293338D01*
G01X296362Y674546D02*
Y672324D01*
X296515Y671859D01*
X296822Y671549D01*
X297205Y671446D01*
X297588Y671549D01*
X297895Y671859D01*
X298048Y672324D01*
Y674546D01*
G01X299577Y674029D02*
X299807Y674339D01*
X300075Y674494D01*
X300382Y674546D01*
X300765Y674443D01*
X301033Y674184D01*
X301110Y673874D01*
X301072Y673564D01*
X300918Y673306D01*
X300152Y672789D01*
X299807Y672428D01*
X299577Y671911D01*
X299500Y671446D01*
X301110D01*
G01X302753Y671808D02*
X303022Y671549D01*
X303328Y671446D01*
X303635Y671549D01*
X303903Y671859D01*
X304095Y672324D01*
X304172Y672789D01*
Y673358D01*
X304095Y673823D01*
X303903Y674236D01*
X303673Y674443D01*
X303405Y674546D01*
X303098Y674443D01*
X302868Y674236D01*
X302715Y673926D01*
X302638Y673513D01*
X302715Y673151D01*
X302907Y672789D01*
X303137Y672583D01*
X303405Y672531D01*
X303712Y672634D01*
X303942Y672893D01*
X304172Y673358D01*
G01X303391Y683290D02*
Y677090D01*
G01D02*
X300191D01*
G01D02*
Y683290D01*
G01D02*
X303391D01*
G01X307285Y685721D02*
X304085D01*
G01D02*
Y687200D01*
G01X293221Y680396D02*
X299421D01*
G01D02*
Y677196D01*
G01D02*
X293221D01*
G01D02*
Y680396D01*
G01X304085Y691921D02*
X307285D01*
G01X304085Y690100D02*
Y691921D01*
G01Y696221D02*
Y702421D01*
G01X307285Y696221D02*
X304085D01*
G01X301028Y701914D02*
Y700216D01*
G01Y689357D02*
Y687503D01*
G01D02*
X300020D01*
G01X304085Y702421D02*
X307285D01*
G01X302628Y712742D02*
X308828D01*
G01Y709542D02*
X302628D01*
G01D02*
Y712742D01*
G01X307262Y703042D02*
X304062D01*
G01D02*
Y709242D01*
G01D02*
X307262D01*
G01X300235Y711125D02*
X301028D01*
G01D02*
Y708525D01*
G01X305485Y714342D02*
X300144D01*
G01Y757650D02*
X305485D01*
G01X298929Y870789D02*
Y888900D01*
G01X404800Y870789D02*
X298929D01*
G01Y898100D02*
Y912200D01*
G01Y920100D02*
Y931900D01*
G01Y939100D02*
Y950500D01*
G01Y958200D02*
Y968900D01*
G01Y977300D02*
Y1011700D01*
G01Y1016800D02*
Y1064200D01*
G01Y1072000D02*
Y1082500D01*
G01Y1090600D02*
Y1102100D01*
G01Y1109500D02*
Y1121400D01*
G01Y1128800D02*
Y1141100D01*
G01Y1151000D02*
Y1167639D01*
G01X296100Y1177706D02*
X387600D01*
G01X298929Y1167639D02*
X382400D01*
G01X295797Y1260477D02*
Y1303785D01*
G01X301138Y1260477D02*
X295797D01*
G01X292429Y1260562D02*
Y1303870D01*
G01X298654Y1308642D02*
Y1305442D01*
G01X292454Y1308642D02*
X298654D01*
G01X292454Y1305442D02*
Y1308642D01*
G01X298654Y1305442D02*
X292454D01*
G01X297220Y1308942D02*
X294020D01*
G01X297220Y1315142D02*
Y1308942D01*
G01X294020D02*
Y1315142D01*
G01X300254Y1307059D02*
Y1309659D01*
G01X301047Y1307059D02*
X300254D01*
G01X295797Y1303785D02*
X301138D01*
G01X297197Y1326263D02*
X293997D01*
G01D02*
Y1332463D01*
G01X297197Y1327600D02*
Y1326263D01*
G01X293997Y1321963D02*
X297197D01*
G01X293997Y1315763D02*
Y1321963D01*
G01X297197Y1315763D02*
X293997D01*
G01X297197Y1321963D02*
Y1315763D01*
G01X293110Y1322389D02*
Y1316189D01*
G01X294020Y1315142D02*
X297220D01*
G01X300254Y1316270D02*
Y1317968D01*
G01X297197Y1332463D02*
Y1331000D01*
G01X293997Y1332463D02*
X297197D01*
G01X301091Y1334894D02*
X297891D01*
G01X301091Y1341094D02*
Y1334894D01*
G01X297891Y1341094D02*
X301091D01*
G01X297891Y1334894D02*
Y1341094D01*
G01X290713Y1334531D02*
Y1337731D01*
G01X296913Y1334531D02*
X290713D01*
G01X296913Y1337731D02*
Y1334531D01*
G01X290713Y1337731D02*
X296913D01*
G01X301861Y1337788D02*
Y1340988D01*
G01X308061Y1337788D02*
X301861D01*
G01Y1340988D02*
X308061D01*
G01X300254Y1330681D02*
X301262D01*
G01X300254Y1328827D02*
Y1330681D01*
G01X293383Y1375500D02*
Y1378600D01*
X294303D01*
X294610Y1378445D01*
X294840Y1378083D01*
X294917Y1377670D01*
X294840Y1377257D01*
X294648Y1376947D01*
X294303Y1376792D01*
X293383D01*
G01X298093Y1378342D02*
X297863Y1378497D01*
X297595Y1378600D01*
X297288D01*
X296943Y1378445D01*
X296675Y1378187D01*
X296483Y1377877D01*
X296330Y1377360D01*
X296292Y1376895D01*
X296368Y1376430D01*
X296483Y1376120D01*
X296713Y1375810D01*
X296982Y1375603D01*
X297250Y1375500D01*
X297518D01*
X297787Y1375603D01*
X298017Y1375758D01*
X298208Y1375965D01*
G01X299507Y1376120D02*
X299737Y1375758D01*
X300043Y1375552D01*
X300388Y1375500D01*
X300695Y1375552D01*
X301002Y1375810D01*
X301193Y1376120D01*
X301232Y1376430D01*
X301155Y1376792D01*
X300887Y1377050D01*
X300618Y1377153D01*
X300273D01*
G01X300618D02*
X300848Y1377308D01*
X301040Y1377567D01*
X301117Y1377877D01*
X301040Y1378187D01*
X300848Y1378445D01*
X300503Y1378600D01*
X300158Y1378548D01*
X299813Y1378342D01*
G01X302798Y1375862D02*
X303067Y1375603D01*
X303373Y1375500D01*
X303680Y1375603D01*
X303948Y1375913D01*
X304140Y1376378D01*
X304217Y1376843D01*
Y1377412D01*
X304140Y1377877D01*
X303948Y1378290D01*
X303718Y1378497D01*
X303450Y1378600D01*
X303143Y1378497D01*
X302913Y1378290D01*
X302760Y1377980D01*
X302683Y1377567D01*
X302760Y1377205D01*
X302952Y1376843D01*
X303182Y1376637D01*
X303450Y1376585D01*
X303757Y1376688D01*
X303987Y1376947D01*
X304217Y1377412D01*
G01X305707Y1376120D02*
X305937Y1375758D01*
X306243Y1375552D01*
X306588Y1375500D01*
X306895Y1375552D01*
X307202Y1375810D01*
X307393Y1376120D01*
X307432Y1376430D01*
X307355Y1376792D01*
X307087Y1377050D01*
X306818Y1377153D01*
X306473D01*
G01X306818D02*
X307048Y1377308D01*
X307240Y1377567D01*
X307317Y1377877D01*
X307240Y1378187D01*
X307048Y1378445D01*
X306703Y1378600D01*
X306358Y1378548D01*
X306013Y1378342D01*
G01X308493Y1384285D02*
X303744D01*
G01X291595D02*
X296344D01*
G01X303744Y1411057D02*
X313430D01*
G01X291012Y1450259D02*
Y1430259D01*
G01D02*
Y1450259D01*
G01X306012Y1430259D02*
X291012D01*
G01X298055Y1437302D02*
X297680Y1437675D01*
X297055Y1437955D01*
X296180Y1438142D01*
X295430Y1437955D01*
X294930Y1437582D01*
X294555Y1436928D01*
Y1434408D01*
X302055D01*
Y1437488D01*
X301555Y1438142D01*
X300805Y1438515D01*
X299930Y1438702D01*
X299055Y1438515D01*
X298305Y1437955D01*
X298055Y1437302D01*
Y1434408D01*
G01X294555Y1444055D02*
X294805Y1443308D01*
X295430Y1442748D01*
X296180Y1442375D01*
X297180Y1442095D01*
X298305Y1442002D01*
X299430Y1442095D01*
X300430Y1442375D01*
X301180Y1442748D01*
X301805Y1443308D01*
X302055Y1444055D01*
X301805Y1444802D01*
X301180Y1445362D01*
X300430Y1445735D01*
X299430Y1446015D01*
X298305Y1446108D01*
X297180Y1446015D01*
X296180Y1445735D01*
X295430Y1445362D01*
X294805Y1444802D01*
X294555Y1444055D01*
G01X291012Y1450259D02*
X306012D01*
G01X296853Y1539911D02*
Y1536503D01*
G01Y1554219D02*
Y1550811D01*
G01X296938Y1588384D02*
X302938D01*
Y1576384D01*
X296938D01*
Y1588384D01*
G01X304330Y1617677D02*
Y1629500D01*
G01X301000Y1617677D02*
X304330D01*
G01X292519Y1661000D02*
Y1629488D01*
G01X304959Y1655284D02*
X304649Y1655514D01*
X304494Y1655782D01*
X304442Y1656089D01*
X304545Y1656472D01*
X304804Y1656740D01*
X305114Y1656817D01*
X305424Y1656779D01*
X305682Y1656625D01*
X306199Y1655859D01*
X306560Y1655514D01*
X307077Y1655284D01*
X307542Y1655207D01*
Y1656817D01*
G01X299668Y1656012D02*
X296568D01*
X297188Y1655552D01*
G01X299668D02*
Y1656472D01*
G01X371260Y1646023D02*
X294500D01*
G01X304330Y1642000D02*
Y1667990D01*
G01X292914Y1661000D02*
Y1657834D01*
G01D02*
X359449D01*
G01X292914Y1740118D02*
X359449D01*
G01X304935Y1736412D02*
X305835Y1737312D01*
G01X299935Y1736412D02*
X304935D01*
G01X299935Y1739812D02*
Y1736412D01*
G01X301935Y1737812D02*
X299935Y1739812D01*
G01X297935Y1737812D02*
X301935D01*
G01X299935Y1739812D02*
X297935Y1737812D01*
G01X319772Y79D02*
Y43779D01*
G01D02*
X308622D01*
G01X306866Y72707D02*
Y66507D01*
G01X321657Y90203D02*
X315457D01*
G01D02*
Y93403D01*
G01X306757Y93367D02*
Y90167D01*
G01X319415Y85567D02*
X305439D01*
G01D02*
Y77379D01*
G01D02*
X319415D01*
G01D02*
Y85567D01*
G01X315457Y93403D02*
X321657D01*
G01X321699Y94252D02*
X315499D01*
G01D02*
Y97452D01*
G01D02*
X321699D01*
G01X321703Y98237D02*
X315503D01*
G01D02*
Y101437D01*
G01D02*
X321703D01*
G01X306915Y100399D02*
Y94199D01*
G01X318060Y110488D02*
X314960D01*
Y111408D01*
X315115Y111715D01*
X315477Y111945D01*
X315890Y112022D01*
X316303Y111945D01*
X316613Y111753D01*
X316768Y111408D01*
Y110488D01*
G01X318060Y113512D02*
X314960D01*
Y114278D01*
X315115Y114585D01*
X315322Y114815D01*
X315632Y115007D01*
X315993Y115160D01*
X316510Y115198D01*
X317027Y115160D01*
X317388Y115007D01*
X317698Y114815D01*
X317905Y114585D01*
X318060Y114278D01*
Y113512D01*
G01Y117455D02*
X314960D01*
X315580Y116995D01*
G01X318060D02*
Y117915D01*
G01X314960Y120555D02*
X315063Y120248D01*
X315322Y120018D01*
X315632Y119865D01*
X316045Y119750D01*
X316510Y119712D01*
X316975Y119750D01*
X317388Y119865D01*
X317698Y120018D01*
X317957Y120248D01*
X318060Y120555D01*
X317957Y120862D01*
X317698Y121092D01*
X317388Y121245D01*
X316975Y121360D01*
X316510Y121398D01*
X316045Y121360D01*
X315632Y121245D01*
X315322Y121092D01*
X315063Y120862D01*
X314960Y120555D01*
G01X318060Y123578D02*
X317388Y123655D01*
X316820Y123770D01*
X316303Y123923D01*
X315735Y124115D01*
X314960Y124422D01*
Y122888D01*
G01X310690Y108194D02*
Y127412D01*
G01X306953Y120053D02*
Y121153D01*
G01Y117053D02*
X305453Y120053D01*
G01D02*
X308453D01*
G01D02*
X306953Y117053D01*
G01D02*
Y116053D01*
G01X308453Y117053D02*
X305453D01*
G01X308739Y232951D02*
X311939D01*
G01X308739Y226751D02*
Y232951D01*
G01X311939Y226751D02*
X308739D01*
G01X311939Y232951D02*
Y226751D01*
G01X315100Y242600D02*
Y239400D01*
G01X308900D02*
Y242600D01*
G01X315100Y239400D02*
X308900D01*
G01X318939Y229451D02*
Y226251D01*
G01X312739Y229451D02*
X318939D01*
G01X312739Y226251D02*
Y229451D01*
G01X318939Y226251D02*
X312739D01*
G01Y233451D02*
X318939D01*
G01D02*
Y230251D01*
G01X312739D02*
Y233451D01*
G01X318939Y230251D02*
X312739D01*
G01X308900Y242600D02*
X315100D01*
G01X319406Y258928D02*
Y245072D01*
G01X307594D02*
Y258928D01*
G01X319406Y245072D02*
X307594D01*
G01X314400Y261400D02*
Y264600D01*
G01X320600Y261400D02*
X314400D01*
G01Y264600D02*
X320600D01*
G01X313600D02*
Y261400D01*
G01X307400Y264600D02*
X313600D01*
G01X307400Y261400D02*
Y264600D01*
G01X313600Y261400D02*
X307400D01*
G01X316202Y269491D02*
X313002D01*
G01X316202Y275691D02*
Y269491D01*
G01X313002D02*
Y275691D01*
G01X307594Y258928D02*
X319406D01*
G01X313002Y275691D02*
X316202D01*
G01X315642Y556532D02*
X317864D01*
X318329Y556685D01*
X318639Y556992D01*
X318742Y557375D01*
X318639Y557758D01*
X318329Y558065D01*
X317864Y558218D01*
X315642D01*
G01X318742Y560935D02*
X315642D01*
X317864Y559517D01*
Y561433D01*
G01X315642Y563575D02*
X315745Y563268D01*
X316004Y563038D01*
X316314Y562885D01*
X316727Y562770D01*
X317192Y562732D01*
X317657Y562770D01*
X318070Y562885D01*
X318380Y563038D01*
X318639Y563268D01*
X318742Y563575D01*
X318639Y563882D01*
X318380Y564112D01*
X318070Y564265D01*
X317657Y564380D01*
X317192Y564418D01*
X316727Y564380D01*
X316314Y564265D01*
X316004Y564112D01*
X315745Y563882D01*
X315642Y563575D01*
G01X312939Y608326D02*
Y596326D01*
G01D02*
X306939D01*
G01D02*
Y608326D01*
G01X306039D02*
Y596326D01*
G01X314961Y596361D02*
Y608361D01*
G01X320961Y596361D02*
X314961D01*
G01X306939Y608326D02*
X312939D01*
G01X314961Y608361D02*
X320961D01*
G01X317952Y640573D02*
Y643673D01*
X318872D01*
X319179Y643518D01*
X319409Y643156D01*
X319486Y642743D01*
X319409Y642330D01*
X319217Y642020D01*
X318872Y641865D01*
X317952D01*
G01X322662Y643415D02*
X322432Y643570D01*
X322164Y643673D01*
X321857D01*
X321512Y643518D01*
X321244Y643260D01*
X321052Y642950D01*
X320899Y642433D01*
X320861Y641968D01*
X320937Y641503D01*
X321052Y641193D01*
X321282Y640883D01*
X321551Y640676D01*
X321819Y640573D01*
X322087D01*
X322356Y640676D01*
X322586Y640831D01*
X322777Y641038D01*
G01X324191Y643156D02*
X324421Y643466D01*
X324689Y643621D01*
X324996Y643673D01*
X325379Y643570D01*
X325647Y643311D01*
X325724Y643001D01*
X325686Y642691D01*
X325532Y642433D01*
X324766Y641916D01*
X324421Y641555D01*
X324191Y641038D01*
X324114Y640573D01*
X325724D01*
G01X327942D02*
X328019Y641245D01*
X328134Y641813D01*
X328287Y642330D01*
X328479Y642898D01*
X328786Y643673D01*
X327252D01*
G01X330391Y643156D02*
X330621Y643466D01*
X330889Y643621D01*
X331196Y643673D01*
X331579Y643570D01*
X331847Y643311D01*
X331924Y643001D01*
X331886Y642691D01*
X331732Y642433D01*
X330966Y641916D01*
X330621Y641555D01*
X330391Y641038D01*
X330314Y640573D01*
X331924D01*
G01X340117Y658315D02*
G02I-13386J0D01*
G01D02*
X313345D01*
G01X307285Y691921D02*
Y685721D01*
G01X312543Y696125D02*
X318743D01*
G01D02*
Y692925D01*
G01D02*
X312543D01*
G01D02*
Y696125D01*
G01X315324Y698050D02*
Y704250D01*
G01X318524D02*
Y698050D01*
G01D02*
X315324D01*
G01X307285Y702421D02*
Y696221D01*
G01X322566Y698050D02*
X319366D01*
G01D02*
Y704250D01*
G01X315324D02*
X318524D01*
G01X308055Y715739D02*
Y721939D01*
G01X311255D02*
Y715739D01*
G01D02*
X308055D01*
G01X308828Y712742D02*
Y709542D01*
G01X307262Y709242D02*
Y703042D01*
G01X319366Y704250D02*
X322566D01*
G01X314845Y707653D02*
X314112D01*
G01D02*
Y709844D01*
G01X305485Y757650D02*
Y714342D01*
G01X308055Y721939D02*
X311255D01*
G01X314112Y728675D02*
Y731275D01*
G01D02*
X314905D01*
G01X308727Y734492D02*
X314068D01*
G01X308727Y777800D02*
Y734492D01*
G01X314068Y777800D02*
X308727D01*
G01X319984Y1260477D02*
X325325D01*
G01X319940Y1307059D02*
X319147D01*
G01X319940Y1309659D02*
Y1307059D01*
G01X325325Y1303785D02*
X319984D01*
G01X315528Y1340284D02*
X318728D01*
G01X315528Y1334084D02*
Y1340284D01*
G01X318728Y1334084D02*
X315528D01*
G01X318728Y1340284D02*
Y1334084D01*
G01X308061Y1340988D02*
Y1337788D01*
G01X314686Y1334084D02*
X311486D01*
G01X314686Y1340284D02*
Y1334084D01*
G01X311486Y1340284D02*
X314686D01*
G01X311486Y1334084D02*
Y1340284D01*
G01X319940Y1330681D02*
Y1328490D01*
G01X319207Y1330681D02*
X319940D01*
G01X307883Y1351000D02*
Y1354100D01*
X308803D01*
X309110Y1353945D01*
X309340Y1353583D01*
X309417Y1353170D01*
X309340Y1352757D01*
X309148Y1352447D01*
X308803Y1352292D01*
X307883D01*
G01X310907Y1354100D02*
Y1351878D01*
X311060Y1351413D01*
X311367Y1351103D01*
X311750Y1351000D01*
X312133Y1351103D01*
X312440Y1351413D01*
X312593Y1351878D01*
Y1354100D01*
G01X314007Y1351465D02*
X314237Y1351207D01*
X314505Y1351052D01*
X314850Y1351000D01*
X315195Y1351103D01*
X315463Y1351310D01*
X315655Y1351672D01*
X315693Y1352085D01*
X315617Y1352498D01*
X315425Y1352757D01*
X315157Y1352963D01*
X314888Y1353015D01*
X314620Y1352963D01*
X314275Y1352757D01*
X314390Y1354100D01*
X315425D01*
G01X307680Y1346785D02*
Y1349885D01*
X308600D01*
X308907Y1349730D01*
X309137Y1349368D01*
X309214Y1348955D01*
X309137Y1348542D01*
X308945Y1348232D01*
X308600Y1348077D01*
X307680D01*
G01X310780Y1349885D02*
Y1346785D01*
X312314D01*
G01X315107D02*
Y1349885D01*
X313689Y1347663D01*
X315605D01*
G01X317747Y1346785D02*
Y1349885D01*
X317287Y1349265D01*
G01Y1346785D02*
X318207D01*
G01X313430Y1389222D02*
X308493Y1384285D01*
G01X315608Y1378831D02*
X320545Y1373894D01*
G01X315608Y1400666D02*
Y1378831D01*
G01X313430Y1411057D02*
Y1389222D01*
G01X325294Y1400666D02*
X315608D01*
G01X306012Y1416759D02*
Y1430259D01*
G01Y1450259D02*
Y1430259D01*
G01X305495Y1507451D02*
Y1524200D01*
G01X311700Y1507451D02*
X305495D01*
G01Y1528500D02*
Y1542491D01*
G01D02*
X311900D01*
G01X314698Y1560717D02*
Y1568217D01*
X316938D01*
X317685Y1567842D01*
X318245Y1566967D01*
X318432Y1565967D01*
X318245Y1564967D01*
X317778Y1564217D01*
X316938Y1563842D01*
X314698D01*
G01X324065Y1568217D02*
X323318Y1567967D01*
X322758Y1567342D01*
X322385Y1566592D01*
X322105Y1565592D01*
X322012Y1564467D01*
X322105Y1563342D01*
X322385Y1562342D01*
X322758Y1561592D01*
X323318Y1560967D01*
X324065Y1560717D01*
X324812Y1560967D01*
X325372Y1561592D01*
X325745Y1562342D01*
X326025Y1563342D01*
X326118Y1564467D01*
X326025Y1565592D01*
X325745Y1566592D01*
X325372Y1567342D01*
X324812Y1567967D01*
X324065Y1568217D01*
G01X338878Y1559342D02*
X339252Y1560967D01*
G01X352198Y1560717D02*
Y1568217D01*
X354438D01*
X355185Y1567842D01*
X355745Y1566967D01*
X355932Y1565967D01*
X355745Y1564967D01*
X355278Y1564217D01*
X354438Y1563842D01*
X352198D01*
G01X361565Y1560717D02*
Y1568217D01*
X360445Y1566717D01*
G01Y1560717D02*
X362685D01*
G01X320278Y1556314D02*
Y1554092D01*
X320431Y1553627D01*
X320738Y1553317D01*
X321121Y1553214D01*
X321504Y1553317D01*
X321811Y1553627D01*
X321964Y1554092D01*
Y1556314D01*
G01X323493Y1554506D02*
X323761Y1554867D01*
X323991Y1555074D01*
X324298Y1555177D01*
X324566Y1555074D01*
X324758Y1554867D01*
X324911Y1554557D01*
X324949Y1554196D01*
X324911Y1553886D01*
X324758Y1553576D01*
X324528Y1553317D01*
X324259Y1553214D01*
X323953Y1553317D01*
X323684Y1553627D01*
X323531Y1554092D01*
X323493Y1554609D01*
X323569Y1555281D01*
X323684Y1555642D01*
X323876Y1556004D01*
X324144Y1556262D01*
X324413Y1556314D01*
X324681Y1556211D01*
X324873Y1555952D01*
G01X327321Y1556314D02*
X327014Y1556211D01*
X326784Y1555952D01*
X326631Y1555642D01*
X326516Y1555229D01*
X326478Y1554764D01*
X326516Y1554299D01*
X326631Y1553886D01*
X326784Y1553576D01*
X327014Y1553317D01*
X327321Y1553214D01*
X327628Y1553317D01*
X327858Y1553576D01*
X328011Y1553886D01*
X328126Y1554299D01*
X328164Y1554764D01*
X328126Y1555229D01*
X328011Y1555642D01*
X327858Y1555952D01*
X327628Y1556211D01*
X327321Y1556314D01*
G01X330421Y1553214D02*
Y1556314D01*
X329961Y1555694D01*
G01Y1553214D02*
X330881D01*
G01X332678Y1553679D02*
X332908Y1553421D01*
X333176Y1553266D01*
X333521Y1553214D01*
X333866Y1553317D01*
X334134Y1553524D01*
X334326Y1553886D01*
X334364Y1554299D01*
X334288Y1554712D01*
X334096Y1554971D01*
X333828Y1555177D01*
X333559Y1555229D01*
X333291Y1555177D01*
X332946Y1554971D01*
X333061Y1556314D01*
X334096D01*
G01X308316Y1629011D02*
Y1636511D01*
X310556D01*
X311303Y1636136D01*
X311863Y1635261D01*
X312050Y1634261D01*
X311863Y1633261D01*
X311396Y1632511D01*
X310556Y1632136D01*
X308316D01*
G01X315816Y1629011D02*
Y1636511D01*
X318150D01*
X318896Y1636136D01*
X319363Y1635636D01*
X319550Y1634636D01*
X319363Y1633636D01*
X318803Y1633011D01*
X318150Y1632636D01*
X315816D01*
G01X318150D02*
X319550Y1629011D01*
G01X327050D02*
X323316D01*
Y1636511D01*
X327050D01*
G01X325556Y1632886D02*
X323316D01*
G01X330723Y1630011D02*
X331470Y1629386D01*
X332310Y1629011D01*
X333056D01*
X333803Y1629386D01*
X334363Y1630011D01*
X334643Y1630886D01*
X334456Y1631761D01*
X333990Y1632511D01*
X333150Y1633011D01*
X332030Y1633261D01*
X331376Y1633761D01*
X331096Y1634636D01*
X331283Y1635511D01*
X331750Y1636136D01*
X332403Y1636511D01*
X333056D01*
X333710Y1636261D01*
X334270Y1635636D01*
G01X338223Y1630011D02*
X338970Y1629386D01*
X339810Y1629011D01*
X340556D01*
X341303Y1629386D01*
X341863Y1630011D01*
X342143Y1630886D01*
X341956Y1631761D01*
X341490Y1632511D01*
X340650Y1633011D01*
X339530Y1633261D01*
X338876Y1633761D01*
X338596Y1634636D01*
X338783Y1635511D01*
X339250Y1636136D01*
X339903Y1636511D01*
X340556D01*
X341210Y1636261D01*
X341770Y1635636D01*
G01X346470Y1631511D02*
X348896D01*
G01X353410Y1629011D02*
Y1636511D01*
X356956D01*
G01X355650Y1632886D02*
X353410D01*
G01X361563Y1636511D02*
X363803D01*
G01X362683D02*
Y1629011D01*
G01X361563D02*
X363803D01*
G01X370183Y1636511D02*
Y1629011D01*
G01X368036Y1636511D02*
X372330D01*
G01X323290Y1656472D02*
X320190D01*
X322412Y1655054D01*
Y1656970D01*
G01X314796Y1655169D02*
X315158Y1655399D01*
X315364Y1655705D01*
X315416Y1656050D01*
X315364Y1656357D01*
X315106Y1656664D01*
X314796Y1656855D01*
X314486Y1656894D01*
X314124Y1656817D01*
X313866Y1656549D01*
X313763Y1656280D01*
Y1655935D01*
G01Y1656280D02*
X313608Y1656510D01*
X313349Y1656702D01*
X313039Y1656779D01*
X312729Y1656702D01*
X312471Y1656510D01*
X312316Y1656165D01*
X312368Y1655820D01*
X312574Y1655475D01*
G01X308018Y1736629D02*
X306952D01*
Y1739129D01*
X308018D01*
G01X307592Y1737921D02*
X306952D01*
G01X309098Y1736629D02*
Y1739129D01*
X309632D01*
X309845Y1739004D01*
X310005Y1738837D01*
X310138Y1738587D01*
X310245Y1738296D01*
X310272Y1737879D01*
X310245Y1737462D01*
X310138Y1737171D01*
X310005Y1736921D01*
X309845Y1736754D01*
X309632Y1736629D01*
X309098D01*
G01X312045Y1737879D02*
X312578D01*
Y1737129D01*
X312418Y1736879D01*
X312232Y1736712D01*
X311965Y1736629D01*
X311698Y1736712D01*
X311512Y1736879D01*
X311352Y1737129D01*
X311245Y1737421D01*
X311192Y1737754D01*
Y1738046D01*
X311245Y1738296D01*
X311352Y1738587D01*
X311512Y1738837D01*
X311672Y1739004D01*
X311885Y1739129D01*
X312072D01*
X312285Y1739046D01*
X312445Y1738879D01*
G01X314618Y1736629D02*
X313552D01*
Y1739129D01*
X314618D01*
G01X314192Y1737921D02*
X313552D01*
G01X318485Y1736629D02*
X318272Y1736671D01*
X318085Y1736837D01*
X317925Y1737087D01*
X317818Y1737379D01*
X317765Y1737712D01*
Y1738046D01*
X317818Y1738379D01*
X317925Y1738671D01*
X318085Y1738921D01*
X318272Y1739087D01*
X318485Y1739129D01*
X318698Y1739087D01*
X318885Y1738921D01*
X319045Y1738671D01*
X319152Y1738379D01*
X319205Y1738046D01*
Y1737712D01*
X319152Y1737379D01*
X319045Y1737087D01*
X318885Y1736837D01*
X318698Y1736671D01*
X318485Y1736629D01*
G01X320178D02*
Y1739129D01*
X321192D01*
G01X320818Y1737921D02*
X320178D01*
G01X324498Y1736629D02*
Y1739129D01*
X325032D01*
X325245Y1739004D01*
X325405Y1738837D01*
X325538Y1738587D01*
X325645Y1738296D01*
X325672Y1737879D01*
X325645Y1737462D01*
X325538Y1737171D01*
X325405Y1736921D01*
X325245Y1736754D01*
X325032Y1736629D01*
X324498D01*
G01X326618D02*
X327285Y1739129D01*
X327952Y1736629D01*
G01X327712Y1737504D02*
X326858D01*
G01X328898Y1739129D02*
Y1737337D01*
X329005Y1736962D01*
X329218Y1736712D01*
X329485Y1736629D01*
X329752Y1736712D01*
X329965Y1736962D01*
X330072Y1737337D01*
Y1739129D01*
G01X331845Y1737879D02*
X332378D01*
Y1737129D01*
X332218Y1736879D01*
X332032Y1736712D01*
X331765Y1736629D01*
X331498Y1736712D01*
X331312Y1736879D01*
X331152Y1737129D01*
X331045Y1737421D01*
X330992Y1737754D01*
Y1738046D01*
X331045Y1738296D01*
X331152Y1738587D01*
X331312Y1738837D01*
X331472Y1739004D01*
X331685Y1739129D01*
X331872D01*
X332085Y1739046D01*
X332245Y1738879D01*
G01X333325Y1736629D02*
Y1739129D01*
G01X334445D02*
Y1736629D01*
G01Y1737879D02*
X333325D01*
G01X336085Y1739129D02*
Y1736629D01*
G01X335472Y1739129D02*
X336698D01*
G01X338818Y1736629D02*
X337752D01*
Y1739129D01*
X338818D01*
G01X338392Y1737921D02*
X337752D01*
G01X339952Y1736629D02*
Y1739129D01*
X340618D01*
X340832Y1739004D01*
X340965Y1738837D01*
X341018Y1738504D01*
X340965Y1738171D01*
X340805Y1737962D01*
X340618Y1737837D01*
X339952D01*
G01X340618D02*
X341018Y1736629D01*
G01X345472Y1738921D02*
X345312Y1739046D01*
X345125Y1739129D01*
X344912D01*
X344672Y1739004D01*
X344485Y1738796D01*
X344352Y1738546D01*
X344245Y1738129D01*
X344218Y1737754D01*
X344272Y1737379D01*
X344352Y1737129D01*
X344512Y1736879D01*
X344698Y1736712D01*
X344885Y1736629D01*
X345072D01*
X345258Y1736712D01*
X345418Y1736837D01*
X345552Y1737004D01*
G01X346418Y1736629D02*
X347085Y1739129D01*
X347752Y1736629D01*
G01X347512Y1737504D02*
X346658D01*
G01X348752Y1736629D02*
Y1739129D01*
X349418D01*
X349632Y1739004D01*
X349765Y1738837D01*
X349818Y1738504D01*
X349765Y1738171D01*
X349605Y1737962D01*
X349418Y1737837D01*
X348752D01*
G01X349418D02*
X349818Y1736629D01*
G01X350898D02*
Y1739129D01*
X351432D01*
X351645Y1739004D01*
X351805Y1738837D01*
X351938Y1738587D01*
X352045Y1738296D01*
X352072Y1737879D01*
X352045Y1737462D01*
X351938Y1737171D01*
X351805Y1736921D01*
X351645Y1736754D01*
X351432Y1736629D01*
X350898D01*
G01X328600Y-620971D02*
X329200Y-620171D01*
X329900Y-619771D01*
X330700Y-619638D01*
X331700Y-619905D01*
X332400Y-620571D01*
X332600Y-621371D01*
X332500Y-622172D01*
X332100Y-622838D01*
X330100Y-624171D01*
X329200Y-625105D01*
X328600Y-626438D01*
X328400Y-627638D01*
X332600D01*
G01X338500Y-619638D02*
X337700Y-619905D01*
X337100Y-620571D01*
X336700Y-621371D01*
X336400Y-622438D01*
X336300Y-623638D01*
X336400Y-624838D01*
X336700Y-625905D01*
X337100Y-626705D01*
X337700Y-627371D01*
X338500Y-627638D01*
X339300Y-627371D01*
X339900Y-626705D01*
X340300Y-625905D01*
X340600Y-624838D01*
X340700Y-623638D01*
X340600Y-622438D01*
X340300Y-621371D01*
X339900Y-620571D01*
X339300Y-619905D01*
X338500Y-619638D01*
G01X344600Y-620971D02*
X345200Y-620171D01*
X345900Y-619771D01*
X346700Y-619638D01*
X347700Y-619905D01*
X348400Y-620571D01*
X348600Y-621371D01*
X348500Y-622172D01*
X348100Y-622838D01*
X346100Y-624171D01*
X345200Y-625105D01*
X344600Y-626438D01*
X344400Y-627638D01*
X348600D01*
G01X352300Y-626038D02*
X352900Y-626971D01*
X353700Y-627505D01*
X354600Y-627638D01*
X355400Y-627505D01*
X356200Y-626838D01*
X356700Y-626038D01*
X356800Y-625238D01*
X356600Y-624305D01*
X355900Y-623638D01*
X355200Y-623371D01*
X354300D01*
G01X355200D02*
X355800Y-622971D01*
X356300Y-622305D01*
X356500Y-621505D01*
X356300Y-620705D01*
X355800Y-620038D01*
X354900Y-619638D01*
X354000Y-619771D01*
X353100Y-620305D01*
G01X360700Y-627905D02*
X364300Y-619638D01*
G01X370500D02*
X369700Y-619905D01*
X369100Y-620571D01*
X368700Y-621371D01*
X368400Y-622438D01*
X368300Y-623638D01*
X368400Y-624838D01*
X368700Y-625905D01*
X369100Y-626705D01*
X369700Y-627371D01*
X370500Y-627638D01*
X371300Y-627371D01*
X371900Y-626705D01*
X372300Y-625905D01*
X372600Y-624838D01*
X372700Y-623638D01*
X372600Y-622438D01*
X372300Y-621371D01*
X371900Y-620571D01*
X371300Y-619905D01*
X370500Y-619638D01*
G01X379700Y-627638D02*
Y-619638D01*
X376000Y-625371D01*
X381000D01*
G01X384700Y-627905D02*
X388300Y-619638D01*
G01X394500Y-627638D02*
Y-619638D01*
X393300Y-621238D01*
G01Y-627638D02*
X395700D01*
G01X402300D02*
X402500Y-625905D01*
X402800Y-624438D01*
X403200Y-623105D01*
X403700Y-621638D01*
X404500Y-619638D01*
X400500D01*
G01X328300Y-602638D02*
Y-594638D01*
X330300D01*
X331100Y-595038D01*
X331700Y-595571D01*
X332200Y-596371D01*
X332600Y-597305D01*
X332700Y-598638D01*
X332600Y-599971D01*
X332200Y-600905D01*
X331700Y-601705D01*
X331100Y-602238D01*
X330300Y-602638D01*
X328300D01*
G01X336000D02*
X338500Y-594638D01*
X341000Y-602638D01*
G01X340100Y-599838D02*
X336900D01*
G01X344600Y-602638D02*
Y-594638D01*
X348400D01*
G01X347000Y-598505D02*
X344600D01*
G01X354500Y-594638D02*
X353700Y-594905D01*
X353100Y-595571D01*
X352700Y-596371D01*
X352400Y-597438D01*
X352300Y-598638D01*
X352400Y-599838D01*
X352700Y-600905D01*
X353100Y-601705D01*
X353700Y-602371D01*
X354500Y-602638D01*
X355300Y-602371D01*
X355900Y-601705D01*
X356300Y-600905D01*
X356600Y-599838D01*
X356700Y-598638D01*
X356600Y-597438D01*
X356300Y-596371D01*
X355900Y-595571D01*
X355300Y-594905D01*
X354500Y-594638D01*
G01X362500D02*
Y-602638D01*
G01X360200Y-594638D02*
X364800D01*
G01X367900Y-602638D02*
Y-594638D01*
X370500Y-601305D01*
X373100Y-594638D01*
Y-602638D01*
G01X379300Y-598371D02*
X379700Y-597971D01*
X380000Y-597305D01*
X380200Y-596371D01*
X380000Y-595571D01*
X379600Y-595038D01*
X378900Y-594638D01*
X376200D01*
Y-602638D01*
X379500D01*
X380200Y-602105D01*
X380600Y-601305D01*
X380800Y-600371D01*
X380600Y-599438D01*
X380000Y-598638D01*
X379300Y-598371D01*
X376200D01*
G01X384300Y-601038D02*
X384900Y-601971D01*
X385700Y-602505D01*
X386600Y-602638D01*
X387400Y-602505D01*
X388200Y-601838D01*
X388700Y-601038D01*
X388800Y-600238D01*
X388600Y-599305D01*
X387900Y-598638D01*
X387200Y-598371D01*
X386300D01*
G01X387200D02*
X387800Y-597971D01*
X388300Y-597305D01*
X388500Y-596505D01*
X388300Y-595705D01*
X387800Y-595038D01*
X386900Y-594638D01*
X386000Y-594771D01*
X385100Y-595305D01*
G01X393300Y-594638D02*
X395700D01*
G01X394500D02*
Y-602638D01*
G01X393300D02*
X395700D01*
G01X404700Y-595305D02*
X404100Y-594905D01*
X403400Y-594638D01*
X402600D01*
X401700Y-595038D01*
X401000Y-595705D01*
X400500Y-596505D01*
X400100Y-597838D01*
X400000Y-599038D01*
X400200Y-600238D01*
X400500Y-601038D01*
X401100Y-601838D01*
X401800Y-602371D01*
X402500Y-602638D01*
X403200D01*
X403900Y-602371D01*
X404500Y-601971D01*
X405000Y-601438D01*
G01X410500Y-594638D02*
X409700Y-594905D01*
X409100Y-595571D01*
X408700Y-596371D01*
X408400Y-597438D01*
X408300Y-598638D01*
X408400Y-599838D01*
X408700Y-600905D01*
X409100Y-601705D01*
X409700Y-602371D01*
X410500Y-602638D01*
X411300Y-602371D01*
X411900Y-601705D01*
X412300Y-600905D01*
X412600Y-599838D01*
X412700Y-598638D01*
X412600Y-597438D01*
X412300Y-596371D01*
X411900Y-595571D01*
X411300Y-594905D01*
X410500Y-594638D01*
G01X321898Y-2520D02*
Y51142D01*
G01X337594Y60153D02*
X335354D01*
G01X336567Y58528D02*
Y61778D01*
G01X333953Y65501D02*
Y54005D01*
G01X320942Y71463D02*
X327142D01*
G01D02*
Y68263D01*
G01D02*
X320942D01*
G01D02*
Y71463D01*
G01X327217Y78463D02*
Y72263D01*
G01D02*
X324017D01*
G01D02*
Y78463D01*
G01X321657Y93403D02*
Y90203D01*
G01X324017Y79643D02*
Y85843D01*
G01D02*
X327217D01*
G01D02*
Y79643D01*
G01D02*
X324017D01*
G01Y78463D02*
X327217D01*
G01X324221Y87542D02*
Y90642D01*
X325141D01*
X325448Y90487D01*
X325678Y90125D01*
X325755Y89712D01*
X325678Y89299D01*
X325486Y88989D01*
X325141Y88834D01*
X324221D01*
G01X327245Y90642D02*
Y88420D01*
X327398Y87955D01*
X327705Y87645D01*
X328088Y87542D01*
X328471Y87645D01*
X328778Y87955D01*
X328931Y88420D01*
Y90642D01*
G01X330460Y90125D02*
X330690Y90435D01*
X330958Y90590D01*
X331265Y90642D01*
X331648Y90539D01*
X331916Y90280D01*
X331993Y89970D01*
X331955Y89660D01*
X331801Y89402D01*
X331035Y88885D01*
X330690Y88524D01*
X330460Y88007D01*
X330383Y87542D01*
X331993D01*
G01X334288Y90642D02*
X333981Y90539D01*
X333751Y90280D01*
X333598Y89970D01*
X333483Y89557D01*
X333445Y89092D01*
X333483Y88627D01*
X333598Y88214D01*
X333751Y87904D01*
X333981Y87645D01*
X334288Y87542D01*
X334595Y87645D01*
X334825Y87904D01*
X334978Y88214D01*
X335093Y88627D01*
X335131Y89092D01*
X335093Y89557D01*
X334978Y89970D01*
X334825Y90280D01*
X334595Y90539D01*
X334288Y90642D01*
G01X337388Y87542D02*
Y90642D01*
X336928Y90022D01*
G01Y87542D02*
X337848D01*
G01X321699Y97452D02*
Y94252D01*
G01X321703Y101437D02*
Y98237D01*
G01X330746Y150520D02*
X324546D01*
G01D02*
Y153720D01*
G01X330746D02*
Y150520D01*
G01Y145520D02*
X324546D01*
G01D02*
Y148720D01*
G01D02*
X330746D01*
G01D02*
Y145520D01*
G01X339014Y163570D02*
X332814D01*
G01D02*
Y166770D01*
G01X324546Y153720D02*
X330746D01*
G01Y154520D02*
X324546D01*
G01D02*
Y157720D01*
G01D02*
X330746D01*
G01D02*
Y154520D01*
G01Y158520D02*
X324546D01*
G01D02*
Y161720D01*
G01D02*
X330746D01*
G01D02*
Y158520D01*
G01X332814Y166770D02*
X339014D01*
G01X336209Y168213D02*
X327351D01*
G01D02*
Y181567D01*
G01D02*
X336209D01*
G01X322383Y209500D02*
Y212600D01*
X323342D01*
X323648Y212445D01*
X323840Y212238D01*
X323917Y211825D01*
X323840Y211412D01*
X323610Y211153D01*
X323342Y210998D01*
X322383D01*
G01X323342D02*
X323917Y209500D01*
G01X325407Y210120D02*
X325637Y209758D01*
X325943Y209552D01*
X326288Y209500D01*
X326595Y209552D01*
X326902Y209810D01*
X327093Y210120D01*
X327132Y210430D01*
X327055Y210792D01*
X326787Y211050D01*
X326518Y211153D01*
X326173D01*
G01X326518D02*
X326748Y211308D01*
X326940Y211567D01*
X327017Y211877D01*
X326940Y212187D01*
X326748Y212445D01*
X326403Y212600D01*
X326058Y212548D01*
X325713Y212342D01*
G01X328622Y210792D02*
X328890Y211153D01*
X329120Y211360D01*
X329427Y211463D01*
X329695Y211360D01*
X329887Y211153D01*
X330040Y210843D01*
X330078Y210482D01*
X330040Y210172D01*
X329887Y209862D01*
X329657Y209603D01*
X329388Y209500D01*
X329082Y209603D01*
X328813Y209913D01*
X328660Y210378D01*
X328622Y210895D01*
X328698Y211567D01*
X328813Y211928D01*
X329005Y212290D01*
X329273Y212548D01*
X329542Y212600D01*
X329810Y212497D01*
X330002Y212238D01*
G01X331607Y210120D02*
X331837Y209758D01*
X332143Y209552D01*
X332488Y209500D01*
X332795Y209552D01*
X333102Y209810D01*
X333293Y210120D01*
X333332Y210430D01*
X333255Y210792D01*
X332987Y211050D01*
X332718Y211153D01*
X332373D01*
G01X332718D02*
X332948Y211308D01*
X333140Y211567D01*
X333217Y211877D01*
X333140Y212187D01*
X332948Y212445D01*
X332603Y212600D01*
X332258Y212548D01*
X331913Y212342D01*
G01X334707Y210120D02*
X334937Y209758D01*
X335243Y209552D01*
X335588Y209500D01*
X335895Y209552D01*
X336202Y209810D01*
X336393Y210120D01*
X336432Y210430D01*
X336355Y210792D01*
X336087Y211050D01*
X335818Y211153D01*
X335473D01*
G01X335818D02*
X336048Y211308D01*
X336240Y211567D01*
X336317Y211877D01*
X336240Y212187D01*
X336048Y212445D01*
X335703Y212600D01*
X335358Y212548D01*
X335013Y212342D01*
G01X321819Y245628D02*
Y214624D01*
X336619D01*
Y245628D01*
X321819D01*
G01X322884Y248178D02*
X325106D01*
X325571Y248331D01*
X325881Y248638D01*
X325984Y249021D01*
X325881Y249404D01*
X325571Y249711D01*
X325106Y249864D01*
X322884D01*
G01X325984Y252121D02*
X325932Y252389D01*
X325777Y252696D01*
X325519Y252888D01*
X325157Y252964D01*
X324796Y252888D01*
X324486Y252658D01*
X324331Y252313D01*
Y251929D01*
X324227Y251699D01*
X323969Y251508D01*
X323607Y251431D01*
X323246Y251546D01*
X322987Y251814D01*
X322884Y252121D01*
X322987Y252428D01*
X323246Y252696D01*
X323607Y252811D01*
X323969Y252734D01*
X324227Y252543D01*
X324331Y252313D01*
Y251929D01*
X324486Y251584D01*
X324796Y251354D01*
X325157Y251278D01*
X325519Y251354D01*
X325777Y251546D01*
X325932Y251853D01*
X325984Y252121D01*
G01X322884Y255221D02*
X322987Y254914D01*
X323246Y254684D01*
X323556Y254531D01*
X323969Y254416D01*
X324434Y254378D01*
X324899Y254416D01*
X325312Y254531D01*
X325622Y254684D01*
X325881Y254914D01*
X325984Y255221D01*
X325881Y255528D01*
X325622Y255758D01*
X325312Y255911D01*
X324899Y256026D01*
X324434Y256064D01*
X323969Y256026D01*
X323556Y255911D01*
X323246Y255758D01*
X322987Y255528D01*
X322884Y255221D01*
G01Y258321D02*
X322987Y258014D01*
X323246Y257784D01*
X323556Y257631D01*
X323969Y257516D01*
X324434Y257478D01*
X324899Y257516D01*
X325312Y257631D01*
X325622Y257784D01*
X325881Y258014D01*
X325984Y258321D01*
X325881Y258628D01*
X325622Y258858D01*
X325312Y259011D01*
X324899Y259126D01*
X324434Y259164D01*
X323969Y259126D01*
X323556Y259011D01*
X323246Y258858D01*
X322987Y258628D01*
X322884Y258321D01*
G01X323401Y260693D02*
X323091Y260923D01*
X322936Y261191D01*
X322884Y261498D01*
X322987Y261881D01*
X323246Y262149D01*
X323556Y262226D01*
X323866Y262188D01*
X324124Y262034D01*
X324641Y261268D01*
X325002Y260923D01*
X325519Y260693D01*
X325984Y260616D01*
Y262226D01*
G01X320600Y264600D02*
Y261400D01*
G01X322900Y267500D02*
Y280500D01*
G01X339100Y267500D02*
X322900D01*
G01X323307Y285067D02*
Y282845D01*
X323460Y282380D01*
X323767Y282070D01*
X324150Y281967D01*
X324533Y282070D01*
X324840Y282380D01*
X324993Y282845D01*
Y285067D01*
G01X326407Y282587D02*
X326637Y282225D01*
X326943Y282019D01*
X327288Y281967D01*
X327595Y282019D01*
X327902Y282277D01*
X328093Y282587D01*
X328132Y282897D01*
X328055Y283259D01*
X327787Y283517D01*
X327518Y283620D01*
X327173D01*
G01X327518D02*
X327748Y283775D01*
X327940Y284034D01*
X328017Y284344D01*
X327940Y284654D01*
X327748Y284912D01*
X327403Y285067D01*
X327058Y285015D01*
X326713Y284809D01*
G01X330810Y281967D02*
Y285067D01*
X329392Y282845D01*
X331308D01*
G01X332500Y280500D02*
X339100D01*
G01X331000Y278000D02*
X332500Y280500D01*
G01X329500D02*
X331000Y278000D01*
G01X322900Y280500D02*
X329500D01*
G01X324291Y547121D02*
X330491D01*
G01D02*
Y543921D01*
G01D02*
X324291D01*
G01D02*
Y547121D01*
G01X332775Y549534D02*
X323975D01*
G01Y555334D02*
Y549534D01*
G01X332775Y563134D02*
Y549534D01*
G01X327129Y567686D02*
X333329D01*
G01D02*
Y564486D01*
G01D02*
X327129D01*
G01D02*
Y567686D01*
G01X323975Y557334D02*
X325475Y556334D01*
G01D02*
X323975Y555334D01*
G01Y563134D02*
X332775D01*
G01X323975D02*
Y557334D01*
G01X335588Y592204D02*
X332388D01*
G01D02*
Y598404D01*
G01X320961Y608361D02*
Y596361D01*
G01X331986Y596594D02*
Y596494D01*
G01Y601094D02*
Y596494D01*
G01D02*
X321986D01*
G01Y601094D02*
Y596494D01*
G01X332388Y598404D02*
X335588D01*
G01X321986Y601094D02*
X331986D01*
G01X336161Y697240D02*
X332961D01*
G01D02*
Y703440D01*
G01X325991Y700546D02*
X332191D01*
G01D02*
Y697346D01*
G01D02*
X325991D01*
G01D02*
Y700546D01*
G01X322566Y704250D02*
Y698050D01*
G01X325118Y691854D02*
Y694954D01*
X326038D01*
X326345Y694799D01*
X326575Y694437D01*
X326652Y694024D01*
X326575Y693611D01*
X326383Y693301D01*
X326038Y693146D01*
X325118D01*
G01X328142Y694954D02*
Y692732D01*
X328295Y692267D01*
X328602Y691957D01*
X328985Y691854D01*
X329368Y691957D01*
X329675Y692267D01*
X329828Y692732D01*
Y694954D01*
G01X332545Y691854D02*
Y694954D01*
X331127Y692732D01*
X333043D01*
G01X332961Y703440D02*
X336161D01*
G01X333798Y709507D02*
Y707653D01*
G01D02*
X332790D01*
G01X333005Y731275D02*
X333798D01*
G01D02*
Y728675D01*
G01Y722064D02*
Y720366D01*
G01X338255Y734492D02*
X332914D01*
G01Y777800D02*
X338255D01*
G01X332393Y857797D02*
G03X334362Y855828I1969J0D01*
G01X332393Y857797D02*
Y870789D01*
G01X346173Y855828D02*
X334362D01*
G01X328701Y1260477D02*
Y1303785D01*
G01X334042Y1260477D02*
X328701D01*
G01X325325D02*
Y1303785D01*
G01X331558Y1308585D02*
Y1305385D01*
G01X325358Y1308585D02*
X331558D01*
G01X325358Y1305385D02*
Y1308585D01*
G01X331558Y1305385D02*
X325358D01*
G01X330124Y1308885D02*
X326924D01*
G01X330124Y1315085D02*
Y1308885D01*
G01X326924D02*
Y1315085D01*
G01X333158Y1307002D02*
Y1309602D01*
G01X333951Y1307002D02*
X333158D01*
G01X328701Y1303785D02*
X334042D01*
G01X322957Y1322527D02*
X326157D01*
G01X322957Y1316327D02*
Y1322527D01*
G01X326157Y1316327D02*
X322957D01*
G01X326157Y1322527D02*
Y1316327D01*
G01X330101Y1326206D02*
X326901D01*
G01D02*
Y1332406D01*
G01X330101Y1328100D02*
Y1326206D01*
G01X326901Y1321906D02*
X330101D01*
G01X326901Y1315706D02*
Y1321906D01*
G01X330101Y1315706D02*
X326901D01*
G01X330101Y1321906D02*
Y1315706D01*
G01X326924Y1315085D02*
X330124D01*
G01X333158Y1316213D02*
Y1317911D01*
G01X330101Y1332406D02*
Y1331200D01*
G01X326901Y1332406D02*
X330101D01*
G01X333995Y1334837D02*
X330795D01*
G01X333995Y1341037D02*
Y1334837D01*
G01X330795Y1341037D02*
X333995D01*
G01X330795Y1334837D02*
Y1341037D01*
G01X323617Y1334474D02*
Y1337674D01*
G01X329817Y1334474D02*
X323617D01*
G01X329817Y1337674D02*
Y1334474D01*
G01X323617Y1337674D02*
X329817D01*
G01X334765Y1337731D02*
Y1340931D01*
G01X340965Y1337731D02*
X334765D01*
G01Y1340931D02*
X340965D01*
G01X333158Y1330624D02*
X334166D01*
G01X333158Y1328770D02*
Y1330624D01*
G01X331383Y1351000D02*
Y1354100D01*
X332303D01*
X332610Y1353945D01*
X332840Y1353583D01*
X332917Y1353170D01*
X332840Y1352757D01*
X332648Y1352447D01*
X332303Y1352292D01*
X331383D01*
G01X334407Y1354100D02*
Y1351878D01*
X334560Y1351413D01*
X334867Y1351103D01*
X335250Y1351000D01*
X335633Y1351103D01*
X335940Y1351413D01*
X336093Y1351878D01*
Y1354100D01*
G01X337507Y1351620D02*
X337737Y1351258D01*
X338043Y1351052D01*
X338388Y1351000D01*
X338695Y1351052D01*
X339002Y1351310D01*
X339193Y1351620D01*
X339232Y1351930D01*
X339155Y1352292D01*
X338887Y1352550D01*
X338618Y1352653D01*
X338273D01*
G01X338618D02*
X338848Y1352808D01*
X339040Y1353067D01*
X339117Y1353377D01*
X339040Y1353687D01*
X338848Y1353945D01*
X338503Y1354100D01*
X338158Y1354048D01*
X337813Y1353842D01*
G01X340607Y1351465D02*
X340837Y1351207D01*
X341105Y1351052D01*
X341450Y1351000D01*
X341795Y1351103D01*
X342063Y1351310D01*
X342255Y1351672D01*
X342293Y1352085D01*
X342217Y1352498D01*
X342025Y1352757D01*
X341757Y1352963D01*
X341488Y1353015D01*
X341220Y1352963D01*
X340875Y1352757D01*
X340990Y1354100D01*
X342025D01*
G01X331383Y1346500D02*
Y1349600D01*
X332303D01*
X332610Y1349445D01*
X332840Y1349083D01*
X332917Y1348670D01*
X332840Y1348257D01*
X332648Y1347947D01*
X332303Y1347792D01*
X331383D01*
G01X334483Y1349600D02*
Y1346500D01*
X336017D01*
G01X338810D02*
Y1349600D01*
X337392Y1347378D01*
X339308D01*
G01X341450Y1349600D02*
X341143Y1349497D01*
X340913Y1349238D01*
X340760Y1348928D01*
X340645Y1348515D01*
X340607Y1348050D01*
X340645Y1347585D01*
X340760Y1347172D01*
X340913Y1346862D01*
X341143Y1346603D01*
X341450Y1346500D01*
X341757Y1346603D01*
X341987Y1346862D01*
X342140Y1347172D01*
X342255Y1347585D01*
X342293Y1348050D01*
X342255Y1348515D01*
X342140Y1348928D01*
X341987Y1349238D01*
X341757Y1349497D01*
X341450Y1349600D01*
G01X321883Y1364500D02*
Y1367600D01*
X322803D01*
X323110Y1367445D01*
X323340Y1367083D01*
X323417Y1366670D01*
X323340Y1366257D01*
X323148Y1365947D01*
X322803Y1365792D01*
X321883D01*
G01X326593Y1367342D02*
X326363Y1367497D01*
X326095Y1367600D01*
X325788D01*
X325443Y1367445D01*
X325175Y1367187D01*
X324983Y1366877D01*
X324830Y1366360D01*
X324792Y1365895D01*
X324868Y1365430D01*
X324983Y1365120D01*
X325213Y1364810D01*
X325482Y1364603D01*
X325750Y1364500D01*
X326018D01*
X326287Y1364603D01*
X326517Y1364758D01*
X326708Y1364965D01*
G01X328007Y1365120D02*
X328237Y1364758D01*
X328543Y1364552D01*
X328888Y1364500D01*
X329195Y1364552D01*
X329502Y1364810D01*
X329693Y1365120D01*
X329732Y1365430D01*
X329655Y1365792D01*
X329387Y1366050D01*
X329118Y1366153D01*
X328773D01*
G01X329118D02*
X329348Y1366308D01*
X329540Y1366567D01*
X329617Y1366877D01*
X329540Y1367187D01*
X329348Y1367445D01*
X329003Y1367600D01*
X328658Y1367548D01*
X328313Y1367342D01*
G01X331298Y1364862D02*
X331567Y1364603D01*
X331873Y1364500D01*
X332180Y1364603D01*
X332448Y1364913D01*
X332640Y1365378D01*
X332717Y1365843D01*
Y1366412D01*
X332640Y1366877D01*
X332448Y1367290D01*
X332218Y1367497D01*
X331950Y1367600D01*
X331643Y1367497D01*
X331413Y1367290D01*
X331260Y1366980D01*
X331183Y1366567D01*
X331260Y1366205D01*
X331452Y1365843D01*
X331682Y1365637D01*
X331950Y1365585D01*
X332257Y1365688D01*
X332487Y1365947D01*
X332717Y1366412D01*
G01X335050Y1367600D02*
X334743Y1367497D01*
X334513Y1367238D01*
X334360Y1366928D01*
X334245Y1366515D01*
X334207Y1366050D01*
X334245Y1365585D01*
X334360Y1365172D01*
X334513Y1364862D01*
X334743Y1364603D01*
X335050Y1364500D01*
X335357Y1364603D01*
X335587Y1364862D01*
X335740Y1365172D01*
X335855Y1365585D01*
X335893Y1366050D01*
X335855Y1366515D01*
X335740Y1366928D01*
X335587Y1367238D01*
X335357Y1367497D01*
X335050Y1367600D01*
G01X337443Y1373894D02*
X332694D01*
G01X320545D02*
X325294D01*
G01X332694Y1400666D02*
X342380D01*
G01X330699Y1655169D02*
X330957Y1655399D01*
X331112Y1655667D01*
X331164Y1656012D01*
X331061Y1656357D01*
X330854Y1656625D01*
X330492Y1656817D01*
X330079Y1656855D01*
X329666Y1656779D01*
X329407Y1656587D01*
X329201Y1656319D01*
X329149Y1656050D01*
X329201Y1655782D01*
X329407Y1655437D01*
X328064Y1655552D01*
Y1656587D01*
G01X346100Y-577638D02*
Y-569638D01*
X349900D01*
G01X348500Y-573505D02*
X346100D01*
G01X356000Y-569638D02*
X355200Y-569905D01*
X354600Y-570571D01*
X354200Y-571371D01*
X353900Y-572438D01*
X353800Y-573638D01*
X353900Y-574838D01*
X354200Y-575905D01*
X354600Y-576705D01*
X355200Y-577371D01*
X356000Y-577638D01*
X356800Y-577371D01*
X357400Y-576705D01*
X357800Y-575905D01*
X358100Y-574838D01*
X358200Y-573638D01*
X358100Y-572438D01*
X357800Y-571371D01*
X357400Y-570571D01*
X356800Y-569905D01*
X356000Y-569638D01*
G01X364000D02*
Y-577638D01*
G01X361700Y-569638D02*
X366300D01*
G01X372600Y-573638D02*
X374600D01*
Y-576038D01*
X374000Y-576838D01*
X373300Y-577371D01*
X372300Y-577638D01*
X371300Y-577371D01*
X370600Y-576838D01*
X370000Y-576038D01*
X369600Y-575105D01*
X369400Y-574038D01*
Y-573105D01*
X369600Y-572305D01*
X370000Y-571371D01*
X370600Y-570571D01*
X371200Y-570038D01*
X372000Y-569638D01*
X372700D01*
X373500Y-569905D01*
X374100Y-570438D01*
G01X377000Y-580305D02*
X383000D01*
G01X385400Y-577638D02*
Y-569638D01*
X388000Y-576305D01*
X390600Y-569638D01*
Y-577638D01*
G01X396800Y-573371D02*
X397200Y-572971D01*
X397500Y-572305D01*
X397700Y-571371D01*
X397500Y-570571D01*
X397100Y-570038D01*
X396400Y-569638D01*
X393700D01*
Y-577638D01*
X397000D01*
X397700Y-577105D01*
X398100Y-576305D01*
X398300Y-575371D01*
X398100Y-574438D01*
X397500Y-573638D01*
X396800Y-573371D01*
X393700D01*
G01X342320Y61880D02*
Y64980D01*
X343240D01*
X343547Y64825D01*
X343777Y64463D01*
X343854Y64050D01*
X343777Y63637D01*
X343585Y63327D01*
X343240Y63172D01*
X342320D01*
G01X345344Y61880D02*
Y64980D01*
X346110D01*
X346417Y64825D01*
X346647Y64618D01*
X346839Y64308D01*
X346992Y63947D01*
X347030Y63430D01*
X346992Y62913D01*
X346839Y62552D01*
X346647Y62242D01*
X346417Y62035D01*
X346110Y61880D01*
X345344D01*
G01X349287D02*
Y64980D01*
X348827Y64360D01*
G01Y61880D02*
X349747D01*
G01X352387Y64980D02*
X352080Y64877D01*
X351850Y64618D01*
X351697Y64308D01*
X351582Y63895D01*
X351544Y63430D01*
X351582Y62965D01*
X351697Y62552D01*
X351850Y62242D01*
X352080Y61983D01*
X352387Y61880D01*
X352694Y61983D01*
X352924Y62242D01*
X353077Y62552D01*
X353192Y62965D01*
X353230Y63430D01*
X353192Y63895D01*
X353077Y64308D01*
X352924Y64618D01*
X352694Y64877D01*
X352387Y64980D01*
G01X355487Y61880D02*
X355755Y61932D01*
X356062Y62087D01*
X356254Y62345D01*
X356330Y62707D01*
X356254Y63068D01*
X356024Y63378D01*
X355679Y63533D01*
X355295D01*
X355065Y63637D01*
X354874Y63895D01*
X354797Y64257D01*
X354912Y64618D01*
X355180Y64877D01*
X355487Y64980D01*
X355794Y64877D01*
X356062Y64618D01*
X356177Y64257D01*
X356100Y63895D01*
X355909Y63637D01*
X355679Y63533D01*
X355295D01*
X354950Y63378D01*
X354720Y63068D01*
X354644Y62707D01*
X354720Y62345D01*
X354912Y62087D01*
X355219Y61932D01*
X355487Y61880D01*
G01X344496Y120163D02*
Y132367D01*
G01X360496Y120163D02*
X344496D01*
G01X338211Y121577D02*
Y127777D01*
G01D02*
X341411D01*
G01D02*
Y121577D01*
G01D02*
X338211D01*
G01X343903Y137232D02*
Y135010D01*
X344056Y134545D01*
X344363Y134235D01*
X344746Y134132D01*
X345129Y134235D01*
X345436Y134545D01*
X345589Y135010D01*
Y137232D01*
G01X347003Y134752D02*
X347233Y134390D01*
X347539Y134184D01*
X347884Y134132D01*
X348191Y134184D01*
X348498Y134442D01*
X348689Y134752D01*
X348728Y135062D01*
X348651Y135424D01*
X348383Y135682D01*
X348114Y135785D01*
X347769D01*
G01X348114D02*
X348344Y135940D01*
X348536Y136199D01*
X348613Y136509D01*
X348536Y136819D01*
X348344Y137077D01*
X347999Y137232D01*
X347654Y137180D01*
X347309Y136974D01*
G01X350218Y136715D02*
X350448Y137025D01*
X350716Y137180D01*
X351023Y137232D01*
X351406Y137129D01*
X351674Y136870D01*
X351751Y136560D01*
X351713Y136250D01*
X351559Y135992D01*
X350793Y135475D01*
X350448Y135114D01*
X350218Y134597D01*
X350141Y134132D01*
X351751D01*
G01X354046D02*
Y137232D01*
X353586Y136612D01*
G01Y134132D02*
X354506D01*
G01X344496Y132367D02*
X360496D01*
G01X339014Y166770D02*
Y163570D01*
G01X338063Y168987D02*
X340285D01*
X340750Y169140D01*
X341060Y169447D01*
X341163Y169830D01*
X341060Y170213D01*
X340750Y170520D01*
X340285Y170673D01*
X338063D01*
G01X338580Y172202D02*
X338270Y172432D01*
X338115Y172700D01*
X338063Y173007D01*
X338166Y173390D01*
X338425Y173658D01*
X338735Y173735D01*
X339045Y173697D01*
X339303Y173543D01*
X339820Y172777D01*
X340181Y172432D01*
X340698Y172202D01*
X341163Y172125D01*
Y173735D01*
G01X338063Y176030D02*
X338166Y175723D01*
X338425Y175493D01*
X338735Y175340D01*
X339148Y175225D01*
X339613Y175187D01*
X340078Y175225D01*
X340491Y175340D01*
X340801Y175493D01*
X341060Y175723D01*
X341163Y176030D01*
X341060Y176337D01*
X340801Y176567D01*
X340491Y176720D01*
X340078Y176835D01*
X339613Y176873D01*
X339148Y176835D01*
X338735Y176720D01*
X338425Y176567D01*
X338166Y176337D01*
X338063Y176030D01*
G01X341163Y179053D02*
X340491Y179130D01*
X339923Y179245D01*
X339406Y179398D01*
X338838Y179590D01*
X338063Y179897D01*
Y178363D01*
G01X336209Y181567D02*
Y168213D01*
G01X346751Y168658D02*
Y171758D01*
G01X348361D02*
Y168658D01*
G01Y170208D02*
X346751D01*
G01X350579Y168658D02*
X350656Y169330D01*
X350771Y169898D01*
X350924Y170415D01*
X351116Y170983D01*
X351423Y171758D01*
X349889D01*
G01X352913Y169123D02*
X353143Y168865D01*
X353411Y168710D01*
X353756Y168658D01*
X354101Y168761D01*
X354369Y168968D01*
X354561Y169330D01*
X354599Y169743D01*
X354523Y170156D01*
X354331Y170415D01*
X354063Y170621D01*
X353794Y170673D01*
X353526Y170621D01*
X353181Y170415D01*
X353296Y171758D01*
X354331D01*
G01X347816Y226670D02*
Y223470D01*
G01D02*
X341616D01*
G01D02*
Y226670D01*
G01X348295Y238655D02*
Y232455D01*
G01D02*
X345095D01*
G01D02*
Y238655D01*
G01D02*
X348295D01*
G01X347770Y227580D02*
X341570D01*
G01D02*
Y230780D01*
G01D02*
X347770D01*
G01D02*
Y227580D01*
G01X341616Y226670D02*
X347816D01*
G01X348786Y239113D02*
Y242213D01*
X349706D01*
X350013Y242058D01*
X350243Y241696D01*
X350320Y241283D01*
X350243Y240870D01*
X350051Y240560D01*
X349706Y240405D01*
X348786D01*
G01X351810Y242213D02*
Y239991D01*
X351963Y239526D01*
X352270Y239216D01*
X352653Y239113D01*
X353036Y239216D01*
X353343Y239526D01*
X353496Y239991D01*
Y242213D01*
G01X355025Y241696D02*
X355255Y242006D01*
X355523Y242161D01*
X355830Y242213D01*
X356213Y242110D01*
X356481Y241851D01*
X356558Y241541D01*
X356520Y241231D01*
X356366Y240973D01*
X355600Y240456D01*
X355255Y240095D01*
X355025Y239578D01*
X354948Y239113D01*
X356558D01*
G01X358853Y242213D02*
X358546Y242110D01*
X358316Y241851D01*
X358163Y241541D01*
X358048Y241128D01*
X358010Y240663D01*
X358048Y240198D01*
X358163Y239785D01*
X358316Y239475D01*
X358546Y239216D01*
X358853Y239113D01*
X359160Y239216D01*
X359390Y239475D01*
X359543Y239785D01*
X359658Y240198D01*
X359696Y240663D01*
X359658Y241128D01*
X359543Y241541D01*
X359390Y241851D01*
X359160Y242110D01*
X358853Y242213D01*
G01X361953D02*
X361646Y242110D01*
X361416Y241851D01*
X361263Y241541D01*
X361148Y241128D01*
X361110Y240663D01*
X361148Y240198D01*
X361263Y239785D01*
X361416Y239475D01*
X361646Y239216D01*
X361953Y239113D01*
X362260Y239216D01*
X362490Y239475D01*
X362643Y239785D01*
X362758Y240198D01*
X362796Y240663D01*
X362758Y241128D01*
X362643Y241541D01*
X362490Y241851D01*
X362260Y242110D01*
X361953Y242213D01*
G01X347753Y268786D02*
X344553D01*
G01X347753Y274986D02*
Y268786D01*
G01X344553D02*
Y274986D01*
G01X339100Y280500D02*
Y267500D01*
G01X355618Y261810D02*
X349618D01*
G01D02*
Y273810D01*
G01X337400Y283400D02*
Y286600D01*
G01X343600Y283400D02*
X337400D01*
G01X343600Y286600D02*
Y283400D01*
G01X340400Y282100D02*
X343600D01*
G01X340400Y275900D02*
Y282100D01*
G01X343600Y275900D02*
X340400D01*
G01X343600Y282100D02*
Y275900D01*
G01X344553Y274986D02*
X347753D01*
G01X349618Y273810D02*
X355618D01*
G01X337400Y286600D02*
X343600D01*
G01X349789Y299048D02*
Y302148D01*
X350709D01*
X351016Y301993D01*
X351246Y301631D01*
X351323Y301218D01*
X351246Y300805D01*
X351054Y300495D01*
X350709Y300340D01*
X349789D01*
G01X352813Y302148D02*
Y299926D01*
X352966Y299461D01*
X353273Y299151D01*
X353656Y299048D01*
X354039Y299151D01*
X354346Y299461D01*
X354499Y299926D01*
Y302148D01*
G01X356028Y301631D02*
X356258Y301941D01*
X356526Y302096D01*
X356833Y302148D01*
X357216Y302045D01*
X357484Y301786D01*
X357561Y301476D01*
X357523Y301166D01*
X357369Y300908D01*
X356603Y300391D01*
X356258Y300030D01*
X356028Y299513D01*
X355951Y299048D01*
X357561D01*
G01X359856Y302148D02*
X359549Y302045D01*
X359319Y301786D01*
X359166Y301476D01*
X359051Y301063D01*
X359013Y300598D01*
X359051Y300133D01*
X359166Y299720D01*
X359319Y299410D01*
X359549Y299151D01*
X359856Y299048D01*
X360163Y299151D01*
X360393Y299410D01*
X360546Y299720D01*
X360661Y300133D01*
X360699Y300598D01*
X360661Y301063D01*
X360546Y301476D01*
X360393Y301786D01*
X360163Y302045D01*
X359856Y302148D01*
G01X362879Y299048D02*
X362956Y299720D01*
X363071Y300288D01*
X363224Y300805D01*
X363416Y301373D01*
X363723Y302148D01*
X362189D01*
G01X349757Y575940D02*
Y569740D01*
G01D02*
X346557D01*
G01D02*
Y575940D01*
G01D02*
X349757D01*
G01X335588Y598404D02*
Y592204D01*
G01X344057Y588015D02*
X350257D01*
G01Y584815D02*
X344057D01*
G01D02*
Y588015D01*
G01X335569Y638110D02*
Y614094D01*
G01D02*
X341680D01*
G01Y638110D02*
X335569D01*
G01X336161Y703440D02*
Y697240D01*
G01X343339Y700603D02*
X337139D01*
G01D02*
Y703803D01*
G01X343339D02*
Y700603D01*
G01X348384Y697782D02*
Y703982D01*
G01X351584Y697782D02*
X348384D01*
G01X337139Y703803D02*
X343339D01*
G01X348384Y703982D02*
X351584D01*
G01X341110Y715712D02*
Y721912D01*
G01X344310D02*
Y715712D01*
G01D02*
X341110D01*
G01X340055Y712071D02*
Y705871D01*
G01D02*
X336855D01*
G01D02*
Y707000D01*
G01Y712071D02*
X340055D01*
G01X336855Y709500D02*
Y712071D01*
G01Y716371D02*
Y722571D01*
G01X340055D02*
Y716371D01*
G01D02*
X336855D01*
G01X347905Y707385D02*
X347172D01*
G01D02*
Y709576D01*
G01X341110Y721912D02*
X344310D01*
G01X336855Y722571D02*
X340055D01*
G01X335398Y729692D02*
Y732892D01*
G01X341598Y729692D02*
X335398D01*
G01X341598Y732892D02*
Y729692D01*
G01X336832Y729392D02*
X340032D01*
G01X336832Y723192D02*
Y729392D01*
G01X340032Y723192D02*
X336832D01*
G01X340032Y729392D02*
Y723192D01*
G01X347172Y728407D02*
Y731007D01*
G01D02*
X347965D01*
G01X335398Y732892D02*
X341598D01*
G01X341787Y734404D02*
X347128D01*
G01X341787Y777712D02*
Y734404D01*
G01X338255Y777800D02*
Y734492D01*
G01X347128Y777712D02*
X341787D01*
G01X346173Y855828D02*
G03X348141Y857797I-1J1969D01*
G01Y870789D02*
Y857797D01*
G01X338102Y1180631D02*
Y1167639D01*
G01X351881Y1182600D02*
X340070D01*
G01D02*
G03X338102Y1180631I0J-1968D01*
G01X348432Y1340227D02*
X351632D01*
G01X348432Y1334027D02*
Y1340227D01*
G01X351632Y1334027D02*
X348432D01*
G01X340965Y1340931D02*
Y1337731D01*
G01X347590Y1334027D02*
X344390D01*
G01X347590Y1340227D02*
Y1334027D01*
G01X344390Y1340227D02*
X347590D01*
G01X344390Y1334027D02*
Y1340227D01*
G01X344440Y1367903D02*
X350551D01*
G01X344440Y1391919D02*
Y1367903D01*
G01X342380Y1378831D02*
X337443Y1373894D01*
G01X342380Y1400666D02*
Y1378831D01*
G01X350551Y1391919D02*
X344440D01*
G01X346912Y1655935D02*
X346240Y1656012D01*
X345672Y1656127D01*
X345155Y1656280D01*
X344587Y1656472D01*
X343812Y1656779D01*
Y1655245D01*
G01X337746Y1655284D02*
X337385Y1655552D01*
X337178Y1655782D01*
X337075Y1656089D01*
X337178Y1656357D01*
X337385Y1656549D01*
X337695Y1656702D01*
X338056Y1656740D01*
X338366Y1656702D01*
X338676Y1656549D01*
X338935Y1656319D01*
X339038Y1656050D01*
X338935Y1655744D01*
X338625Y1655475D01*
X338160Y1655322D01*
X337643Y1655284D01*
X336971Y1655360D01*
X336610Y1655475D01*
X336248Y1655667D01*
X335990Y1655935D01*
X335938Y1656204D01*
X336041Y1656472D01*
X336300Y1656664D01*
G01X353354Y108879D02*
Y111979D01*
G01X354964D02*
Y108879D01*
G01Y110429D02*
X353354D01*
G01X356607Y109241D02*
X356876Y108982D01*
X357182Y108879D01*
X357489Y108982D01*
X357757Y109292D01*
X357949Y109757D01*
X358026Y110222D01*
Y110791D01*
X357949Y111256D01*
X357757Y111669D01*
X357527Y111876D01*
X357259Y111979D01*
X356952Y111876D01*
X356722Y111669D01*
X356569Y111359D01*
X356492Y110946D01*
X356569Y110584D01*
X356761Y110222D01*
X356991Y110016D01*
X357259Y109964D01*
X357566Y110067D01*
X357796Y110326D01*
X358026Y110791D01*
G01X359516Y109499D02*
X359746Y109137D01*
X360052Y108931D01*
X360397Y108879D01*
X360704Y108931D01*
X361011Y109189D01*
X361202Y109499D01*
X361241Y109809D01*
X361164Y110171D01*
X360896Y110429D01*
X360627Y110532D01*
X360282D01*
G01X360627D02*
X360857Y110687D01*
X361049Y110946D01*
X361126Y111256D01*
X361049Y111566D01*
X360857Y111824D01*
X360512Y111979D01*
X360167Y111927D01*
X359822Y111721D01*
G01X360496Y132367D02*
Y120163D01*
G01X362096Y131765D02*
X368296D01*
G01Y128565D02*
X362096D01*
G01D02*
Y131765D01*
G01X370415Y209761D02*
X364215D01*
G01D02*
Y212961D01*
G01X357033Y213007D02*
Y209807D01*
G01D02*
X350833D01*
G01D02*
Y213007D01*
G01X350815Y216925D02*
X357015D01*
G01D02*
Y213725D01*
G01D02*
X350815D01*
G01D02*
Y216925D01*
G01X357033Y217743D02*
X350833D01*
G01D02*
Y220943D01*
G01D02*
X357033D01*
G01D02*
Y217743D01*
G01X364215Y212961D02*
X370415D01*
G01X364215Y220961D02*
X370415D01*
G01Y217761D02*
X364215D01*
G01D02*
Y220961D01*
G01X350833Y213007D02*
X357033D01*
G01X364215Y216961D02*
X370415D01*
G01Y213761D02*
X364215D01*
G01D02*
Y216961D01*
G01X353057Y225561D02*
X367033D01*
G01Y233749D02*
X353057D01*
G01D02*
Y225561D01*
G01X355618Y273810D02*
Y261810D01*
G01X351028Y282190D02*
Y288390D01*
G01X354228D02*
Y282190D01*
G01D02*
X351028D01*
G01X354208Y281430D02*
Y275230D01*
G01D02*
X351008D01*
G01D02*
Y281430D01*
G01D02*
X354208D01*
G01X356908Y271970D02*
Y277970D01*
G01D02*
X368908D01*
G01Y271970D02*
X356908D01*
G01X372475Y280989D02*
X360701D01*
G01D02*
Y290751D01*
G01X351028Y288390D02*
X354228D01*
G01X367508Y292430D02*
X361308D01*
G01D02*
Y295630D01*
G01D02*
X367508D01*
G01X357428Y296490D02*
Y290290D01*
G01D02*
X354228D01*
G01D02*
Y296490D01*
G01D02*
X357428D01*
G01X360701Y290751D02*
X372475D01*
G01X356400Y305900D02*
Y309100D01*
G01X362600Y305900D02*
X356400D01*
G01X362600Y309100D02*
Y305900D01*
G01X356400Y309100D02*
X362600D01*
G01X354507Y552015D02*
X360707D01*
G01D02*
Y548815D01*
G01D02*
X354507D01*
G01D02*
Y552015D01*
G01X355982Y553690D02*
Y559890D01*
G01D02*
X359182D01*
G01D02*
Y553690D01*
G01D02*
X355982D01*
G01X352057Y564015D02*
X358257D01*
G01D02*
Y560815D01*
G01D02*
X352057D01*
G01D02*
Y564015D01*
G01X351982Y553690D02*
Y559890D01*
G01D02*
X355182D01*
G01D02*
Y553690D01*
G01D02*
X351982D01*
G01X358257Y568015D02*
Y564815D01*
G01D02*
X352057D01*
G01D02*
Y568015D01*
G01X358257Y580815D02*
X352057D01*
G01D02*
Y584015D01*
G01X358257D02*
Y580815D01*
G01X352057Y580015D02*
X358257D01*
G01Y576815D02*
X352057D01*
G01D02*
Y580015D01*
G01X358257D02*
Y576815D01*
G01X352057Y568015D02*
X358257D01*
G01X352057Y572015D02*
X358257D01*
G01D02*
Y568815D01*
G01D02*
X352057D01*
G01D02*
Y572015D01*
G01Y576015D02*
X358257D01*
G01D02*
Y572815D01*
G01D02*
X352057D01*
G01D02*
Y576015D01*
G01X350257Y588015D02*
Y584815D01*
G01X360657Y588815D02*
X354457D01*
G01D02*
Y592015D01*
G01D02*
X360657D01*
G01D02*
Y588815D01*
G01Y584815D02*
X354457D01*
G01D02*
Y588015D01*
G01D02*
X360657D01*
G01D02*
Y584815D01*
G01X352057Y584015D02*
X358257D01*
G01X363032Y619038D02*
X369232D01*
G01Y615838D02*
X363032D01*
G01D02*
Y619038D01*
G01X363753Y626681D02*
X360653D01*
Y627601D01*
X360808Y627908D01*
X361170Y628138D01*
X361583Y628215D01*
X361996Y628138D01*
X362306Y627946D01*
X362461Y627601D01*
Y626681D01*
G01X360653Y629781D02*
X363753D01*
Y631315D01*
G01X363133Y632805D02*
X363495Y633035D01*
X363701Y633341D01*
X363753Y633686D01*
X363701Y633993D01*
X363443Y634300D01*
X363133Y634491D01*
X362823Y634530D01*
X362461Y634453D01*
X362203Y634185D01*
X362100Y633916D01*
Y633571D01*
G01Y633916D02*
X361945Y634146D01*
X361686Y634338D01*
X361376Y634415D01*
X361066Y634338D01*
X360808Y634146D01*
X360653Y633801D01*
X360705Y633456D01*
X360911Y633111D01*
G01X360653Y636748D02*
X360756Y636441D01*
X361015Y636211D01*
X361325Y636058D01*
X361738Y635943D01*
X362203Y635905D01*
X362668Y635943D01*
X363081Y636058D01*
X363391Y636211D01*
X363650Y636441D01*
X363753Y636748D01*
X363650Y637055D01*
X363391Y637285D01*
X363081Y637438D01*
X362668Y637553D01*
X362203Y637591D01*
X361738Y637553D01*
X361325Y637438D01*
X361015Y637285D01*
X360756Y637055D01*
X360653Y636748D01*
G01X359191Y614094D02*
Y638110D01*
G01X353080Y614094D02*
X359191D01*
G01Y638110D02*
X353080D01*
G01X377117Y658315D02*
G02I-13386J0D01*
G01D02*
X350345D01*
G01X351584Y703982D02*
Y697782D01*
G01X359051Y700278D02*
X365251D01*
G01Y697078D02*
X359051D01*
G01D02*
Y700278D01*
G01X355626Y703982D02*
Y697782D01*
G01D02*
X352426D01*
G01D02*
Y703982D01*
G01X359438Y691654D02*
Y694754D01*
X360358D01*
X360665Y694599D01*
X360895Y694237D01*
X360972Y693824D01*
X360895Y693411D01*
X360703Y693101D01*
X360358Y692946D01*
X359438D01*
G01X362462Y694754D02*
Y692532D01*
X362615Y692067D01*
X362922Y691757D01*
X363305Y691654D01*
X363688Y691757D01*
X363995Y692067D01*
X364148Y692532D01*
Y694754D01*
G01X365677Y694237D02*
X365907Y694547D01*
X366175Y694702D01*
X366482Y694754D01*
X366865Y694651D01*
X367133Y694392D01*
X367210Y694082D01*
X367172Y693772D01*
X367018Y693514D01*
X366252Y692997D01*
X365907Y692636D01*
X365677Y692119D01*
X365600Y691654D01*
X367210D01*
G01X368777Y692946D02*
X369045Y693307D01*
X369275Y693514D01*
X369582Y693617D01*
X369850Y693514D01*
X370042Y693307D01*
X370195Y692997D01*
X370233Y692636D01*
X370195Y692326D01*
X370042Y692016D01*
X369812Y691757D01*
X369543Y691654D01*
X369237Y691757D01*
X368968Y692067D01*
X368815Y692532D01*
X368777Y693049D01*
X368853Y693721D01*
X368968Y694082D01*
X369160Y694444D01*
X369428Y694702D01*
X369697Y694754D01*
X369965Y694651D01*
X370157Y694392D01*
G01X352426Y703982D02*
X355626D01*
G01X353850Y1167639D02*
Y1180631D01*
G01D02*
G03X351881Y1182600I-1969J0D01*
G01X361197Y1260534D02*
Y1303842D01*
G01X366538Y1260534D02*
X361197D01*
G01X358229Y1260477D02*
Y1303785D01*
G01X352888Y1260477D02*
X358229D01*
G01X364358Y1308785D02*
Y1305585D01*
G01X358158Y1308785D02*
X364358D01*
G01X358158Y1305585D02*
Y1308785D01*
G01X364358Y1305585D02*
X358158D01*
G01X362924Y1309085D02*
X359724D01*
G01X362924Y1315285D02*
Y1309085D01*
G01X359724D02*
Y1315285D01*
G01X352844Y1307002D02*
X352051D01*
G01X352844Y1309602D02*
Y1307002D01*
G01X361197Y1303842D02*
X366538D01*
G01X358229Y1303785D02*
X352888D01*
G01X355710Y1322504D02*
X358910D01*
G01X355710Y1316304D02*
Y1322504D01*
G01X358910Y1316304D02*
X355710D01*
G01X358910Y1322504D02*
Y1316304D01*
G01X362901Y1326406D02*
X359701D01*
G01D02*
Y1332606D01*
G01X362901Y1328600D02*
Y1326406D01*
G01X359701Y1322106D02*
X362901D01*
G01X359701Y1315906D02*
Y1322106D01*
G01X362901Y1315906D02*
X359701D01*
G01X362901Y1322106D02*
Y1315906D01*
G01X359724Y1315285D02*
X362924D01*
G01X362901Y1332606D02*
Y1331000D01*
G01X359701Y1332606D02*
X362901D01*
G01X366795Y1335037D02*
X363595D01*
G01Y1341237D02*
X366795D01*
G01X363595Y1335037D02*
Y1341237D01*
G01X356417Y1334674D02*
Y1337874D01*
G01X362617Y1334674D02*
X356417D01*
G01X362617Y1337874D02*
Y1334674D01*
G01X356417Y1337874D02*
X362617D01*
G01X351632Y1340227D02*
Y1334027D01*
G01X352844Y1330624D02*
Y1328433D01*
G01X352111Y1330624D02*
X352844D01*
G01X361951Y1367903D02*
X368062D01*
G01Y1391919D02*
X361951D01*
G01X354768Y1642149D02*
X354960Y1641839D01*
X355190Y1641632D01*
X355458Y1641529D01*
X355765Y1641632D01*
X355995Y1641839D01*
X356225Y1642149D01*
X356302Y1642562D01*
Y1644629D01*
G01X358635Y1641529D02*
Y1644629D01*
X358175Y1644009D01*
G01Y1641529D02*
X359095D01*
G01X361735D02*
Y1644629D01*
X361275Y1644009D01*
G01Y1641529D02*
X362195D01*
G01X364835D02*
Y1644629D01*
X364375Y1644009D01*
G01Y1641529D02*
X365295D01*
G01X354786Y1656012D02*
X354734Y1656280D01*
X354579Y1656587D01*
X354321Y1656779D01*
X353959Y1656855D01*
X353598Y1656779D01*
X353288Y1656549D01*
X353133Y1656204D01*
Y1655820D01*
X353029Y1655590D01*
X352771Y1655399D01*
X352409Y1655322D01*
X352048Y1655437D01*
X351789Y1655705D01*
X351686Y1656012D01*
X351789Y1656319D01*
X352048Y1656587D01*
X352409Y1656702D01*
X352771Y1656625D01*
X353029Y1656434D01*
X353133Y1656204D01*
Y1655820D01*
X353288Y1655475D01*
X353598Y1655245D01*
X353959Y1655169D01*
X354321Y1655245D01*
X354579Y1655437D01*
X354734Y1655744D01*
X354786Y1656012D01*
G01X364287Y1670913D02*
X361187D01*
X364287Y1672677D01*
X361187D01*
G01X359449Y1657834D02*
Y1736118D01*
G01X364287Y1675522D02*
X361187D01*
X363770Y1676519D01*
X361187Y1677516D01*
X364287D01*
G01X361187Y1680476D02*
X364287D01*
Y1682010D01*
G01Y1685125D02*
X361187D01*
G01Y1686581D02*
X363099Y1685125D01*
G01X364287Y1686811D02*
X362220Y1685776D01*
G01X361187Y1694957D02*
Y1695877D01*
G01Y1695417D02*
X364287D01*
G01Y1694957D02*
Y1695877D01*
G01Y1699336D02*
X361187D01*
G01Y1700946D02*
X364287D01*
G01X362737D02*
Y1699336D01*
G01X363667Y1689925D02*
X363977Y1690117D01*
X364184Y1690347D01*
X364287Y1690615D01*
X364184Y1690922D01*
X363977Y1691152D01*
X363667Y1691382D01*
X363254Y1691459D01*
X361187D01*
G01X362737Y1705096D02*
Y1705863D01*
X363667D01*
X363977Y1705633D01*
X364184Y1705364D01*
X364287Y1704981D01*
X364184Y1704598D01*
X363977Y1704329D01*
X363667Y1704099D01*
X363305Y1703946D01*
X362892Y1703869D01*
X362530D01*
X362220Y1703946D01*
X361859Y1704099D01*
X361549Y1704329D01*
X361342Y1704559D01*
X361187Y1704866D01*
Y1705134D01*
X361290Y1705441D01*
X361497Y1705671D01*
G01X364287Y1708862D02*
X361187D01*
Y1710318D01*
G01X362685Y1709782D02*
Y1708862D01*
G01X364287Y1715081D02*
Y1713547D01*
X361187D01*
Y1715081D01*
G01X362685Y1714467D02*
Y1713547D01*
G01X361445Y1724606D02*
X361290Y1724376D01*
X361187Y1724108D01*
Y1723801D01*
X361342Y1723456D01*
X361600Y1723188D01*
X361910Y1722996D01*
X362427Y1722843D01*
X362892Y1722805D01*
X363357Y1722881D01*
X363667Y1722996D01*
X363977Y1723226D01*
X364184Y1723495D01*
X364287Y1723763D01*
Y1724031D01*
X364184Y1724300D01*
X364029Y1724530D01*
X363822Y1724721D01*
G01X362634Y1728795D02*
X362479Y1728948D01*
X362220Y1729063D01*
X361859Y1729140D01*
X361549Y1729063D01*
X361342Y1728910D01*
X361187Y1728641D01*
Y1727606D01*
X364287D01*
Y1728871D01*
X364080Y1729140D01*
X363770Y1729293D01*
X363409Y1729370D01*
X363047Y1729293D01*
X362737Y1729063D01*
X362634Y1728795D01*
Y1727606D01*
G01X364287Y1718196D02*
X361187D01*
Y1718962D01*
X361342Y1719269D01*
X361549Y1719499D01*
X361859Y1719691D01*
X362220Y1719844D01*
X362737Y1719882D01*
X363254Y1719844D01*
X363615Y1719691D01*
X363925Y1719499D01*
X364132Y1719269D01*
X364287Y1718962D01*
Y1718196D01*
G01X368296Y131765D02*
Y128565D01*
G01X371270Y130974D02*
Y128752D01*
X371423Y128287D01*
X371730Y127977D01*
X372113Y127874D01*
X372496Y127977D01*
X372803Y128287D01*
X372956Y128752D01*
Y130974D01*
G01X374485Y130457D02*
X374715Y130767D01*
X374983Y130922D01*
X375290Y130974D01*
X375673Y130871D01*
X375941Y130612D01*
X376018Y130302D01*
X375980Y129992D01*
X375826Y129734D01*
X375060Y129217D01*
X374715Y128856D01*
X374485Y128339D01*
X374408Y127874D01*
X376018D01*
G01X378313D02*
Y130974D01*
X377853Y130354D01*
G01Y127874D02*
X378773D01*
G01X380761Y128236D02*
X381030Y127977D01*
X381336Y127874D01*
X381643Y127977D01*
X381911Y128287D01*
X382103Y128752D01*
X382180Y129217D01*
Y129786D01*
X382103Y130251D01*
X381911Y130664D01*
X381681Y130871D01*
X381413Y130974D01*
X381106Y130871D01*
X380876Y130664D01*
X380723Y130354D01*
X380646Y129941D01*
X380723Y129579D01*
X380915Y129217D01*
X381145Y129011D01*
X381413Y128959D01*
X381720Y129062D01*
X381950Y129321D01*
X382180Y129786D01*
G01X368899Y132795D02*
X382547D01*
G01X368899Y144999D02*
Y132795D01*
G01X374395Y147477D02*
Y150677D01*
G01X380595Y147477D02*
X374395D01*
G01X382547Y144999D02*
X378325D01*
G01D02*
X375723Y142397D01*
G01X373121Y144999D02*
X368899D01*
G01X375723Y142397D02*
X373121Y144999D01*
G01X374395Y150677D02*
X380595D01*
G01X375563Y164773D02*
Y161573D01*
G01X369363Y164773D02*
X375563D01*
G01X369363Y161573D02*
Y164773D01*
G01X375563Y161573D02*
X369363D01*
G01Y156428D02*
Y159628D01*
G01X375563Y156428D02*
X369363D01*
G01X375563Y159628D02*
Y156428D01*
G01X369363Y159628D02*
X375563D01*
G01X370415Y212961D02*
Y209761D01*
G01Y220961D02*
Y217761D01*
G01X378145Y226745D02*
Y223545D01*
G01D02*
X371945D01*
G01D02*
Y226745D01*
G01X370415Y216961D02*
Y213761D01*
G01X378625Y233855D02*
X372425D01*
G01D02*
Y237055D01*
G01D02*
X378625D01*
G01D02*
Y233855D01*
G01X378655Y238015D02*
X372455D01*
G01D02*
Y241215D01*
G01X378655D02*
Y238015D01*
G01X371945Y226745D02*
X378145D01*
G01X371945Y230245D02*
X378145D01*
G01D02*
Y227045D01*
G01D02*
X371945D01*
G01D02*
Y230245D01*
G01X368464Y238036D02*
Y244236D01*
G01X371664D02*
Y238036D01*
G01D02*
X368464D01*
G01X367033Y225561D02*
Y233749D01*
G01X372455Y241215D02*
X378655D01*
G01X368464Y244236D02*
X371664D01*
G01X372455Y245215D02*
X378655D01*
G01D02*
Y242015D01*
G01D02*
X372455D01*
G01D02*
Y245215D01*
G01X379695Y247760D02*
Y277319D01*
G01X391191Y247760D02*
X379695D01*
G01X379488Y281970D02*
X385688D01*
G01Y278770D02*
X379488D01*
G01D02*
Y281970D01*
G01X369812Y270477D02*
Y276677D01*
G01D02*
X373012D01*
G01D02*
Y270477D01*
G01D02*
X369812D01*
G01X368908Y277970D02*
Y271970D01*
G01X372475Y290751D02*
Y280989D01*
G01X379695Y277319D02*
X391191D01*
G01X379488Y295970D02*
X385688D01*
G01Y292770D02*
X379488D01*
G01D02*
Y295970D01*
G01X367508Y295630D02*
Y292430D01*
G01X385688Y285770D02*
X379488D01*
G01D02*
Y288970D01*
G01D02*
X385688D01*
G01X369807Y318567D02*
Y316345D01*
X369960Y315880D01*
X370267Y315570D01*
X370650Y315467D01*
X371033Y315570D01*
X371340Y315880D01*
X371493Y316345D01*
Y318567D01*
G01X372907Y316087D02*
X373137Y315725D01*
X373443Y315519D01*
X373788Y315467D01*
X374095Y315519D01*
X374402Y315777D01*
X374593Y316087D01*
X374632Y316397D01*
X374555Y316759D01*
X374287Y317017D01*
X374018Y317120D01*
X373673D01*
G01X374018D02*
X374248Y317275D01*
X374440Y317534D01*
X374517Y317844D01*
X374440Y318154D01*
X374248Y318412D01*
X373903Y318567D01*
X373558Y318515D01*
X373213Y318309D01*
G01X376007Y316087D02*
X376237Y315725D01*
X376543Y315519D01*
X376888Y315467D01*
X377195Y315519D01*
X377502Y315777D01*
X377693Y316087D01*
X377732Y316397D01*
X377655Y316759D01*
X377387Y317017D01*
X377118Y317120D01*
X376773D01*
G01X377118D02*
X377348Y317275D01*
X377540Y317534D01*
X377617Y317844D01*
X377540Y318154D01*
X377348Y318412D01*
X377003Y318567D01*
X376658Y318515D01*
X376313Y318309D01*
G01X379000Y314000D02*
X385600D01*
G01X377500Y311500D02*
X379000Y314000D01*
G01X376000D02*
X377500Y311500D01*
G01X369400Y314000D02*
X376000D01*
G01X369400Y301000D02*
Y314000D01*
G01X385600Y301000D02*
X369400D01*
G01X379784Y473451D02*
Y467251D01*
G01D02*
X376584D01*
G01D02*
Y473451D01*
G01D02*
X379784D01*
G01X377557Y483849D02*
X379779D01*
X380244Y484002D01*
X380554Y484309D01*
X380657Y484692D01*
X380554Y485075D01*
X380244Y485382D01*
X379779Y485535D01*
X377557D01*
G01X380037Y486949D02*
X380399Y487179D01*
X380605Y487485D01*
X380657Y487830D01*
X380605Y488137D01*
X380347Y488444D01*
X380037Y488635D01*
X379727Y488674D01*
X379365Y488597D01*
X379107Y488329D01*
X379004Y488060D01*
Y487715D01*
G01Y488060D02*
X378849Y488290D01*
X378590Y488482D01*
X378280Y488559D01*
X377970Y488482D01*
X377712Y488290D01*
X377557Y487945D01*
X377609Y487600D01*
X377815Y487255D01*
G01X380657Y490892D02*
X380605Y491160D01*
X380450Y491467D01*
X380192Y491659D01*
X379830Y491735D01*
X379469Y491659D01*
X379159Y491429D01*
X379004Y491084D01*
Y490700D01*
X378900Y490470D01*
X378642Y490279D01*
X378280Y490202D01*
X377919Y490317D01*
X377660Y490585D01*
X377557Y490892D01*
X377660Y491199D01*
X377919Y491467D01*
X378280Y491582D01*
X378642Y491505D01*
X378900Y491314D01*
X379004Y491084D01*
Y490700D01*
X379159Y490355D01*
X379469Y490125D01*
X379830Y490049D01*
X380192Y490125D01*
X380450Y490317D01*
X380605Y490624D01*
X380657Y490892D01*
G01X377543Y538796D02*
Y532596D01*
G01D02*
X374343D01*
G01D02*
Y538796D01*
G01X370362Y532567D02*
Y538767D01*
G01X373562D02*
Y532567D01*
G01D02*
X370362D01*
G01X382371Y532538D02*
X379171D01*
G01D02*
Y538738D01*
G01X374343Y538796D02*
X377543D01*
G01X370362Y538767D02*
X373562D01*
G01X379171Y538738D02*
X382371D01*
G01X369232Y619038D02*
Y615838D01*
G01X367952Y641073D02*
Y644173D01*
X368872D01*
X369179Y644018D01*
X369409Y643656D01*
X369486Y643243D01*
X369409Y642830D01*
X369217Y642520D01*
X368872Y642365D01*
X367952D01*
G01X372662Y643915D02*
X372432Y644070D01*
X372164Y644173D01*
X371857D01*
X371512Y644018D01*
X371244Y643760D01*
X371052Y643450D01*
X370899Y642933D01*
X370861Y642468D01*
X370937Y642003D01*
X371052Y641693D01*
X371282Y641383D01*
X371551Y641176D01*
X371819Y641073D01*
X372087D01*
X372356Y641176D01*
X372586Y641331D01*
X372777Y641538D01*
G01X374191Y643656D02*
X374421Y643966D01*
X374689Y644121D01*
X374996Y644173D01*
X375379Y644070D01*
X375647Y643811D01*
X375724Y643501D01*
X375686Y643191D01*
X375532Y642933D01*
X374766Y642416D01*
X374421Y642055D01*
X374191Y641538D01*
X374114Y641073D01*
X375724D01*
G01X377942D02*
X378019Y641745D01*
X378134Y642313D01*
X378287Y642830D01*
X378479Y643398D01*
X378786Y644173D01*
X377252D01*
G01X380276Y641693D02*
X380506Y641331D01*
X380812Y641125D01*
X381157Y641073D01*
X381464Y641125D01*
X381771Y641383D01*
X381962Y641693D01*
X382001Y642003D01*
X381924Y642365D01*
X381656Y642623D01*
X381387Y642726D01*
X381042D01*
G01X381387D02*
X381617Y642881D01*
X381809Y643140D01*
X381886Y643450D01*
X381809Y643760D01*
X381617Y644018D01*
X381272Y644173D01*
X380927Y644121D01*
X380582Y643915D01*
G01X369221Y703172D02*
Y696972D01*
G01D02*
X366021D01*
G01D02*
Y703172D01*
G01X376399Y700335D02*
X370199D01*
G01D02*
Y703535D01*
G01X376399D02*
Y700335D01*
G01X365251Y700278D02*
Y697078D01*
G01X366021Y703172D02*
X369221D01*
G01X370199Y703535D02*
X376399D01*
G01X374104Y715863D02*
Y722063D01*
G01X377304D02*
Y715863D01*
G01D02*
X374104D01*
G01X373115Y711803D02*
Y705603D01*
G01D02*
X369915D01*
G01D02*
Y707500D01*
G01Y711803D02*
X373115D01*
G01X369915Y709800D02*
Y711803D01*
G01Y716103D02*
Y722303D01*
G01X373115D02*
Y716103D01*
G01D02*
X369915D01*
G01X366858Y709239D02*
Y707385D01*
G01D02*
X365850D01*
G01X374104Y722063D02*
X377304D01*
G01X369915Y722303D02*
X373115D01*
G01X368458Y729424D02*
Y732624D01*
G01X374658Y729424D02*
X368458D01*
G01X374658Y732624D02*
Y729424D01*
G01X369892Y729124D02*
X373092D01*
G01X369892Y722924D02*
Y729124D01*
G01X373092Y722924D02*
X369892D01*
G01X373092Y729124D02*
Y722924D01*
G01X366065Y731007D02*
X366858D01*
G01D02*
Y728407D01*
G01Y721796D02*
Y720098D01*
G01X368458Y732624D02*
X374658D01*
G01X374827Y734292D02*
X380168D01*
G01X374827Y777600D02*
Y734292D01*
G01X371315Y734404D02*
X365974D01*
G01X371315Y777712D02*
Y734404D01*
G01X380168Y777600D02*
X374827D01*
G01X365974Y777712D02*
X371315D01*
G01X365958Y1307202D02*
Y1309802D01*
G01X366751Y1307202D02*
X365958D01*
G01Y1316413D02*
Y1318111D01*
G01X366795Y1341237D02*
Y1335037D01*
G01X367565Y1337931D02*
Y1341131D01*
G01X373765Y1337931D02*
X367565D01*
G01X373765Y1341131D02*
Y1337931D01*
G01X367565Y1341131D02*
X373765D01*
G01X380390Y1334227D02*
X377190D01*
G01Y1340427D02*
X380390D01*
G01X377190Y1334227D02*
Y1340427D01*
G01X365958Y1330824D02*
X366966D01*
G01X365958Y1328970D02*
Y1330824D01*
G01X365883Y1351000D02*
Y1354100D01*
X366803D01*
X367110Y1353945D01*
X367340Y1353583D01*
X367417Y1353170D01*
X367340Y1352757D01*
X367148Y1352447D01*
X366803Y1352292D01*
X365883D01*
G01X368907Y1354100D02*
Y1351878D01*
X369060Y1351413D01*
X369367Y1351103D01*
X369750Y1351000D01*
X370133Y1351103D01*
X370440Y1351413D01*
X370593Y1351878D01*
Y1354100D01*
G01X372007Y1351620D02*
X372237Y1351258D01*
X372543Y1351052D01*
X372888Y1351000D01*
X373195Y1351052D01*
X373502Y1351310D01*
X373693Y1351620D01*
X373732Y1351930D01*
X373655Y1352292D01*
X373387Y1352550D01*
X373118Y1352653D01*
X372773D01*
G01X373118D02*
X373348Y1352808D01*
X373540Y1353067D01*
X373617Y1353377D01*
X373540Y1353687D01*
X373348Y1353945D01*
X373003Y1354100D01*
X372658Y1354048D01*
X372313Y1353842D01*
G01X375950Y1351000D02*
X376218Y1351052D01*
X376525Y1351207D01*
X376717Y1351465D01*
X376793Y1351827D01*
X376717Y1352188D01*
X376487Y1352498D01*
X376142Y1352653D01*
X375758D01*
X375528Y1352757D01*
X375337Y1353015D01*
X375260Y1353377D01*
X375375Y1353738D01*
X375643Y1353997D01*
X375950Y1354100D01*
X376257Y1353997D01*
X376525Y1353738D01*
X376640Y1353377D01*
X376563Y1353015D01*
X376372Y1352757D01*
X376142Y1352653D01*
X375758D01*
X375413Y1352498D01*
X375183Y1352188D01*
X375107Y1351827D01*
X375183Y1351465D01*
X375375Y1351207D01*
X375682Y1351052D01*
X375950Y1351000D01*
G01X365883Y1346500D02*
Y1349600D01*
X366803D01*
X367110Y1349445D01*
X367340Y1349083D01*
X367417Y1348670D01*
X367340Y1348257D01*
X367148Y1347947D01*
X366803Y1347792D01*
X365883D01*
G01X368983Y1349600D02*
Y1346500D01*
X370517D01*
G01X373310D02*
Y1349600D01*
X371892Y1347378D01*
X373808D01*
G01X375107Y1346965D02*
X375337Y1346707D01*
X375605Y1346552D01*
X375950Y1346500D01*
X376295Y1346603D01*
X376563Y1346810D01*
X376755Y1347172D01*
X376793Y1347585D01*
X376717Y1347998D01*
X376525Y1348257D01*
X376257Y1348463D01*
X375988Y1348515D01*
X375720Y1348463D01*
X375375Y1348257D01*
X375490Y1349600D01*
X376525D01*
G01X370383Y1368000D02*
Y1371100D01*
X371303D01*
X371610Y1370945D01*
X371840Y1370583D01*
X371917Y1370170D01*
X371840Y1369757D01*
X371648Y1369447D01*
X371303Y1369292D01*
X370383D01*
G01X373483Y1371100D02*
Y1368000D01*
X375017D01*
G01X377810D02*
Y1371100D01*
X376392Y1368878D01*
X378308D01*
G01X379722Y1370583D02*
X379952Y1370893D01*
X380220Y1371048D01*
X380527Y1371100D01*
X380910Y1370997D01*
X381178Y1370738D01*
X381255Y1370428D01*
X381217Y1370118D01*
X381063Y1369860D01*
X380297Y1369343D01*
X379952Y1368982D01*
X379722Y1368465D01*
X379645Y1368000D01*
X381255D01*
G01X368062Y1367903D02*
Y1391919D01*
G01X369662Y1386097D02*
Y1389297D01*
G01X375862Y1386097D02*
X369662D01*
G01X375862Y1389297D02*
Y1386097D01*
G01X369662Y1389297D02*
X375862D01*
G01X369960Y1393820D02*
X490000D01*
G01X378727Y1579162D02*
Y1589276D01*
G01X386867Y1579162D02*
X378727D01*
G01X377609Y1598401D02*
Y1596179D01*
X377762Y1595714D01*
X378069Y1595404D01*
X378452Y1595301D01*
X378835Y1595404D01*
X379142Y1595714D01*
X379295Y1596179D01*
Y1598401D01*
G01X382012Y1595301D02*
Y1598401D01*
X380594Y1596179D01*
X382510D01*
G01X383809Y1595766D02*
X384039Y1595508D01*
X384307Y1595353D01*
X384652Y1595301D01*
X384997Y1595404D01*
X385265Y1595611D01*
X385457Y1595973D01*
X385495Y1596386D01*
X385419Y1596799D01*
X385227Y1597058D01*
X384959Y1597264D01*
X384690Y1597316D01*
X384422Y1597264D01*
X384077Y1597058D01*
X384192Y1598401D01*
X385227D01*
G01X378727Y1589276D02*
X386867D01*
G01X371260Y1736118D02*
Y1646023D01*
G01X376249Y1651638D02*
X378471D01*
X378936Y1651791D01*
X379246Y1652098D01*
X379349Y1652481D01*
X379246Y1652864D01*
X378936Y1653171D01*
X378471Y1653324D01*
X376249D01*
G01X376766Y1654853D02*
X376456Y1655083D01*
X376301Y1655351D01*
X376249Y1655658D01*
X376352Y1656041D01*
X376611Y1656309D01*
X376921Y1656386D01*
X377231Y1656348D01*
X377489Y1656194D01*
X378006Y1655428D01*
X378367Y1655083D01*
X378884Y1654853D01*
X379349Y1654776D01*
Y1656386D01*
G01Y1658604D02*
X378677Y1658681D01*
X378109Y1658796D01*
X377592Y1658949D01*
X377024Y1659141D01*
X376249Y1659448D01*
Y1657914D01*
G01X376766Y1661053D02*
X376456Y1661283D01*
X376301Y1661551D01*
X376249Y1661858D01*
X376352Y1662241D01*
X376611Y1662509D01*
X376921Y1662586D01*
X377231Y1662548D01*
X377489Y1662394D01*
X378006Y1661628D01*
X378367Y1661283D01*
X378884Y1661053D01*
X379349Y1660976D01*
Y1662586D01*
G01X373893Y1731438D02*
Y1734538D01*
G01X375503D02*
Y1731438D01*
G01Y1732988D02*
X373893D01*
G01X377146Y1731800D02*
X377415Y1731541D01*
X377721Y1731438D01*
X378028Y1731541D01*
X378296Y1731851D01*
X378488Y1732316D01*
X378565Y1732781D01*
Y1733350D01*
X378488Y1733815D01*
X378296Y1734228D01*
X378066Y1734435D01*
X377798Y1734538D01*
X377491Y1734435D01*
X377261Y1734228D01*
X377108Y1733918D01*
X377031Y1733505D01*
X377108Y1733143D01*
X377300Y1732781D01*
X377530Y1732575D01*
X377798Y1732523D01*
X378105Y1732626D01*
X378335Y1732885D01*
X378565Y1733350D01*
G01X381358Y1731438D02*
Y1734538D01*
X379940Y1732316D01*
X381856D01*
G01X389823Y-15731D02*
Y-32011D01*
X380223D01*
Y-15731D01*
X389823D01*
G01X388303Y128437D02*
Y122237D01*
G01D02*
X385103D01*
G01D02*
Y128437D01*
G01D02*
X388303D01*
G01X394306Y133380D02*
Y136580D01*
G01X400506Y133380D02*
X394306D01*
G01X392459Y128484D02*
Y122284D01*
G01D02*
X389259D01*
G01D02*
Y128484D01*
G01D02*
X392459D01*
G01X393448Y122078D02*
Y128278D01*
G01D02*
X396648D01*
G01Y122078D02*
X393448D01*
G01X382547Y132795D02*
Y144999D01*
G01X380595Y150677D02*
Y147477D01*
G01X384893Y141337D02*
Y144537D01*
G01X391093Y141337D02*
X384893D01*
G01X391093Y144537D02*
Y141337D01*
G01X384893Y144537D02*
X391093D01*
G01X394306Y136580D02*
X400506D01*
G01X391196Y137380D02*
Y140580D01*
G01X397396Y137380D02*
X391196D01*
G01Y140580D02*
X397396D01*
G01X383360Y164344D02*
Y162122D01*
X383513Y161657D01*
X383820Y161347D01*
X384203Y161244D01*
X384586Y161347D01*
X384893Y161657D01*
X385046Y162122D01*
Y164344D01*
G01X386575Y163827D02*
X386805Y164137D01*
X387073Y164292D01*
X387380Y164344D01*
X387763Y164241D01*
X388031Y163982D01*
X388108Y163672D01*
X388070Y163362D01*
X387916Y163104D01*
X387150Y162587D01*
X386805Y162226D01*
X386575Y161709D01*
X386498Y161244D01*
X388108D01*
G01X390403D02*
Y164344D01*
X389943Y163724D01*
G01Y161244D02*
X390863D01*
G01X393426D02*
X393503Y161916D01*
X393618Y162484D01*
X393771Y163001D01*
X393963Y163569D01*
X394270Y164344D01*
X392736D01*
G01X393407Y159708D02*
Y151046D01*
G01X382383Y159708D02*
X393407D01*
G01X382383Y151046D02*
Y159708D01*
G01Y151046D02*
X393407D01*
G01X395153Y207195D02*
X389153D01*
G01D02*
Y219195D01*
G01D02*
X395153D01*
G01X396848Y248073D02*
X393748D01*
Y248993D01*
X393903Y249300D01*
X394265Y249530D01*
X394678Y249607D01*
X395091Y249530D01*
X395401Y249338D01*
X395556Y248993D01*
Y248073D01*
G01X396848Y251097D02*
X393748D01*
Y251863D01*
X393903Y252170D01*
X394110Y252400D01*
X394420Y252592D01*
X394781Y252745D01*
X395298Y252783D01*
X395815Y252745D01*
X396176Y252592D01*
X396486Y252400D01*
X396693Y252170D01*
X396848Y251863D01*
Y251097D01*
G01Y255040D02*
X393748D01*
X394368Y254580D01*
G01X396848D02*
Y255500D01*
G01X393748Y258140D02*
X393851Y257833D01*
X394110Y257603D01*
X394420Y257450D01*
X394833Y257335D01*
X395298Y257297D01*
X395763Y257335D01*
X396176Y257450D01*
X396486Y257603D01*
X396745Y257833D01*
X396848Y258140D01*
X396745Y258447D01*
X396486Y258677D01*
X396176Y258830D01*
X395763Y258945D01*
X395298Y258983D01*
X394833Y258945D01*
X394420Y258830D01*
X394110Y258677D01*
X393851Y258447D01*
X393748Y258140D01*
G01X396486Y260588D02*
X396745Y260857D01*
X396848Y261163D01*
X396745Y261470D01*
X396435Y261738D01*
X395970Y261930D01*
X395505Y262007D01*
X394936D01*
X394471Y261930D01*
X394058Y261738D01*
X393851Y261508D01*
X393748Y261240D01*
X393851Y260933D01*
X394058Y260703D01*
X394368Y260550D01*
X394781Y260473D01*
X395143Y260550D01*
X395505Y260742D01*
X395711Y260972D01*
X395763Y261240D01*
X395660Y261547D01*
X395401Y261777D01*
X394936Y262007D01*
G01X385143Y244220D02*
Y246646D01*
G01X391191Y277319D02*
Y247760D01*
G01X385688Y281970D02*
Y278770D01*
G01X389952Y283141D02*
Y280901D01*
G01X391577Y282114D02*
X388327D01*
G01X385688Y295970D02*
Y292770D01*
G01Y288970D02*
Y285770D01*
G01X389900Y309900D02*
Y313100D01*
G01X396100Y309900D02*
X389900D01*
G01Y313100D02*
X396100D01*
G01X392400Y302400D02*
Y305600D01*
G01X398600Y302400D02*
X392400D01*
G01Y305600D02*
X398600D01*
G01X385600Y314000D02*
Y301000D01*
G01X380584Y467251D02*
Y473451D01*
G01D02*
X383784D01*
G01D02*
Y467251D01*
G01D02*
X380584D01*
G01X388784Y477595D02*
Y471395D01*
G01D02*
X385584D01*
G01D02*
Y477595D01*
G01D02*
X388784D01*
G01X394976Y467597D02*
X391776D01*
G01Y473797D02*
X394976D01*
G01X391776Y467597D02*
Y473797D01*
G01X396168Y484436D02*
X396116Y484129D01*
X395910Y483861D01*
X395600Y483631D01*
X395238Y483478D01*
X394825Y483401D01*
X394411D01*
X393998Y483478D01*
X393636Y483631D01*
X393326Y483861D01*
X393120Y484129D01*
X393068Y484436D01*
X393120Y484743D01*
X393326Y485011D01*
X393636Y485241D01*
X393998Y485394D01*
X394411Y485471D01*
X394825D01*
X395238Y485394D01*
X395600Y485241D01*
X395910Y485011D01*
X396116Y484743D01*
X396168Y484436D01*
G01X395341Y484743D02*
X396168Y485203D01*
G01Y487536D02*
X393068D01*
X393688Y487076D01*
G01X396168D02*
Y487996D01*
G01Y490636D02*
X396116Y490904D01*
X395961Y491211D01*
X395703Y491403D01*
X395341Y491479D01*
X394980Y491403D01*
X394670Y491173D01*
X394515Y490828D01*
Y490444D01*
X394411Y490214D01*
X394153Y490023D01*
X393791Y489946D01*
X393430Y490061D01*
X393171Y490329D01*
X393068Y490636D01*
X393171Y490943D01*
X393430Y491211D01*
X393791Y491326D01*
X394153Y491249D01*
X394411Y491058D01*
X394515Y490828D01*
Y490444D01*
X394670Y490099D01*
X394980Y489869D01*
X395341Y489793D01*
X395703Y489869D01*
X395961Y490061D01*
X396116Y490368D01*
X396168Y490636D01*
G01X391416Y493382D02*
X382952D01*
G01D02*
Y480070D01*
G01D02*
X391416D01*
G01D02*
Y484994D01*
G01D02*
X388684Y486726D01*
G01D02*
X391416Y488458D01*
G01D02*
Y493382D01*
G01X383784Y506201D02*
Y500001D01*
G01D02*
X380584D01*
G01D02*
Y506201D01*
G01D02*
X383784D01*
G01X393784D02*
Y500001D01*
G01D02*
X390584D01*
G01D02*
Y506201D01*
G01D02*
X393784D01*
G01X382371Y538738D02*
Y532538D01*
G01X390894Y524905D02*
Y528005D01*
X391814D01*
X392121Y527850D01*
X392351Y527488D01*
X392428Y527075D01*
X392351Y526662D01*
X392159Y526352D01*
X391814Y526197D01*
X390894D01*
G01X394761Y524905D02*
X394454Y524957D01*
X394186Y525163D01*
X393956Y525473D01*
X393803Y525835D01*
X393726Y526248D01*
Y526662D01*
X393803Y527075D01*
X393956Y527437D01*
X394186Y527747D01*
X394454Y527953D01*
X394761Y528005D01*
X395068Y527953D01*
X395336Y527747D01*
X395566Y527437D01*
X395719Y527075D01*
X395796Y526662D01*
Y526248D01*
X395719Y525835D01*
X395566Y525473D01*
X395336Y525163D01*
X395068Y524957D01*
X394761Y524905D01*
G01X395068Y525732D02*
X395528Y524905D01*
G01X397861D02*
Y528005D01*
X397401Y527385D01*
G01Y524905D02*
X398321D01*
G01X400118Y525370D02*
X400348Y525112D01*
X400616Y524957D01*
X400961Y524905D01*
X401306Y525008D01*
X401574Y525215D01*
X401766Y525577D01*
X401804Y525990D01*
X401728Y526403D01*
X401536Y526662D01*
X401268Y526868D01*
X400999Y526920D01*
X400731Y526868D01*
X400386Y526662D01*
X400501Y528005D01*
X401536D01*
G01X399448Y529799D02*
X384094D01*
G01D02*
Y542477D01*
G01D02*
X399448D01*
G01X392257Y564315D02*
X386057D01*
G01D02*
Y567515D01*
G01D02*
X392257D01*
G01D02*
Y564315D01*
G01X392057Y569515D02*
X385857D01*
G01D02*
Y572715D01*
G01D02*
X392057D01*
G01D02*
Y569515D01*
G01X381424Y697850D02*
Y704050D01*
G01X384624D02*
Y697850D01*
G01D02*
X381424D01*
G01X392091Y700346D02*
X398291D01*
G01Y697146D02*
X392091D01*
G01D02*
Y700346D01*
G01X388666Y704050D02*
Y697850D01*
G01D02*
X385466D01*
G01D02*
Y704050D01*
G01X387328Y691916D02*
Y695016D01*
X388248D01*
X388555Y694861D01*
X388785Y694499D01*
X388862Y694086D01*
X388785Y693673D01*
X388593Y693363D01*
X388248Y693208D01*
X387328D01*
G01X390352Y695016D02*
Y692794D01*
X390505Y692329D01*
X390812Y692019D01*
X391195Y691916D01*
X391578Y692019D01*
X391885Y692329D01*
X392038Y692794D01*
Y695016D01*
G01X393567Y694499D02*
X393797Y694809D01*
X394065Y694964D01*
X394372Y695016D01*
X394755Y694913D01*
X395023Y694654D01*
X395100Y694344D01*
X395062Y694034D01*
X394908Y693776D01*
X394142Y693259D01*
X393797Y692898D01*
X393567Y692381D01*
X393490Y691916D01*
X395100D01*
G01X397318D02*
X397395Y692588D01*
X397510Y693156D01*
X397663Y693673D01*
X397855Y694241D01*
X398162Y695016D01*
X396628D01*
G01X381424Y704050D02*
X384624D01*
G01X385466D02*
X388666D01*
G01X380945Y707453D02*
X380212D01*
G01D02*
Y709644D01*
G01Y728475D02*
Y731075D01*
G01D02*
X381005D01*
G01X388600Y1167639D02*
X415200D01*
G01X390725Y1260534D02*
Y1303842D01*
G01X385384Y1260534D02*
X390725D01*
G01X394083Y1280008D02*
Y1323316D01*
G01X399424Y1280008D02*
X394083D01*
G01X385644Y1307202D02*
X384851D01*
G01X385644Y1309802D02*
Y1307202D01*
G01X390725Y1303842D02*
X385384D01*
G01X388510Y1322704D02*
X391710D01*
G01X388510Y1316504D02*
Y1322704D01*
G01X391710Y1316504D02*
X388510D01*
G01X391710Y1322704D02*
Y1316504D01*
G01X390740Y1328116D02*
X396940D01*
G01X390740Y1324916D02*
Y1328116D01*
G01X396940Y1324916D02*
X390740D01*
G01X394083Y1323316D02*
X399424D01*
G01X381232Y1340427D02*
X384432D01*
G01X381232Y1334227D02*
Y1340427D01*
G01X384432Y1334227D02*
X381232D01*
G01X384432Y1340427D02*
Y1334227D01*
G01X392283Y1341437D02*
X395483D01*
G01X392283Y1335237D02*
Y1341437D01*
G01X395483Y1335237D02*
X392283D01*
G01X395506Y1328416D02*
X392306D01*
G01Y1334616D02*
X395506D01*
G01X392306Y1328416D02*
Y1334616D01*
G01X380390Y1340427D02*
Y1334227D01*
G01X385644Y1330824D02*
Y1328633D01*
G01X384911Y1330824D02*
X385644D01*
G01X395483Y1345737D02*
X392283D01*
G01Y1351937D02*
X395483D01*
G01X392283Y1345737D02*
Y1351937D01*
G01X395259Y1507451D02*
X388300D01*
G01X388100Y1542491D02*
X395259D01*
G01X386867Y1589276D02*
Y1579162D01*
G01X392505Y1609422D02*
Y1612622D01*
G01X398705Y1609422D02*
X392505D01*
G01Y1608622D02*
X398705D01*
G01X392505Y1605422D02*
Y1608622D01*
G01X398705Y1605422D02*
X392505D01*
G01Y1604622D02*
X398705D01*
G01X392505Y1601422D02*
Y1604622D01*
G01X398705Y1601422D02*
X392505D01*
G01Y1600622D02*
X398705D01*
G01X392505Y1597422D02*
Y1600622D01*
G01X398705Y1597422D02*
X392505D01*
G01Y1612622D02*
X398705D01*
G01X386424Y1622613D02*
X383224D01*
G01X386424Y1628813D02*
Y1622613D01*
G01X383224D02*
Y1628813D01*
G01X396424Y1622613D02*
X393224D01*
G01D02*
Y1628813D01*
G01X391424Y1622613D02*
X388224D01*
G01X391424Y1628813D02*
Y1622613D01*
G01X388224D02*
Y1628813D01*
G01X389003Y1620022D02*
Y1613622D01*
G01X401883D02*
X389003D01*
G01Y1620022D02*
X401883D01*
G01X383224Y1628813D02*
X386424D01*
G01X393224D02*
X396424D01*
G01X388224D02*
X391424D01*
G01X388324Y1644587D02*
X382481Y1638744D01*
Y1631013D01*
X402167D01*
Y1658161D01*
X382481D01*
Y1650430D01*
X388324Y1644587D01*
G01X386424Y1660020D02*
X383224D01*
G01X386424Y1666220D02*
Y1660020D01*
G01X383224Y1666220D02*
X386424D01*
G01X383224Y1660020D02*
Y1666220D01*
G01X396424Y1660020D02*
X393224D01*
G01Y1666220D02*
X396424D01*
G01X393224Y1660020D02*
Y1666220D01*
G01X391424Y1660020D02*
X388224D01*
G01X391424Y1666220D02*
Y1660020D01*
G01X388224Y1666220D02*
X391424D01*
G01X388224Y1660020D02*
Y1666220D01*
G01X381392Y1679546D02*
X384592D01*
G01X381392Y1673346D02*
Y1679546D01*
G01X384592Y1673346D02*
X381392D01*
G01X384592Y1679546D02*
Y1673346D01*
G01X385724Y1679595D02*
X388924D01*
G01X385724Y1673395D02*
Y1679595D01*
G01X388924Y1673395D02*
X385724D01*
G01X388924Y1679595D02*
Y1673395D01*
G01X390724Y1679595D02*
X393924D01*
G01X390724Y1673395D02*
Y1679595D01*
G01X393924Y1673395D02*
X390724D01*
G01X393924Y1679595D02*
Y1673395D01*
G01X406629Y-23927D02*
X406821Y-24237D01*
X407051Y-24444D01*
X407319Y-24547D01*
X407626Y-24444D01*
X407856Y-24237D01*
X408086Y-23927D01*
X408163Y-23514D01*
Y-21447D01*
G01X410419Y-24547D02*
X410496Y-23875D01*
X410611Y-23307D01*
X410764Y-22790D01*
X410956Y-22222D01*
X411263Y-21447D01*
X409729D01*
G01X413519Y-24547D02*
X413596Y-23875D01*
X413711Y-23307D01*
X413864Y-22790D01*
X414056Y-22222D01*
X414363Y-21447D01*
X412829D01*
G01X410461Y74454D02*
Y75849D01*
X409694Y77554D01*
G01X411228D02*
X410461Y75849D01*
G01X412833Y75746D02*
X413101Y76107D01*
X413331Y76314D01*
X413638Y76417D01*
X413906Y76314D01*
X414098Y76107D01*
X414251Y75797D01*
X414289Y75436D01*
X414251Y75126D01*
X414098Y74816D01*
X413868Y74557D01*
X413599Y74454D01*
X413293Y74557D01*
X413024Y74867D01*
X412871Y75332D01*
X412833Y75849D01*
X412909Y76521D01*
X413024Y76882D01*
X413216Y77244D01*
X413484Y77502D01*
X413753Y77554D01*
X414021Y77451D01*
X414213Y77192D01*
G01X416661Y77554D02*
X416354Y77451D01*
X416124Y77192D01*
X415971Y76882D01*
X415856Y76469D01*
X415818Y76004D01*
X415856Y75539D01*
X415971Y75126D01*
X416124Y74816D01*
X416354Y74557D01*
X416661Y74454D01*
X416968Y74557D01*
X417198Y74816D01*
X417351Y75126D01*
X417466Y75539D01*
X417504Y76004D01*
X417466Y76469D01*
X417351Y76882D01*
X417198Y77192D01*
X416968Y77451D01*
X416661Y77554D01*
G01X419761D02*
X419454Y77451D01*
X419224Y77192D01*
X419071Y76882D01*
X418956Y76469D01*
X418918Y76004D01*
X418956Y75539D01*
X419071Y75126D01*
X419224Y74816D01*
X419454Y74557D01*
X419761Y74454D01*
X420068Y74557D01*
X420298Y74816D01*
X420451Y75126D01*
X420566Y75539D01*
X420604Y76004D01*
X420566Y76469D01*
X420451Y76882D01*
X420298Y77192D01*
X420068Y77451D01*
X419761Y77554D01*
G01X422861D02*
X422554Y77451D01*
X422324Y77192D01*
X422171Y76882D01*
X422056Y76469D01*
X422018Y76004D01*
X422056Y75539D01*
X422171Y75126D01*
X422324Y74816D01*
X422554Y74557D01*
X422861Y74454D01*
X423168Y74557D01*
X423398Y74816D01*
X423551Y75126D01*
X423666Y75539D01*
X423704Y76004D01*
X423666Y76469D01*
X423551Y76882D01*
X423398Y77192D01*
X423168Y77451D01*
X422861Y77554D01*
G01X404643Y100976D02*
Y107176D01*
G01X407843D02*
Y100976D01*
G01D02*
X404643D01*
G01Y107176D02*
X407843D01*
G01X400506Y136580D02*
Y133380D01*
G01X396648Y128278D02*
Y122078D01*
G01X397664Y122044D02*
Y128244D01*
G01D02*
X400864D01*
G01D02*
Y122044D01*
G01D02*
X397664D01*
G01X397396Y140580D02*
Y137380D01*
G01X404041Y149900D02*
X410241D01*
G01Y146700D02*
X404041D01*
G01D02*
Y149900D01*
G01X410241Y142700D02*
X404041D01*
G01D02*
Y145900D01*
G01D02*
X410241D01*
G01X402232Y139625D02*
X399032D01*
G01D02*
Y145825D01*
G01D02*
X402232D01*
G01D02*
Y139625D01*
G01X406893Y158634D02*
Y155434D01*
G01X400693Y158634D02*
X406893D01*
G01X400693Y155434D02*
Y158634D01*
G01X406893Y155434D02*
X400693D01*
G01X406893Y153878D02*
Y150678D01*
G01X400693Y153878D02*
X406893D01*
G01X400693Y150678D02*
Y153878D01*
G01X406893Y150678D02*
X400693D01*
G01X408899Y205020D02*
X405699D01*
G01X408899Y211220D02*
Y205020D01*
G01X405699D02*
Y211220D01*
G01X404899Y205020D02*
X401699D01*
G01X404899Y211220D02*
Y205020D01*
G01X401699D02*
Y211220D01*
G01X395153Y219195D02*
Y207195D01*
G01X404899Y219171D02*
Y212971D01*
G01D02*
X401699D01*
G01D02*
Y219171D01*
G01D02*
X404899D01*
G01X397699Y212971D02*
Y219171D01*
G01D02*
X400899D01*
G01D02*
Y212971D01*
G01D02*
X397699D01*
G01X408899Y219171D02*
Y212971D01*
G01D02*
X405699D01*
G01D02*
Y219171D01*
G01D02*
X408899D01*
G01X405699Y211220D02*
X408899D01*
G01X401699D02*
X404899D01*
G01X396100Y313100D02*
Y309900D01*
G01X406100Y305600D02*
Y302400D01*
G01X399900Y305600D02*
X406100D01*
G01X399900Y302400D02*
Y305600D01*
G01X406100Y302400D02*
X399900D01*
G01X398600Y305600D02*
Y302400D01*
G01X400584Y467369D02*
Y473569D01*
G01D02*
X403784D01*
G01D02*
Y467369D01*
G01D02*
X400584D01*
G01X394976Y473797D02*
Y467597D01*
G01X410910Y484307D02*
X410858Y484000D01*
X410652Y483732D01*
X410342Y483502D01*
X409980Y483349D01*
X409567Y483272D01*
X409153D01*
X408740Y483349D01*
X408378Y483502D01*
X408068Y483732D01*
X407862Y484000D01*
X407810Y484307D01*
X407862Y484614D01*
X408068Y484882D01*
X408378Y485112D01*
X408740Y485265D01*
X409153Y485342D01*
X409567D01*
X409980Y485265D01*
X410342Y485112D01*
X410652Y484882D01*
X410858Y484614D01*
X410910Y484307D01*
G01X410083Y484614D02*
X410910Y485074D01*
G01Y487407D02*
X407810D01*
X408430Y486947D01*
G01X410910D02*
Y487867D01*
G01X410548Y489855D02*
X410807Y490124D01*
X410910Y490430D01*
X410807Y490737D01*
X410497Y491005D01*
X410032Y491197D01*
X409567Y491274D01*
X408998D01*
X408533Y491197D01*
X408120Y491005D01*
X407913Y490775D01*
X407810Y490507D01*
X407913Y490200D01*
X408120Y489970D01*
X408430Y489817D01*
X408843Y489740D01*
X409205Y489817D01*
X409567Y490009D01*
X409773Y490239D01*
X409825Y490507D01*
X409722Y490814D01*
X409463Y491044D01*
X408998Y491274D01*
G01X406515Y493485D02*
Y480085D01*
G01D02*
X397853D01*
G01D02*
Y493485D01*
G01X400584Y500001D02*
Y506201D01*
G01D02*
X403784D01*
G01D02*
Y500001D01*
G01D02*
X400584D01*
G01X407784Y506201D02*
Y500001D01*
G01D02*
X404584D01*
G01D02*
Y506201D01*
G01D02*
X407784D01*
G01X398784D02*
Y500001D01*
G01D02*
X395584D01*
G01D02*
Y506201D01*
G01D02*
X398784D01*
G01X412584Y499924D02*
X409384D01*
G01D02*
Y506124D01*
G01D02*
X412584D01*
G01X397853Y493485D02*
X406515D01*
G01X399448Y542280D02*
Y529799D01*
G01X404471Y553515D02*
Y550315D01*
G01D02*
X398271D01*
G01D02*
Y553515D01*
G01X404471Y554315D02*
X398271D01*
G01D02*
Y557515D01*
G01D02*
X404471D01*
G01D02*
Y554315D01*
G01X398271Y553515D02*
X404471D01*
G01Y559815D02*
X398271D01*
G01D02*
Y563015D01*
G01D02*
X404471D01*
G01D02*
Y559815D01*
G01X402273Y575453D02*
Y569253D01*
G01D02*
X399073D01*
G01D02*
Y575453D01*
G01D02*
X402273D01*
G01X399657Y668057D02*
Y671157D01*
G01X401267D02*
Y668057D01*
G01Y669607D02*
X399657D01*
G01X404022Y668057D02*
Y671157D01*
X402604Y668935D01*
X404520D01*
G01X405819Y668677D02*
X406049Y668315D01*
X406355Y668109D01*
X406700Y668057D01*
X407007Y668109D01*
X407314Y668367D01*
X407505Y668677D01*
X407544Y668987D01*
X407467Y669349D01*
X407199Y669607D01*
X406930Y669710D01*
X406585D01*
G01X406930D02*
X407160Y669865D01*
X407352Y670124D01*
X407429Y670434D01*
X407352Y670744D01*
X407160Y671002D01*
X406815Y671157D01*
X406470Y671105D01*
X406125Y670899D01*
G01X402403Y681215D02*
Y684315D01*
X403323D01*
X403630Y684160D01*
X403860Y683798D01*
X403937Y683385D01*
X403860Y682972D01*
X403668Y682662D01*
X403323Y682507D01*
X402403D01*
G01X405427Y684315D02*
Y682093D01*
X405580Y681628D01*
X405887Y681318D01*
X406270Y681215D01*
X406653Y681318D01*
X406960Y681628D01*
X407113Y682093D01*
Y684315D01*
G01X408642Y683798D02*
X408872Y684108D01*
X409140Y684263D01*
X409447Y684315D01*
X409830Y684212D01*
X410098Y683953D01*
X410175Y683643D01*
X410137Y683333D01*
X409983Y683075D01*
X409217Y682558D01*
X408872Y682197D01*
X408642Y681680D01*
X408565Y681215D01*
X410175D01*
G01X412470D02*
X412738Y681267D01*
X413045Y681422D01*
X413237Y681680D01*
X413313Y682042D01*
X413237Y682403D01*
X413007Y682713D01*
X412662Y682868D01*
X412278D01*
X412048Y682972D01*
X411857Y683230D01*
X411780Y683592D01*
X411895Y683953D01*
X412163Y684212D01*
X412470Y684315D01*
X412777Y684212D01*
X413045Y683953D01*
X413160Y683592D01*
X413083Y683230D01*
X412892Y682972D01*
X412662Y682868D01*
X412278D01*
X411933Y682713D01*
X411703Y682403D01*
X411627Y682042D01*
X411703Y681680D01*
X411895Y681422D01*
X412202Y681267D01*
X412470Y681215D01*
G01X402261Y703240D02*
Y697040D01*
G01D02*
X399061D01*
G01D02*
Y703240D01*
G01X407139Y697994D02*
Y704194D01*
G01X410339Y697994D02*
X407139D01*
G01X403171Y691538D02*
Y697738D01*
G01D02*
X406371D01*
G01D02*
Y691538D01*
G01D02*
X403171D01*
G01X398291Y700346D02*
Y697146D01*
G01X399061Y703240D02*
X402261D01*
G01X407139Y704194D02*
X410339D01*
G01X406155Y711871D02*
Y705671D01*
G01D02*
X402955D01*
G01D02*
Y707300D01*
G01Y711871D02*
X406155D01*
G01X402955Y709700D02*
Y711871D01*
G01Y716171D02*
Y722371D01*
G01X406155D02*
Y716171D01*
G01D02*
X402955D01*
G01X399898Y709307D02*
Y707453D01*
G01D02*
X398890D01*
G01X402955Y722371D02*
X406155D01*
G01X401498Y729492D02*
Y732692D01*
G01X407698Y729492D02*
X401498D01*
G01X407698Y732692D02*
Y729492D01*
G01X402932Y729192D02*
X406132D01*
G01X402932Y722992D02*
Y729192D01*
G01X406132Y722992D02*
X402932D01*
G01X406132Y729192D02*
Y722992D01*
G01X399105Y731075D02*
X399898D01*
G01D02*
Y728475D01*
G01Y721864D02*
Y720166D01*
G01X401498Y732692D02*
X407698D01*
G01X404355Y734292D02*
X399014D01*
G01X404355Y777600D02*
Y734292D01*
G01X408962Y769668D02*
X405862D01*
Y770588D01*
X406017Y770895D01*
X406379Y771125D01*
X406792Y771202D01*
X407205Y771125D01*
X407515Y770933D01*
X407670Y770588D01*
Y769668D01*
G01X405862Y772768D02*
X408962D01*
Y774302D01*
G01X406379Y775907D02*
X406069Y776137D01*
X405914Y776405D01*
X405862Y776712D01*
X405965Y777095D01*
X406224Y777363D01*
X406534Y777440D01*
X406844Y777402D01*
X407102Y777248D01*
X407619Y776482D01*
X407980Y776137D01*
X408497Y775907D01*
X408962Y775830D01*
Y777440D01*
G01Y779735D02*
X408910Y780003D01*
X408755Y780310D01*
X408497Y780502D01*
X408135Y780578D01*
X407774Y780502D01*
X407464Y780272D01*
X407309Y779927D01*
Y779543D01*
X407205Y779313D01*
X406947Y779122D01*
X406585Y779045D01*
X406224Y779160D01*
X405965Y779428D01*
X405862Y779735D01*
X405965Y780042D01*
X406224Y780310D01*
X406585Y780425D01*
X406947Y780348D01*
X407205Y780157D01*
X407309Y779927D01*
Y779543D01*
X407464Y779198D01*
X407774Y778968D01*
X408135Y778892D01*
X408497Y778968D01*
X408755Y779160D01*
X408910Y779467D01*
X408962Y779735D01*
G01X399014Y777600D02*
X404355D01*
G01X421800Y860722D02*
X409400D01*
G01X415600Y870789D02*
X408600D01*
G01X398300Y1177706D02*
X414600D01*
G01X396940Y1328116D02*
Y1324916D01*
G01X398540Y1326533D02*
Y1329133D01*
G01X399333Y1326533D02*
X398540D01*
G01X395483Y1341437D02*
Y1335237D01*
G01X395506Y1334616D02*
Y1328416D01*
G01X398540Y1335744D02*
Y1337442D01*
G01X399377Y1354368D02*
X396177D01*
G01X399377Y1360568D02*
Y1354368D01*
G01X396177D02*
Y1360568D01*
G01X395483Y1351937D02*
Y1350300D01*
G01Y1347800D02*
Y1345737D01*
G01X400147Y1357262D02*
Y1360462D01*
G01X406347Y1357262D02*
X400147D01*
G01X406347Y1360462D02*
Y1357262D01*
G01X398540Y1350155D02*
X399548D01*
G01X398540Y1348301D02*
Y1350155D01*
G01X396177Y1360568D02*
X399377D01*
G01X400147Y1360462D02*
X406347D01*
G01X396883Y1367000D02*
Y1370100D01*
X397803D01*
X398110Y1369945D01*
X398340Y1369583D01*
X398417Y1369170D01*
X398340Y1368757D01*
X398148Y1368447D01*
X397803Y1368292D01*
X396883D01*
G01X399907Y1370100D02*
Y1367878D01*
X400060Y1367413D01*
X400367Y1367103D01*
X400750Y1367000D01*
X401133Y1367103D01*
X401440Y1367413D01*
X401593Y1367878D01*
Y1370100D01*
G01X403007Y1367620D02*
X403237Y1367258D01*
X403543Y1367052D01*
X403888Y1367000D01*
X404195Y1367052D01*
X404502Y1367310D01*
X404693Y1367620D01*
X404732Y1367930D01*
X404655Y1368292D01*
X404387Y1368550D01*
X404118Y1368653D01*
X403773D01*
G01X404118D02*
X404348Y1368808D01*
X404540Y1369067D01*
X404617Y1369377D01*
X404540Y1369687D01*
X404348Y1369945D01*
X404003Y1370100D01*
X403658Y1370048D01*
X403313Y1369842D01*
G01X406107Y1367620D02*
X406337Y1367258D01*
X406643Y1367052D01*
X406988Y1367000D01*
X407295Y1367052D01*
X407602Y1367310D01*
X407793Y1367620D01*
X407832Y1367930D01*
X407755Y1368292D01*
X407487Y1368550D01*
X407218Y1368653D01*
X406873D01*
G01X407218D02*
X407448Y1368808D01*
X407640Y1369067D01*
X407717Y1369377D01*
X407640Y1369687D01*
X407448Y1369945D01*
X407103Y1370100D01*
X406758Y1370048D01*
X406413Y1369842D01*
G01X396966Y1362816D02*
Y1365916D01*
X397886D01*
X398193Y1365761D01*
X398423Y1365399D01*
X398500Y1364986D01*
X398423Y1364573D01*
X398231Y1364263D01*
X397886Y1364108D01*
X396966D01*
G01X400066Y1365916D02*
Y1362816D01*
X401600D01*
G01X403205Y1364108D02*
X403473Y1364469D01*
X403703Y1364676D01*
X404010Y1364779D01*
X404278Y1364676D01*
X404470Y1364469D01*
X404623Y1364159D01*
X404661Y1363798D01*
X404623Y1363488D01*
X404470Y1363178D01*
X404240Y1362919D01*
X403971Y1362816D01*
X403665Y1362919D01*
X403396Y1363229D01*
X403243Y1363694D01*
X403205Y1364211D01*
X403281Y1364883D01*
X403396Y1365244D01*
X403588Y1365606D01*
X403856Y1365864D01*
X404125Y1365916D01*
X404393Y1365813D01*
X404585Y1365554D01*
G01X406381Y1363178D02*
X406650Y1362919D01*
X406956Y1362816D01*
X407263Y1362919D01*
X407531Y1363229D01*
X407723Y1363694D01*
X407800Y1364159D01*
Y1364728D01*
X407723Y1365193D01*
X407531Y1365606D01*
X407301Y1365813D01*
X407033Y1365916D01*
X406726Y1365813D01*
X406496Y1365606D01*
X406343Y1365296D01*
X406266Y1364883D01*
X406343Y1364521D01*
X406535Y1364159D01*
X406765Y1363953D01*
X407033Y1363901D01*
X407340Y1364004D01*
X407570Y1364263D01*
X407800Y1364728D01*
G01X395259Y1542491D02*
Y1507451D01*
G01X403261Y1517620D02*
X409261D01*
Y1514620D01*
X403261D01*
Y1517620D01*
G01X400059Y1518320D02*
Y1524520D01*
X403259D01*
Y1518320D01*
X400059D01*
G01X405961D02*
Y1524520D01*
X409161D01*
Y1518320D01*
X405961D01*
G01X409361Y1510620D02*
X403161D01*
Y1513820D01*
X409361D01*
Y1510620D01*
G01X406211D02*
X400011D01*
Y1513820D01*
X406211D01*
Y1510620D01*
G01Y1514520D02*
X400011D01*
Y1517720D01*
X406211D01*
Y1514520D01*
G01X405369Y1549978D02*
Y1546878D01*
X406903D01*
G01X409236D02*
Y1549978D01*
X408776Y1549358D01*
G01Y1546878D02*
X409696D01*
G01X412336Y1549978D02*
X412029Y1549875D01*
X411799Y1549616D01*
X411646Y1549306D01*
X411531Y1548893D01*
X411493Y1548428D01*
X411531Y1547963D01*
X411646Y1547550D01*
X411799Y1547240D01*
X412029Y1546981D01*
X412336Y1546878D01*
X412643Y1546981D01*
X412873Y1547240D01*
X413026Y1547550D01*
X413141Y1547963D01*
X413179Y1548428D01*
X413141Y1548893D01*
X413026Y1549306D01*
X412873Y1549616D01*
X412643Y1549875D01*
X412336Y1549978D01*
G01X398036Y1572839D02*
X417722D01*
G01X398036Y1587239D02*
Y1572839D01*
G01X417722Y1587239D02*
X398036D01*
G01X398705Y1612622D02*
Y1609422D01*
G01Y1608622D02*
Y1605422D01*
G01Y1604622D02*
Y1601422D01*
G01Y1600622D02*
Y1597422D01*
G01X408450Y1604785D02*
Y1602882D01*
G01D02*
X410353D01*
G01X400600Y1628813D02*
Y1622613D01*
G01X397400D02*
Y1628813D01*
G01X400600Y1622613D02*
X397400D01*
G01X396424Y1628813D02*
Y1622613D01*
G01X404569Y1621224D02*
X401369D01*
G01X404569Y1627424D02*
Y1621224D01*
G01X401369D02*
Y1627424D01*
G01X401883Y1620022D02*
Y1613622D01*
G01X410353Y1622568D02*
X408450D01*
G01D02*
Y1620665D01*
G01X397400Y1628813D02*
X400600D01*
G01X402906Y1629619D02*
Y1632819D01*
G01X409106Y1629619D02*
X402906D01*
G01X409106Y1632819D02*
Y1629619D01*
G01X402906Y1632819D02*
X409106D01*
G01X401369Y1627424D02*
X404569D01*
G01X407400Y1635400D02*
Y1638600D01*
G01X413600Y1635400D02*
X407400D01*
G01Y1638600D02*
X413600D01*
G01X407400Y1639400D02*
Y1642600D01*
G01X413600Y1639400D02*
X407400D01*
G01X404400Y1647100D02*
X410600D01*
G01X404400Y1643900D02*
Y1647100D01*
G01X410600Y1643900D02*
X404400D01*
G01Y1651100D02*
X410600D01*
G01X404400Y1647900D02*
Y1651100D01*
G01X410600Y1647900D02*
X404400D01*
G01Y1651900D02*
Y1655100D01*
G01X410600Y1651900D02*
X404400D01*
G01Y1655100D02*
X410600D01*
G01X407400Y1642600D02*
X413600D01*
G01X401424Y1660020D02*
X398224D01*
G01X401424Y1666220D02*
Y1660020D01*
G01X398224Y1666220D02*
X401424D01*
G01X398224Y1660020D02*
Y1666220D01*
G01X396424D02*
Y1660020D01*
G01X404669Y1660560D02*
X413331D01*
G01X404669Y1671440D02*
Y1660560D01*
G01X395724Y1679595D02*
X398924D01*
G01X395724Y1673395D02*
Y1679595D01*
G01X398924Y1673395D02*
X395724D01*
G01X398924Y1679595D02*
Y1673395D01*
G01X407400Y1682100D02*
X410600D01*
G01X407400Y1675900D02*
Y1682100D01*
G01X410600Y1675900D02*
X407400D01*
G01X406600D02*
X403400D01*
G01X406600Y1682100D02*
Y1675900D01*
G01X403400Y1682100D02*
X406600D01*
G01X403400Y1675900D02*
Y1682100D01*
G01X413331Y1671440D02*
X404669D01*
G01X417000Y-630638D02*
Y-622638D01*
X415800Y-624238D01*
G01Y-630638D02*
X418200D01*
G01X423100Y-627305D02*
X423800Y-626371D01*
X424400Y-625838D01*
X425200Y-625571D01*
X425900Y-625838D01*
X426400Y-626371D01*
X426800Y-627171D01*
X426900Y-628105D01*
X426800Y-628905D01*
X426400Y-629705D01*
X425800Y-630371D01*
X425100Y-630638D01*
X424300Y-630371D01*
X423600Y-629572D01*
X423200Y-628371D01*
X423100Y-627038D01*
X423300Y-625305D01*
X423600Y-624371D01*
X424100Y-623438D01*
X424800Y-622771D01*
X425500Y-622638D01*
X426200Y-622905D01*
X426700Y-623571D01*
G01X433000Y-630905D02*
X432800Y-630771D01*
Y-630505D01*
X433000Y-630371D01*
X433200Y-630505D01*
Y-630771D01*
X433000Y-630905D01*
G01X439100Y-627305D02*
X439800Y-626371D01*
X440400Y-625838D01*
X441200Y-625571D01*
X441900Y-625838D01*
X442400Y-626371D01*
X442800Y-627171D01*
X442900Y-628105D01*
X442800Y-628905D01*
X442400Y-629705D01*
X441800Y-630371D01*
X441100Y-630638D01*
X440300Y-630371D01*
X439600Y-629572D01*
X439200Y-628371D01*
X439100Y-627038D01*
X439300Y-625305D01*
X439600Y-624371D01*
X440100Y-623438D01*
X440800Y-622771D01*
X441500Y-622638D01*
X442200Y-622905D01*
X442700Y-623571D01*
G01X417893Y58335D02*
Y61535D01*
G01X424093Y58335D02*
X417893D01*
G01X424093Y61535D02*
Y58335D01*
G01X424100Y56362D02*
Y53162D01*
G01X417900Y56362D02*
X424100D01*
G01X417900Y53162D02*
Y56362D01*
G01X424100Y53162D02*
X417900D01*
G01X423937Y73265D02*
Y70065D01*
G01X417737D02*
Y73265D01*
G01X423937Y70065D02*
X417737D01*
G01Y73265D02*
X423937D01*
G01Y68465D02*
Y65265D01*
G01X417737D02*
Y68465D01*
G01X423937Y65265D02*
X417737D01*
G01Y68465D02*
X423937D01*
G01X417893Y61535D02*
X424093D01*
G01X412009Y79983D02*
Y95383D01*
G01X424609Y79983D02*
X412009D01*
G01X417801Y97548D02*
X411601D01*
G01D02*
Y100748D01*
G01D02*
X417801D01*
G01D02*
Y97548D01*
G01X418701Y100748D02*
X424901D01*
G01Y97548D02*
X418701D01*
G01D02*
Y100748D01*
G01X415151Y105748D02*
X421351D01*
G01D02*
Y102548D01*
G01D02*
X415151D01*
G01D02*
Y105748D01*
G01X412009Y95383D02*
X424609D01*
G01X418059Y107441D02*
X420281D01*
X420746Y107594D01*
X421056Y107901D01*
X421159Y108284D01*
X421056Y108667D01*
X420746Y108974D01*
X420281Y109127D01*
X418059D01*
G01X419867Y110656D02*
X419506Y110924D01*
X419299Y111154D01*
X419196Y111461D01*
X419299Y111729D01*
X419506Y111921D01*
X419816Y112074D01*
X420177Y112112D01*
X420487Y112074D01*
X420797Y111921D01*
X421056Y111691D01*
X421159Y111422D01*
X421056Y111116D01*
X420746Y110847D01*
X420281Y110694D01*
X419764Y110656D01*
X419092Y110732D01*
X418731Y110847D01*
X418369Y111039D01*
X418111Y111307D01*
X418059Y111576D01*
X418162Y111844D01*
X418421Y112036D01*
G01X418059Y114484D02*
X418162Y114177D01*
X418421Y113947D01*
X418731Y113794D01*
X419144Y113679D01*
X419609Y113641D01*
X420074Y113679D01*
X420487Y113794D01*
X420797Y113947D01*
X421056Y114177D01*
X421159Y114484D01*
X421056Y114791D01*
X420797Y115021D01*
X420487Y115174D01*
X420074Y115289D01*
X419609Y115327D01*
X419144Y115289D01*
X418731Y115174D01*
X418421Y115021D01*
X418162Y114791D01*
X418059Y114484D01*
G01Y117584D02*
X418162Y117277D01*
X418421Y117047D01*
X418731Y116894D01*
X419144Y116779D01*
X419609Y116741D01*
X420074Y116779D01*
X420487Y116894D01*
X420797Y117047D01*
X421056Y117277D01*
X421159Y117584D01*
X421056Y117891D01*
X420797Y118121D01*
X420487Y118274D01*
X420074Y118389D01*
X419609Y118427D01*
X419144Y118389D01*
X418731Y118274D01*
X418421Y118121D01*
X418162Y117891D01*
X418059Y117584D01*
G01X418576Y119956D02*
X418266Y120186D01*
X418111Y120454D01*
X418059Y120761D01*
X418162Y121144D01*
X418421Y121412D01*
X418731Y121489D01*
X419041Y121451D01*
X419299Y121297D01*
X419816Y120531D01*
X420177Y120186D01*
X420694Y119956D01*
X421159Y119879D01*
Y121489D01*
G01X410241Y149900D02*
Y146700D01*
G01Y145900D02*
Y142700D01*
G01X411041Y145900D02*
X417241D01*
G01D02*
Y142700D01*
G01D02*
X411041D01*
G01D02*
Y145900D01*
G01Y149900D02*
X417241D01*
G01D02*
Y146700D01*
G01D02*
X411041D01*
G01D02*
Y149900D01*
G01X421699Y205020D02*
Y211220D01*
G01X424899Y205020D02*
X421699D01*
G01X409699D02*
Y211220D01*
G01X412899D02*
Y205020D01*
G01D02*
X409699D01*
G01X416899D02*
X413699D01*
G01X416899Y211220D02*
Y205020D01*
G01X413699D02*
Y211220D01*
G01X420899Y205020D02*
X417699D01*
G01X420899Y211220D02*
Y205020D01*
G01X417699D02*
Y211220D01*
G01X419040Y224723D02*
X412840D01*
G01D02*
Y227923D01*
G01X419040D02*
Y224723D01*
G01X421699Y211220D02*
X424899D01*
G01X409699Y212971D02*
Y219171D01*
G01D02*
X412899D01*
G01D02*
Y212971D01*
G01D02*
X409699D01*
G01Y211220D02*
X412899D01*
G01X416899Y219171D02*
Y212971D01*
G01D02*
X413699D01*
G01D02*
Y219171D01*
G01D02*
X416899D01*
G01X413699Y211220D02*
X416899D01*
G01X417699D02*
X420899D01*
G01X412840Y227923D02*
X419040D01*
G01X412840Y237042D02*
X419040D01*
G01D02*
Y233842D01*
G01D02*
X412840D01*
G01D02*
Y237042D01*
G01X419040Y228723D02*
X412840D01*
G01D02*
Y231923D01*
G01D02*
X419040D01*
G01D02*
Y228723D01*
G01Y238901D02*
X412840D01*
G01D02*
Y242101D01*
G01X419040D02*
Y238901D01*
G01X412840Y242101D02*
X419040D01*
G01X413615Y251765D02*
X419815D01*
G01D02*
Y248565D01*
G01D02*
X413615D01*
G01D02*
Y251765D01*
G01X419815Y252565D02*
X413615D01*
G01D02*
Y255765D01*
G01X419815D02*
Y252565D01*
G01X413615Y259765D02*
X419815D01*
G01D02*
Y256565D01*
G01D02*
X413615D01*
G01D02*
Y259765D01*
G01X419815Y268565D02*
X413615D01*
G01D02*
Y271765D01*
G01X419815D02*
Y268565D01*
G01X413615Y255765D02*
X419815D01*
G01Y260565D02*
X413615D01*
G01D02*
Y263765D01*
G01D02*
X419815D01*
G01D02*
Y260565D01*
G01X413615Y267765D02*
X419815D01*
G01D02*
Y264565D01*
G01D02*
X413615D01*
G01D02*
Y267765D01*
G01Y271765D02*
X419815D01*
G01X414384Y467292D02*
Y473492D01*
G01D02*
X417584D01*
G01D02*
Y467292D01*
G01D02*
X414384D01*
G01X424882Y484051D02*
X424830Y483744D01*
X424624Y483476D01*
X424314Y483246D01*
X423952Y483093D01*
X423539Y483016D01*
X423125D01*
X422712Y483093D01*
X422350Y483246D01*
X422040Y483476D01*
X421834Y483744D01*
X421782Y484051D01*
X421834Y484358D01*
X422040Y484626D01*
X422350Y484856D01*
X422712Y485009D01*
X423125Y485086D01*
X423539D01*
X423952Y485009D01*
X424314Y484856D01*
X424624Y484626D01*
X424830Y484358D01*
X424882Y484051D01*
G01X424055Y484358D02*
X424882Y484818D01*
G01X422299Y486423D02*
X421989Y486653D01*
X421834Y486921D01*
X421782Y487228D01*
X421885Y487611D01*
X422144Y487879D01*
X422454Y487956D01*
X422764Y487918D01*
X423022Y487764D01*
X423539Y486998D01*
X423900Y486653D01*
X424417Y486423D01*
X424882Y486346D01*
Y487956D01*
G01Y490174D02*
X424210Y490251D01*
X423642Y490366D01*
X423125Y490519D01*
X422557Y490711D01*
X421782Y491018D01*
Y489484D01*
G01X411653Y493408D02*
X420315D01*
G01D02*
Y480008D01*
G01D02*
X411653D01*
G01D02*
Y493408D01*
G01X414384Y499924D02*
Y506124D01*
G01D02*
X417584D01*
G01D02*
Y499924D01*
G01D02*
X414384D01*
G01X421584Y506124D02*
Y499924D01*
G01D02*
X418384D01*
G01D02*
Y506124D01*
G01D02*
X421584D01*
G01X412584D02*
Y499924D01*
G01X426384Y499847D02*
X423184D01*
G01D02*
Y506047D01*
G01D02*
X426384D01*
G01X411171Y529538D02*
Y535738D01*
G01D02*
X414371D01*
G01D02*
Y529538D01*
G01D02*
X411171D01*
G01X428177Y530326D02*
X416365D01*
G01D02*
Y542950D01*
G01D02*
X428177D01*
G01X414424Y680050D02*
Y686250D01*
G01D02*
X417624D01*
G01D02*
Y680050D01*
G01D02*
X414424D01*
G01X421666Y686250D02*
Y680050D01*
G01D02*
X418466D01*
G01D02*
Y686250D01*
G01D02*
X421666D01*
G01X410339Y704194D02*
Y697994D01*
G01X413945Y689653D02*
X413212D01*
G01D02*
Y691844D01*
G01Y710675D02*
Y713275D01*
G01D02*
X414005D01*
G01X410798Y759815D02*
Y716507D01*
G01D02*
X416139D01*
G01Y759815D02*
X410798D01*
G01X420422Y770438D02*
X417322D01*
Y771358D01*
X417477Y771665D01*
X417839Y771895D01*
X418252Y771972D01*
X418665Y771895D01*
X418975Y771703D01*
X419130Y771358D01*
Y770438D01*
G01X417322Y773538D02*
X420422D01*
Y775072D01*
G01X419802Y776562D02*
X420164Y776792D01*
X420370Y777098D01*
X420422Y777443D01*
X420370Y777750D01*
X420112Y778057D01*
X419802Y778248D01*
X419492Y778287D01*
X419130Y778210D01*
X418872Y777942D01*
X418769Y777673D01*
Y777328D01*
G01Y777673D02*
X418614Y777903D01*
X418355Y778095D01*
X418045Y778172D01*
X417735Y778095D01*
X417477Y777903D01*
X417322Y777558D01*
X417374Y777213D01*
X417580Y776868D01*
G01X420422Y780505D02*
X417322D01*
X417942Y780045D01*
G01X420422D02*
Y780965D01*
G01X413974Y769598D02*
X410874D01*
Y770518D01*
X411029Y770825D01*
X411391Y771055D01*
X411804Y771132D01*
X412217Y771055D01*
X412527Y770863D01*
X412682Y770518D01*
Y769598D01*
G01X410874Y772698D02*
X413974D01*
Y774232D01*
G01X411391Y775837D02*
X411081Y776067D01*
X410926Y776335D01*
X410874Y776642D01*
X410977Y777025D01*
X411236Y777293D01*
X411546Y777370D01*
X411856Y777332D01*
X412114Y777178D01*
X412631Y776412D01*
X412992Y776067D01*
X413509Y775837D01*
X413974Y775760D01*
Y777370D01*
G01X413612Y779013D02*
X413871Y779282D01*
X413974Y779588D01*
X413871Y779895D01*
X413561Y780163D01*
X413096Y780355D01*
X412631Y780432D01*
X412062D01*
X411597Y780355D01*
X411184Y780163D01*
X410977Y779933D01*
X410874Y779665D01*
X410977Y779358D01*
X411184Y779128D01*
X411494Y778975D01*
X411907Y778898D01*
X412269Y778975D01*
X412631Y779167D01*
X412837Y779397D01*
X412889Y779665D01*
X412786Y779972D01*
X412527Y780202D01*
X412062Y780432D01*
G01X426600Y870789D02*
X419600D01*
G01X412905Y1003466D02*
Y1034962D01*
G01X468417Y1003466D02*
X412905D01*
G01X414066Y1007723D02*
X420266D01*
Y1004523D01*
X414066D01*
Y1007723D01*
G01Y1011464D02*
X420266D01*
Y1008264D01*
X414066D01*
Y1011464D01*
G01X423516Y1016366D02*
X429716D01*
Y1013166D01*
X423516D01*
Y1016366D01*
G01X422321Y1004823D02*
Y1011023D01*
X425521D01*
Y1004823D01*
X422321D01*
G01X414066Y1015204D02*
X420266D01*
Y1012004D01*
X414066D01*
Y1015204D01*
G01Y1030164D02*
X420266D01*
Y1026964D01*
X414066D01*
Y1030164D01*
G01X423498Y1020479D02*
X429698D01*
Y1017279D01*
X423498D01*
Y1020479D01*
G01X414066Y1022684D02*
X420266D01*
Y1019484D01*
X414066D01*
Y1022684D01*
G01Y1026424D02*
X420266D01*
Y1023224D01*
X414066D01*
Y1026424D01*
G01X425526Y1033604D02*
Y1027404D01*
X422326D01*
Y1033604D01*
X425526D01*
G01X414066Y1018944D02*
X420266D01*
Y1015744D01*
X414066D01*
Y1018944D01*
G01X423498Y1024613D02*
X429698D01*
Y1021413D01*
X423498D01*
Y1024613D01*
G01X412905Y1034962D02*
X468417D01*
G01X420266Y1030704D02*
X414066D01*
Y1033904D01*
X420266D01*
Y1030704D01*
G01X423611Y1280008D02*
Y1323316D01*
G01X418270Y1280008D02*
X423611D01*
G01X418226Y1326533D02*
X417433D01*
G01X418226Y1329133D02*
Y1326533D01*
G01X423611Y1323316D02*
X418270D01*
G01X421092Y1342035D02*
X424292D01*
G01X421092Y1335835D02*
Y1342035D01*
G01X424292Y1335835D02*
X421092D01*
G01X424292Y1342035D02*
Y1335835D01*
G01X413814Y1353558D02*
Y1359758D01*
G01X417014Y1353558D02*
X413814D01*
G01X417014Y1359758D02*
Y1353558D01*
G01X412972D02*
X409772D01*
G01X412972Y1359758D02*
Y1353558D01*
G01X409772D02*
Y1359758D01*
G01X418226Y1350155D02*
Y1347964D01*
G01X417493Y1350155D02*
X418226D01*
G01X413814Y1359758D02*
X417014D01*
G01X409772D02*
X412972D01*
G01X415248Y1536503D02*
Y1539911D01*
G01X432964Y1536503D02*
X415248D01*
G01Y1550811D02*
Y1554219D01*
G01D02*
X432964D01*
G01X418857Y1577050D02*
X421079D01*
X421544Y1577203D01*
X421854Y1577510D01*
X421957Y1577893D01*
X421854Y1578276D01*
X421544Y1578583D01*
X421079Y1578736D01*
X418857D01*
G01X421957Y1580993D02*
X418857D01*
X419477Y1580533D01*
G01X421957D02*
Y1581453D01*
G01X419374Y1583365D02*
X419064Y1583595D01*
X418909Y1583863D01*
X418857Y1584170D01*
X418960Y1584553D01*
X419219Y1584821D01*
X419529Y1584898D01*
X419839Y1584860D01*
X420097Y1584706D01*
X420614Y1583940D01*
X420975Y1583595D01*
X421492Y1583365D01*
X421957Y1583288D01*
Y1584898D01*
G01X417722Y1575796D02*
X413479Y1580039D01*
G01X417722Y1572839D02*
Y1575796D01*
G01X413479Y1580039D02*
X417722Y1584282D01*
G01X423031Y1572839D02*
X442717D01*
G01X423031Y1587239D02*
Y1572839D01*
G01X417722Y1584282D02*
Y1587239D01*
G01X442717D02*
X423031D01*
G01X424100Y1640600D02*
Y1637400D01*
G01X417900Y1640600D02*
X424100D01*
G01X417900Y1637400D02*
Y1640600D01*
G01X424100Y1637400D02*
X417900D01*
G01X424100Y1635600D02*
Y1632400D01*
G01X417900Y1635600D02*
X424100D01*
G01X417900Y1632400D02*
Y1635600D01*
G01X424100Y1632400D02*
X417900D01*
G01X413600Y1638600D02*
Y1635400D01*
G01Y1642600D02*
Y1639400D01*
G01X418600Y1651100D02*
Y1647900D01*
G01X412400Y1651100D02*
X418600D01*
G01X412400Y1647900D02*
Y1651100D01*
G01X418600Y1647900D02*
X412400D01*
G01Y1655900D02*
Y1659100D01*
G01X418600Y1655900D02*
X412400D01*
G01X418600Y1659100D02*
Y1655900D01*
G01Y1655100D02*
Y1651900D01*
G01X412400Y1655100D02*
X418600D01*
G01X412400Y1651900D02*
Y1655100D01*
G01X418600Y1651900D02*
X412400D01*
G01X410600Y1647100D02*
Y1643900D01*
G01Y1651100D02*
Y1647900D01*
G01Y1655100D02*
Y1651900D01*
G01X421900Y1646800D02*
X432100D01*
G01X421900Y1642200D02*
Y1646800D01*
G01X432100Y1642200D02*
X421900D01*
G01X418600Y1663400D02*
X415400D01*
G01X418600Y1669600D02*
Y1663400D01*
G01X415400Y1669600D02*
X418600D01*
G01X415400Y1663400D02*
Y1669600D01*
G01X412400Y1659100D02*
X418600D01*
G01X421708Y1661379D02*
X423930D01*
X424395Y1661532D01*
X424705Y1661839D01*
X424808Y1662222D01*
X424705Y1662605D01*
X424395Y1662912D01*
X423930Y1663065D01*
X421708D01*
G01X422225Y1664594D02*
X421915Y1664824D01*
X421760Y1665092D01*
X421708Y1665399D01*
X421811Y1665782D01*
X422070Y1666050D01*
X422380Y1666127D01*
X422690Y1666089D01*
X422948Y1665935D01*
X423465Y1665169D01*
X423826Y1664824D01*
X424343Y1664594D01*
X424808Y1664517D01*
Y1666127D01*
G01X424343Y1667579D02*
X424601Y1667809D01*
X424756Y1668077D01*
X424808Y1668422D01*
X424705Y1668767D01*
X424498Y1669035D01*
X424136Y1669227D01*
X423723Y1669265D01*
X423310Y1669189D01*
X423051Y1668997D01*
X422845Y1668729D01*
X422793Y1668460D01*
X422845Y1668192D01*
X423051Y1667847D01*
X421708Y1667962D01*
Y1668997D01*
G01X424343Y1670679D02*
X424601Y1670909D01*
X424756Y1671177D01*
X424808Y1671522D01*
X424705Y1671867D01*
X424498Y1672135D01*
X424136Y1672327D01*
X423723Y1672365D01*
X423310Y1672289D01*
X423051Y1672097D01*
X422845Y1671829D01*
X422793Y1671560D01*
X422845Y1671292D01*
X423051Y1670947D01*
X421708Y1671062D01*
Y1672097D01*
G01X413331Y1663669D02*
X411000Y1666000D01*
G01X413331Y1668331D02*
Y1671440D01*
G01X411000Y1666000D02*
X413331Y1668331D01*
G01Y1660560D02*
Y1663669D01*
G01X418600Y1675900D02*
X415400D01*
G01X418600Y1682100D02*
Y1675900D01*
G01X415400Y1682100D02*
X418600D01*
G01X415400Y1675900D02*
Y1682100D01*
G01X414600D02*
Y1675900D01*
G01X411400Y1682100D02*
X414600D01*
G01X411400Y1675900D02*
Y1682100D01*
G01X414600Y1675900D02*
X411400D01*
G01X410600Y1682100D02*
Y1675900D01*
G01X432121Y52673D02*
X459269D01*
G01X432121Y72359D02*
Y52673D01*
G01X440273Y75600D02*
X437073D01*
G01D02*
Y81800D01*
G01X432073Y75600D02*
Y81800D01*
G01X435273D02*
Y75600D01*
G01D02*
X432073D01*
G01X431273Y81800D02*
Y75600D01*
G01D02*
X428073D01*
G01D02*
Y81800D01*
G01X439852Y72359D02*
X432121D01*
G01X437073Y81800D02*
X440273D01*
G01X435285Y95757D02*
Y89557D01*
G01D02*
X432085D01*
G01D02*
Y95757D01*
G01X431285D02*
Y89557D01*
G01D02*
X428085D01*
G01D02*
Y95757D01*
G01X432073Y81800D02*
X435273D01*
G01X428073D02*
X431273D01*
G01X435273Y88800D02*
Y82600D01*
G01D02*
X432073D01*
G01D02*
Y88800D01*
G01D02*
X435273D01*
G01X440273Y82600D02*
X437073D01*
G01D02*
Y88800D01*
G01D02*
X440273D01*
G01X424609Y95383D02*
Y79983D01*
G01X424901Y100748D02*
Y97548D01*
G01X432085Y95757D02*
X435285D01*
G01X428085D02*
X431285D01*
G01X426177Y106094D02*
Y108201D01*
G01X428284Y106094D02*
X426177D01*
G01Y141920D02*
X428284D01*
G01X426177Y139813D02*
Y141920D01*
G01X439597Y159025D02*
X436397D01*
G01D02*
Y165225D01*
G01D02*
X439597D01*
G01X428397Y159025D02*
Y165225D01*
G01D02*
X431597D01*
G01D02*
Y159025D01*
G01D02*
X428397D01*
G01X435597Y165225D02*
Y159025D01*
G01D02*
X432397D01*
G01D02*
Y165225D01*
G01D02*
X435597D01*
G01X432397Y152025D02*
Y158225D01*
G01D02*
X435597D01*
G01D02*
Y152025D01*
G01D02*
X432397D01*
G01X436397D02*
Y158225D01*
G01D02*
X439597D01*
G01Y152025D02*
X436397D01*
G01X440899Y205020D02*
X437699D01*
G01D02*
Y211220D01*
G01X436899D02*
Y205020D01*
G01D02*
X433699D01*
G01D02*
Y211220D01*
G01X428899Y205020D02*
X425699D01*
G01X428899Y211220D02*
Y205020D01*
G01X425699D02*
Y211220D01*
G01X424899D02*
Y205020D01*
G01X432899Y211220D02*
Y205020D01*
G01D02*
X429699D01*
G01D02*
Y211220D01*
G01X432899Y219171D02*
Y212971D01*
G01D02*
X429699D01*
G01D02*
Y219171D01*
G01D02*
X432899D01*
G01X437699Y211220D02*
X440899D01*
G01X433699D02*
X436899D01*
G01X428899Y219171D02*
Y212971D01*
G01D02*
X425699D01*
G01D02*
Y219171D01*
G01D02*
X428899D01*
G01X425699Y211220D02*
X428899D01*
G01X436899Y219171D02*
Y212971D01*
G01D02*
X433699D01*
G01D02*
Y219171D01*
G01D02*
X436899D01*
G01X437699Y212971D02*
Y219171D01*
G01D02*
X440899D01*
G01Y212971D02*
X437699D01*
G01X429699Y211220D02*
X432899D01*
G01X432099Y221564D02*
Y241642D01*
G01X448731Y221564D02*
X432099D01*
G01X437643Y241642D02*
X440415Y238870D01*
G01X440756Y261868D02*
X436513Y266111D01*
X433556D01*
Y246425D01*
X447956D01*
Y266111D01*
X444999D01*
X440756Y261868D01*
G01X430950Y245961D02*
Y243739D01*
X431103Y243274D01*
X431410Y242964D01*
X431793Y242861D01*
X432176Y242964D01*
X432483Y243274D01*
X432636Y243739D01*
Y245961D01*
G01X434893Y242861D02*
Y245961D01*
X434433Y245341D01*
G01Y242861D02*
X435353D01*
G01X437265Y244153D02*
X437533Y244514D01*
X437763Y244721D01*
X438070Y244824D01*
X438338Y244721D01*
X438530Y244514D01*
X438683Y244204D01*
X438721Y243843D01*
X438683Y243533D01*
X438530Y243223D01*
X438300Y242964D01*
X438031Y242861D01*
X437725Y242964D01*
X437456Y243274D01*
X437303Y243739D01*
X437265Y244256D01*
X437341Y244928D01*
X437456Y245289D01*
X437648Y245651D01*
X437916Y245909D01*
X438185Y245961D01*
X438453Y245858D01*
X438645Y245599D01*
G01X441093Y245961D02*
X440786Y245858D01*
X440556Y245599D01*
X440403Y245289D01*
X440288Y244876D01*
X440250Y244411D01*
X440288Y243946D01*
X440403Y243533D01*
X440556Y243223D01*
X440786Y242964D01*
X441093Y242861D01*
X441400Y242964D01*
X441630Y243223D01*
X441783Y243533D01*
X441898Y243946D01*
X441936Y244411D01*
X441898Y244876D01*
X441783Y245289D01*
X441630Y245599D01*
X441400Y245858D01*
X441093Y245961D01*
G01X432099Y241642D02*
X437643D01*
G01X432763Y270435D02*
Y268213D01*
X432916Y267748D01*
X433223Y267438D01*
X433606Y267335D01*
X433989Y267438D01*
X434296Y267748D01*
X434449Y268213D01*
Y270435D01*
G01X435978Y268627D02*
X436246Y268988D01*
X436476Y269195D01*
X436783Y269298D01*
X437051Y269195D01*
X437243Y268988D01*
X437396Y268678D01*
X437434Y268317D01*
X437396Y268007D01*
X437243Y267697D01*
X437013Y267438D01*
X436744Y267335D01*
X436438Y267438D01*
X436169Y267748D01*
X436016Y268213D01*
X435978Y268730D01*
X436054Y269402D01*
X436169Y269763D01*
X436361Y270125D01*
X436629Y270383D01*
X436898Y270435D01*
X437166Y270332D01*
X437358Y270073D01*
G01X439806Y270435D02*
X439499Y270332D01*
X439269Y270073D01*
X439116Y269763D01*
X439001Y269350D01*
X438963Y268885D01*
X439001Y268420D01*
X439116Y268007D01*
X439269Y267697D01*
X439499Y267438D01*
X439806Y267335D01*
X440113Y267438D01*
X440343Y267697D01*
X440496Y268007D01*
X440611Y268420D01*
X440649Y268885D01*
X440611Y269350D01*
X440496Y269763D01*
X440343Y270073D01*
X440113Y270332D01*
X439806Y270435D01*
G01X442906D02*
X442599Y270332D01*
X442369Y270073D01*
X442216Y269763D01*
X442101Y269350D01*
X442063Y268885D01*
X442101Y268420D01*
X442216Y268007D01*
X442369Y267697D01*
X442599Y267438D01*
X442906Y267335D01*
X443213Y267438D01*
X443443Y267697D01*
X443596Y268007D01*
X443711Y268420D01*
X443749Y268885D01*
X443711Y269350D01*
X443596Y269763D01*
X443443Y270073D01*
X443213Y270332D01*
X442906Y270435D01*
G01X445163Y267955D02*
X445393Y267593D01*
X445699Y267387D01*
X446044Y267335D01*
X446351Y267387D01*
X446658Y267645D01*
X446849Y267955D01*
X446888Y268265D01*
X446811Y268627D01*
X446543Y268885D01*
X446274Y268988D01*
X445929D01*
G01X446274D02*
X446504Y269143D01*
X446696Y269402D01*
X446773Y269712D01*
X446696Y270022D01*
X446504Y270280D01*
X446159Y270435D01*
X445814Y270383D01*
X445469Y270177D01*
G01X428184Y467215D02*
Y473415D01*
G01D02*
X431384D01*
G01D02*
Y467215D01*
G01D02*
X428184D01*
G01X437900Y491100D02*
X441100D01*
G01X437900Y484900D02*
Y491100D01*
G01X441100Y484900D02*
X437900D01*
G01X441100Y491900D02*
X437900D01*
G01D02*
Y498100D01*
G01X425453Y493331D02*
X434115D01*
G01D02*
Y479931D01*
G01D02*
X425453D01*
G01D02*
Y493331D01*
G01X426384Y506047D02*
Y499847D01*
G01X437900Y498100D02*
X441100D01*
G01X432771Y532021D02*
X429671D01*
Y532941D01*
X429826Y533248D01*
X430188Y533478D01*
X430601Y533555D01*
X431014Y533478D01*
X431324Y533286D01*
X431479Y532941D01*
Y532021D01*
G01X432771Y535888D02*
X432719Y535581D01*
X432513Y535313D01*
X432203Y535083D01*
X431841Y534930D01*
X431428Y534853D01*
X431014D01*
X430601Y534930D01*
X430239Y535083D01*
X429929Y535313D01*
X429723Y535581D01*
X429671Y535888D01*
X429723Y536195D01*
X429929Y536463D01*
X430239Y536693D01*
X430601Y536846D01*
X431014Y536923D01*
X431428D01*
X431841Y536846D01*
X432203Y536693D01*
X432513Y536463D01*
X432719Y536195D01*
X432771Y535888D01*
G01X431944Y536195D02*
X432771Y536655D01*
G01Y538988D02*
X429671D01*
X430291Y538528D01*
G01X432771D02*
Y539448D01*
G01Y542088D02*
X429671D01*
X430291Y541628D01*
G01X432771D02*
Y542548D01*
G01X428177Y542950D02*
Y530326D01*
G01X438545Y580873D02*
Y607645D01*
G01X451931Y594259D02*
G02I-13386J0D01*
G01X431442Y609343D02*
Y612443D01*
X432362D01*
X432669Y612288D01*
X432899Y611926D01*
X432976Y611513D01*
X432899Y611100D01*
X432707Y610790D01*
X432362Y610635D01*
X431442D01*
G01X436152Y612185D02*
X435922Y612340D01*
X435654Y612443D01*
X435347D01*
X435002Y612288D01*
X434734Y612030D01*
X434542Y611720D01*
X434389Y611203D01*
X434351Y610738D01*
X434427Y610273D01*
X434542Y609963D01*
X434772Y609653D01*
X435041Y609446D01*
X435309Y609343D01*
X435577D01*
X435846Y609446D01*
X436076Y609601D01*
X436267Y609808D01*
G01X437566Y609963D02*
X437796Y609601D01*
X438102Y609395D01*
X438447Y609343D01*
X438754Y609395D01*
X439061Y609653D01*
X439252Y609963D01*
X439291Y610273D01*
X439214Y610635D01*
X438946Y610893D01*
X438677Y610996D01*
X438332D01*
G01X438677D02*
X438907Y611151D01*
X439099Y611410D01*
X439176Y611720D01*
X439099Y612030D01*
X438907Y612288D01*
X438562Y612443D01*
X438217Y612391D01*
X437872Y612185D01*
G01X440666Y609963D02*
X440896Y609601D01*
X441202Y609395D01*
X441547Y609343D01*
X441854Y609395D01*
X442161Y609653D01*
X442352Y609963D01*
X442391Y610273D01*
X442314Y610635D01*
X442046Y610893D01*
X441777Y610996D01*
X441432D01*
G01X441777D02*
X442007Y611151D01*
X442199Y611410D01*
X442276Y611720D01*
X442199Y612030D01*
X442007Y612288D01*
X441662Y612443D01*
X441317Y612391D01*
X440972Y612185D01*
G01X443881Y610635D02*
X444149Y610996D01*
X444379Y611203D01*
X444686Y611306D01*
X444954Y611203D01*
X445146Y610996D01*
X445299Y610686D01*
X445337Y610325D01*
X445299Y610015D01*
X445146Y609705D01*
X444916Y609446D01*
X444647Y609343D01*
X444341Y609446D01*
X444072Y609756D01*
X443919Y610221D01*
X443881Y610738D01*
X443957Y611410D01*
X444072Y611771D01*
X444264Y612133D01*
X444532Y612391D01*
X444801Y612443D01*
X445069Y612340D01*
X445261Y612081D01*
G01X435261Y685440D02*
Y679240D01*
G01D02*
X432061D01*
G01D02*
Y685440D01*
G01D02*
X435261D01*
G01X435709Y673327D02*
Y679527D01*
G01D02*
X438909D01*
G01D02*
Y673327D01*
G01D02*
X435709D01*
G01X425091Y682546D02*
X431291D01*
G01D02*
Y679346D01*
G01D02*
X425091D01*
G01D02*
Y682546D01*
G01X439155Y694071D02*
Y687871D01*
G01D02*
X435955D01*
G01D02*
Y689500D01*
G01Y694071D02*
X439155D01*
G01X435955Y692400D02*
Y694071D01*
G01Y698371D02*
Y704571D01*
G01X439155D02*
Y698371D01*
G01D02*
X435955D01*
G01X432898Y691507D02*
Y689653D01*
G01D02*
X431890D01*
G01X435955Y704571D02*
X439155D01*
G01X434498Y714892D02*
X440698D01*
G01Y711692D02*
X434498D01*
G01D02*
Y714892D01*
G01X439132Y711392D02*
Y705192D01*
G01D02*
X435932D01*
G01D02*
Y711392D01*
G01D02*
X439132D01*
G01X432105Y713275D02*
X432898D01*
G01D02*
Y710675D01*
G01Y704064D02*
Y702366D01*
G01X440326Y716507D02*
X434985D01*
G01X429317Y761353D02*
Y764453D01*
X430237D01*
X430544Y764298D01*
X430774Y763936D01*
X430851Y763523D01*
X430774Y763110D01*
X430582Y762800D01*
X430237Y762645D01*
X429317D01*
G01X432417Y764453D02*
Y761353D01*
X433951D01*
G01X435441Y761973D02*
X435671Y761611D01*
X435977Y761405D01*
X436322Y761353D01*
X436629Y761405D01*
X436936Y761663D01*
X437127Y761973D01*
X437166Y762283D01*
X437089Y762645D01*
X436821Y762903D01*
X436552Y763006D01*
X436207D01*
G01X436552D02*
X436782Y763161D01*
X436974Y763420D01*
X437051Y763730D01*
X436974Y764040D01*
X436782Y764298D01*
X436437Y764453D01*
X436092Y764401D01*
X435747Y764195D01*
G01X438656Y763936D02*
X438886Y764246D01*
X439154Y764401D01*
X439461Y764453D01*
X439844Y764350D01*
X440112Y764091D01*
X440189Y763781D01*
X440151Y763471D01*
X439997Y763213D01*
X439231Y762696D01*
X438886Y762335D01*
X438656Y761818D01*
X438579Y761353D01*
X440189D01*
G01X434985Y759815D02*
X440326D01*
G01X535800Y860722D02*
X433900D01*
G01X436100Y870789D02*
X431400D01*
G01X433541Y1004823D02*
Y1011023D01*
X436741D01*
Y1004823D01*
X433541D01*
G01X437282D02*
Y1011023D01*
X440482D01*
Y1004823D01*
X437282D01*
G01X426061D02*
Y1011023D01*
X429261D01*
Y1004823D01*
X426061D01*
G01X433345Y1016345D02*
X439545D01*
Y1013145D01*
X433345D01*
Y1016345D01*
G01X429801Y1004823D02*
Y1011023D01*
X433001D01*
Y1004823D01*
X429801D01*
G01X436746Y1033604D02*
Y1027404D01*
X433546D01*
Y1033604D01*
X436746D01*
G01X433341Y1020479D02*
X439541D01*
Y1017279D01*
X433341D01*
Y1020479D01*
G01X429266Y1033604D02*
Y1027404D01*
X426066D01*
Y1033604D01*
X429266D01*
G01X433341Y1024613D02*
X439541D01*
Y1021413D01*
X433341D01*
Y1024613D01*
G01X433006Y1033604D02*
Y1027404D01*
X429806D01*
Y1033604D01*
X433006D01*
G01X440486D02*
Y1027404D01*
X437286D01*
Y1033604D01*
X440486D01*
G01X434400Y1177706D02*
X584700D01*
G01X433400Y1167639D02*
X582393D01*
G01X440350Y1281300D02*
Y1278200D01*
G01X439468Y1281300D02*
X441232D01*
G01X442683Y1278200D02*
Y1281300D01*
X443603D01*
X443910Y1281145D01*
X444140Y1280783D01*
X444217Y1280370D01*
X444140Y1279957D01*
X443948Y1279647D01*
X443603Y1279492D01*
X442683D01*
G01X446550Y1278200D02*
Y1281300D01*
X446090Y1280680D01*
G01Y1278200D02*
X447010D01*
G01X448922Y1279492D02*
X449190Y1279853D01*
X449420Y1280060D01*
X449727Y1280163D01*
X449995Y1280060D01*
X450187Y1279853D01*
X450340Y1279543D01*
X450378Y1279182D01*
X450340Y1278872D01*
X450187Y1278562D01*
X449957Y1278303D01*
X449688Y1278200D01*
X449382Y1278303D01*
X449113Y1278613D01*
X448960Y1279078D01*
X448922Y1279595D01*
X448998Y1280267D01*
X449113Y1280628D01*
X449305Y1280990D01*
X449573Y1281248D01*
X449842Y1281300D01*
X450110Y1281197D01*
X450302Y1280938D01*
G01X428851Y1284594D02*
X425651D01*
G01X428851Y1290794D02*
Y1284594D01*
G01X425651Y1290794D02*
X428851D01*
G01X425651Y1284594D02*
Y1290794D01*
G01X435851Y1287294D02*
Y1284094D01*
G01X429651Y1287294D02*
X435851D01*
G01X429651Y1284094D02*
Y1287294D01*
G01X435851Y1284094D02*
X429651D01*
G01X435851Y1291294D02*
Y1288094D01*
G01X429651Y1291294D02*
X435851D01*
G01X429651Y1288094D02*
Y1291294D01*
G01X435851Y1288094D02*
X429651D01*
G01X425905Y1297178D02*
Y1322768D01*
G01X429900Y1297178D02*
X425905D01*
G01Y1322768D02*
X429900D01*
G01X424961Y1342019D02*
X428161D01*
G01X424961Y1335819D02*
Y1342019D01*
G01X428161Y1335819D02*
X424961D01*
G01X428161Y1342019D02*
Y1335819D01*
G01X428753Y1356068D02*
Y1359168D01*
G01X430363D02*
Y1356068D01*
G01Y1357618D02*
X428753D01*
G01X431930Y1358651D02*
X432160Y1358961D01*
X432428Y1359116D01*
X432735Y1359168D01*
X433118Y1359065D01*
X433386Y1358806D01*
X433463Y1358496D01*
X433425Y1358186D01*
X433271Y1357928D01*
X432505Y1357411D01*
X432160Y1357050D01*
X431930Y1356533D01*
X431853Y1356068D01*
X433463D01*
G01X435758D02*
Y1359168D01*
X435298Y1358548D01*
G01Y1356068D02*
X436218D01*
G01X432964Y1539911D02*
Y1536503D01*
G01Y1554219D02*
Y1550811D01*
G01X442717Y1575796D02*
X438474Y1580039D01*
G01D02*
X442717Y1584282D01*
G01X436900Y1602600D02*
Y1605800D01*
G01X443100Y1602600D02*
X436900D01*
G01Y1605800D02*
X443100D01*
G01X436900Y1598600D02*
Y1601800D01*
G01X443100Y1598600D02*
X436900D01*
G01Y1601800D02*
X443100D01*
G01X431787Y1609100D02*
X434009D01*
X434474Y1609253D01*
X434784Y1609560D01*
X434887Y1609943D01*
X434784Y1610326D01*
X434474Y1610633D01*
X434009Y1610786D01*
X431787D01*
G01X434887Y1613043D02*
X431787D01*
X432407Y1612583D01*
G01X434887D02*
Y1613503D01*
G01X431787Y1616143D02*
X431890Y1615836D01*
X432149Y1615606D01*
X432459Y1615453D01*
X432872Y1615338D01*
X433337Y1615300D01*
X433802Y1615338D01*
X434215Y1615453D01*
X434525Y1615606D01*
X434784Y1615836D01*
X434887Y1616143D01*
X434784Y1616450D01*
X434525Y1616680D01*
X434215Y1616833D01*
X433802Y1616948D01*
X433337Y1616986D01*
X432872Y1616948D01*
X432459Y1616833D01*
X432149Y1616680D01*
X431890Y1616450D01*
X431787Y1616143D01*
G01X426233Y1602882D02*
X428136D01*
G01D02*
Y1604785D01*
G01X433900Y1625200D02*
Y1629800D01*
G01X444100Y1625200D02*
X433900D01*
G01X428136Y1620665D02*
Y1622568D01*
G01D02*
X426233D01*
G01X426900Y1638600D02*
X430100D01*
G01X426900Y1632400D02*
Y1638600D01*
G01X430100Y1632400D02*
X426900D01*
G01X430100Y1638600D02*
Y1632400D01*
G01X431560Y1630800D02*
Y1637200D01*
G01D02*
X444440D01*
G01Y1630800D02*
X431560D01*
G01X433900Y1629800D02*
X444100D01*
G01X436705Y1653175D02*
X436897Y1652865D01*
X437127Y1652658D01*
X437395Y1652555D01*
X437702Y1652658D01*
X437932Y1652865D01*
X438162Y1653175D01*
X438239Y1653588D01*
Y1655655D01*
G01X440572Y1652555D02*
Y1655655D01*
X440112Y1655035D01*
G01Y1652555D02*
X441032D01*
G01X442944Y1655138D02*
X443174Y1655448D01*
X443442Y1655603D01*
X443749Y1655655D01*
X444132Y1655552D01*
X444400Y1655293D01*
X444477Y1654983D01*
X444439Y1654673D01*
X444285Y1654415D01*
X443519Y1653898D01*
X443174Y1653537D01*
X442944Y1653020D01*
X442867Y1652555D01*
X444477D01*
G01X445929Y1653175D02*
X446159Y1652813D01*
X446465Y1652607D01*
X446810Y1652555D01*
X447117Y1652607D01*
X447424Y1652865D01*
X447615Y1653175D01*
X447654Y1653485D01*
X447577Y1653847D01*
X447309Y1654105D01*
X447040Y1654208D01*
X446695D01*
G01X447040D02*
X447270Y1654363D01*
X447462Y1654622D01*
X447539Y1654932D01*
X447462Y1655242D01*
X447270Y1655500D01*
X446925Y1655655D01*
X446580Y1655603D01*
X446235Y1655397D01*
G01X432100Y1646800D02*
Y1642200D01*
G01X427165Y1707500D02*
Y1656969D01*
G01D02*
X454921D01*
G01X427165Y1736120D02*
Y1722500D01*
G01X440273Y81800D02*
Y75600D01*
G01X451097Y77962D02*
Y75740D01*
X451250Y75275D01*
X451557Y74965D01*
X451940Y74862D01*
X452323Y74965D01*
X452630Y75275D01*
X452783Y75740D01*
Y77962D01*
G01X454312Y77445D02*
X454542Y77755D01*
X454810Y77910D01*
X455117Y77962D01*
X455500Y77859D01*
X455768Y77600D01*
X455845Y77290D01*
X455807Y76980D01*
X455653Y76722D01*
X454887Y76205D01*
X454542Y75844D01*
X454312Y75327D01*
X454235Y74862D01*
X455845D01*
G01X458063D02*
X458140Y75534D01*
X458255Y76102D01*
X458408Y76619D01*
X458600Y77187D01*
X458907Y77962D01*
X457373D01*
G01X460397Y75482D02*
X460627Y75120D01*
X460933Y74914D01*
X461278Y74862D01*
X461585Y74914D01*
X461892Y75172D01*
X462083Y75482D01*
X462122Y75792D01*
X462045Y76154D01*
X461777Y76412D01*
X461508Y76515D01*
X461163D01*
G01X461508D02*
X461738Y76670D01*
X461930Y76929D01*
X462007Y77239D01*
X461930Y77549D01*
X461738Y77807D01*
X461393Y77962D01*
X461048Y77910D01*
X460703Y77704D01*
G01X459269Y72359D02*
X451538D01*
G01D02*
X445695Y66516D01*
G01D02*
X439852Y72359D01*
G01X444273Y88800D02*
Y82600D01*
G01D02*
X441073D01*
G01D02*
Y88800D01*
G01D02*
X444273D01*
G01X440273D02*
Y82600D01*
G01X439597Y165225D02*
Y159025D01*
G01Y158225D02*
Y152025D01*
G01X451597Y165225D02*
Y159025D01*
G01D02*
X448397D01*
G01D02*
Y165225D01*
G01D02*
X451597D01*
G01X440397Y159025D02*
Y165225D01*
G01D02*
X443597D01*
G01D02*
Y159025D01*
G01D02*
X440397D01*
G01X447597Y165225D02*
Y159025D01*
G01D02*
X444397D01*
G01D02*
Y165225D01*
G01D02*
X447597D01*
G01X451597Y158225D02*
Y152025D01*
G01D02*
X448397D01*
G01D02*
Y158225D01*
G01D02*
X451597D01*
G01X447597D02*
Y152025D01*
G01D02*
X444397D01*
G01D02*
Y158225D01*
G01D02*
X447597D01*
G01X455597Y159025D02*
X452397D01*
G01D02*
Y165225D01*
G01D02*
X455597D01*
G01X440899Y211220D02*
Y205020D01*
G01X444899Y211220D02*
Y205020D01*
G01D02*
X441699D01*
G01D02*
Y211220D01*
G01X448899D02*
Y205020D01*
G01D02*
X445699D01*
G01D02*
Y211220D01*
G01X455899Y205020D02*
X449699D01*
G01D02*
Y208220D01*
G01D02*
X455899D01*
G01Y209020D02*
X449699D01*
G01D02*
Y212220D01*
G01X448899Y219171D02*
Y212971D01*
G01D02*
X445699D01*
G01D02*
Y219171D01*
G01D02*
X448899D01*
G01X449699Y212971D02*
Y219171D01*
G01D02*
X452899D01*
G01D02*
Y212971D01*
G01D02*
X449699D01*
G01X444899Y219171D02*
Y212971D01*
G01D02*
X441699D01*
G01D02*
Y219171D01*
G01D02*
X444899D01*
G01X441699Y211220D02*
X444899D01*
G01X445699D02*
X448899D01*
G01X449699Y212220D02*
X455899D01*
G01X440899Y219171D02*
Y212971D01*
G01X448731Y241642D02*
Y221564D01*
G01X440415Y238870D02*
X443187Y241642D01*
G01D02*
X448731D01*
G01X454005Y272511D02*
Y269311D01*
G01D02*
X447805D01*
G01D02*
Y272511D01*
G01X455952Y281718D02*
X449752D01*
G01D02*
Y284918D01*
G01X447805Y272511D02*
X454005D01*
G01X449752Y284918D02*
X455952D01*
G01X459871Y297161D02*
X453871D01*
G01D02*
Y309161D01*
G01X458268Y286158D02*
X453668D01*
G01X458268Y296158D02*
X453668D01*
G01X453768Y286158D02*
X453668D01*
G01D02*
Y296158D01*
G01X453871Y309161D02*
X459871D01*
G01X441900Y484900D02*
Y491100D01*
G01D02*
X445100D01*
G01D02*
Y484900D01*
G01D02*
X441900D01*
G01X441100Y491100D02*
Y484900D01*
G01Y498100D02*
Y491900D01*
G01X451072Y487594D02*
Y499406D01*
G01X464928Y487594D02*
X451072D01*
G01X450513Y505878D02*
Y503656D01*
X450666Y503191D01*
X450973Y502881D01*
X451356Y502778D01*
X451739Y502881D01*
X452046Y503191D01*
X452199Y503656D01*
Y505878D01*
G01X453728Y504070D02*
X453996Y504431D01*
X454226Y504638D01*
X454533Y504741D01*
X454801Y504638D01*
X454993Y504431D01*
X455146Y504121D01*
X455184Y503760D01*
X455146Y503450D01*
X454993Y503140D01*
X454763Y502881D01*
X454494Y502778D01*
X454188Y502881D01*
X453919Y503191D01*
X453766Y503656D01*
X453728Y504173D01*
X453804Y504845D01*
X453919Y505206D01*
X454111Y505568D01*
X454379Y505826D01*
X454648Y505878D01*
X454916Y505775D01*
X455108Y505516D01*
G01X457556Y505878D02*
X457249Y505775D01*
X457019Y505516D01*
X456866Y505206D01*
X456751Y504793D01*
X456713Y504328D01*
X456751Y503863D01*
X456866Y503450D01*
X457019Y503140D01*
X457249Y502881D01*
X457556Y502778D01*
X457863Y502881D01*
X458093Y503140D01*
X458246Y503450D01*
X458361Y503863D01*
X458399Y504328D01*
X458361Y504793D01*
X458246Y505206D01*
X458093Y505516D01*
X457863Y505775D01*
X457556Y505878D01*
G01X460656D02*
X460349Y505775D01*
X460119Y505516D01*
X459966Y505206D01*
X459851Y504793D01*
X459813Y504328D01*
X459851Y503863D01*
X459966Y503450D01*
X460119Y503140D01*
X460349Y502881D01*
X460656Y502778D01*
X460963Y502881D01*
X461193Y503140D01*
X461346Y503450D01*
X461461Y503863D01*
X461499Y504328D01*
X461461Y504793D01*
X461346Y505206D01*
X461193Y505516D01*
X460963Y505775D01*
X460656Y505878D01*
G01X463028Y504070D02*
X463296Y504431D01*
X463526Y504638D01*
X463833Y504741D01*
X464101Y504638D01*
X464293Y504431D01*
X464446Y504121D01*
X464484Y503760D01*
X464446Y503450D01*
X464293Y503140D01*
X464063Y502881D01*
X463794Y502778D01*
X463488Y502881D01*
X463219Y503191D01*
X463066Y503656D01*
X463028Y504173D01*
X463104Y504845D01*
X463219Y505206D01*
X463411Y505568D01*
X463679Y505826D01*
X463948Y505878D01*
X464216Y505775D01*
X464408Y505516D01*
G01X451072Y499406D02*
X464928D01*
G01X446824Y655450D02*
Y661650D01*
G01X450024D02*
Y655450D01*
G01D02*
X446824D01*
G01X454066Y661650D02*
Y655450D01*
G01D02*
X450866D01*
G01D02*
Y661650D01*
G01X446008Y647096D02*
Y650196D01*
X446928D01*
X447235Y650041D01*
X447465Y649679D01*
X447542Y649266D01*
X447465Y648853D01*
X447273Y648543D01*
X446928Y648388D01*
X446008D01*
G01X449032Y650196D02*
Y647974D01*
X449185Y647509D01*
X449492Y647199D01*
X449875Y647096D01*
X450258Y647199D01*
X450565Y647509D01*
X450718Y647974D01*
Y650196D01*
G01X452132Y647716D02*
X452362Y647354D01*
X452668Y647148D01*
X453013Y647096D01*
X453320Y647148D01*
X453627Y647406D01*
X453818Y647716D01*
X453857Y648026D01*
X453780Y648388D01*
X453512Y648646D01*
X453243Y648749D01*
X452898D01*
G01X453243D02*
X453473Y648904D01*
X453665Y649163D01*
X453742Y649473D01*
X453665Y649783D01*
X453473Y650041D01*
X453128Y650196D01*
X452783Y650144D01*
X452438Y649938D01*
G01X456075Y650196D02*
X455768Y650093D01*
X455538Y649834D01*
X455385Y649524D01*
X455270Y649111D01*
X455232Y648646D01*
X455270Y648181D01*
X455385Y647768D01*
X455538Y647458D01*
X455768Y647199D01*
X456075Y647096D01*
X456382Y647199D01*
X456612Y647458D01*
X456765Y647768D01*
X456880Y648181D01*
X456918Y648646D01*
X456880Y649111D01*
X456765Y649524D01*
X456612Y649834D01*
X456382Y650093D01*
X456075Y650196D01*
G01X446824Y661650D02*
X450024D01*
G01X450866D02*
X454066D01*
G01X446345Y665053D02*
X445612D01*
G01D02*
Y667244D01*
G01X439537Y673313D02*
Y679513D01*
G01D02*
X442737D01*
G01D02*
Y673313D01*
G01D02*
X439537D01*
G01X445612Y686075D02*
Y688675D01*
G01D02*
X446405D01*
G01X442326Y735200D02*
Y691892D01*
G01D02*
X447667D01*
G01X440698Y714892D02*
Y711692D01*
G01X440326Y759815D02*
Y716507D01*
G01X447667Y735200D02*
X442326D01*
G01X504500Y870789D02*
X441700D01*
G01X448502Y1004823D02*
Y1011023D01*
X451702D01*
Y1004823D01*
X448502D01*
G01X442199Y1016345D02*
X448399D01*
Y1013145D01*
X442199D01*
Y1016345D01*
G01X441022Y1004823D02*
Y1011023D01*
X444222D01*
Y1004823D01*
X441022D01*
G01X444762D02*
Y1011023D01*
X447962D01*
Y1004823D01*
X444762D01*
G01X452242D02*
Y1011023D01*
X455442D01*
Y1004823D01*
X452242D01*
G01X452435Y1016345D02*
X458635D01*
Y1013145D01*
X452435D01*
Y1016345D01*
G01X451707Y1033604D02*
Y1027404D01*
X448507D01*
Y1033604D01*
X451707D01*
G01X444226D02*
Y1027404D01*
X441026D01*
Y1033604D01*
X444226D01*
G01X455447D02*
Y1027404D01*
X452247D01*
Y1033604D01*
X455447D01*
G01X442199Y1020479D02*
X448399D01*
Y1017279D01*
X442199D01*
Y1020479D01*
G01X452435D02*
X458635D01*
Y1017279D01*
X452435D01*
Y1020479D01*
G01X447966Y1033604D02*
Y1027404D01*
X444766D01*
Y1033604D01*
X447966D01*
G01X442199Y1024613D02*
X448399D01*
Y1021413D01*
X442199D01*
Y1024613D01*
G01X452435D02*
X458635D01*
Y1021413D01*
X452435D01*
Y1024613D01*
G01X455933Y1297356D02*
X452833D01*
Y1298276D01*
X452988Y1298583D01*
X453350Y1298813D01*
X453763Y1298890D01*
X454176Y1298813D01*
X454486Y1298621D01*
X454641Y1298276D01*
Y1297356D01*
G01X452833Y1300456D02*
X455933D01*
Y1301990D01*
G01X455313Y1303480D02*
X455675Y1303710D01*
X455881Y1304016D01*
X455933Y1304361D01*
X455881Y1304668D01*
X455623Y1304975D01*
X455313Y1305166D01*
X455003Y1305205D01*
X454641Y1305128D01*
X454383Y1304860D01*
X454280Y1304591D01*
Y1304246D01*
G01Y1304591D02*
X454125Y1304821D01*
X453866Y1305013D01*
X453556Y1305090D01*
X453246Y1305013D01*
X452988Y1304821D01*
X452833Y1304476D01*
X452885Y1304131D01*
X453091Y1303786D01*
G01X455571Y1306771D02*
X455830Y1307040D01*
X455933Y1307346D01*
X455830Y1307653D01*
X455520Y1307921D01*
X455055Y1308113D01*
X454590Y1308190D01*
X454021D01*
X453556Y1308113D01*
X453143Y1307921D01*
X452936Y1307691D01*
X452833Y1307423D01*
X452936Y1307116D01*
X453143Y1306886D01*
X453453Y1306733D01*
X453866Y1306656D01*
X454228Y1306733D01*
X454590Y1306925D01*
X454796Y1307155D01*
X454848Y1307423D01*
X454745Y1307730D01*
X454486Y1307960D01*
X454021Y1308190D01*
G01X451495Y1297178D02*
X447500D01*
G01X451495Y1322768D02*
Y1297178D01*
G01X447500Y1322768D02*
X451495D01*
G01X441606Y1507451D02*
Y1524300D01*
G01X446300Y1507451D02*
X441606D01*
G01Y1528200D02*
Y1542491D01*
G01D02*
X448000D01*
G01X453783Y1567115D02*
Y1564893D01*
X453936Y1564428D01*
X454243Y1564118D01*
X454626Y1564015D01*
X455009Y1564118D01*
X455316Y1564428D01*
X455469Y1564893D01*
Y1567115D01*
G01X458186Y1564015D02*
Y1567115D01*
X456768Y1564893D01*
X458684D01*
G01X460098Y1566598D02*
X460328Y1566908D01*
X460596Y1567063D01*
X460903Y1567115D01*
X461286Y1567012D01*
X461554Y1566753D01*
X461631Y1566443D01*
X461593Y1566133D01*
X461439Y1565875D01*
X460673Y1565358D01*
X460328Y1564997D01*
X460098Y1564480D01*
X460021Y1564015D01*
X461631D01*
G01X443302Y1563604D02*
X445524D01*
X445989Y1563757D01*
X446299Y1564064D01*
X446402Y1564447D01*
X446299Y1564830D01*
X445989Y1565137D01*
X445524Y1565290D01*
X443302D01*
G01X446402Y1567547D02*
X443302D01*
X443922Y1567087D01*
G01X446402D02*
Y1568007D01*
G01X446040Y1569995D02*
X446299Y1570264D01*
X446402Y1570570D01*
X446299Y1570877D01*
X445989Y1571145D01*
X445524Y1571337D01*
X445059Y1571414D01*
X444490D01*
X444025Y1571337D01*
X443612Y1571145D01*
X443405Y1570915D01*
X443302Y1570647D01*
X443405Y1570340D01*
X443612Y1570110D01*
X443922Y1569957D01*
X444335Y1569880D01*
X444697Y1569957D01*
X445059Y1570149D01*
X445265Y1570379D01*
X445317Y1570647D01*
X445214Y1570954D01*
X444955Y1571184D01*
X444490Y1571414D01*
G01X450218Y1575076D02*
Y1585190D01*
G01X458358Y1575076D02*
X450218D01*
G01X442717Y1572839D02*
Y1575796D01*
G01X450218Y1585190D02*
X458358D01*
G01X442717Y1584282D02*
Y1587239D01*
G01X443100Y1605800D02*
Y1602600D01*
G01Y1601800D02*
Y1598600D01*
G01X440400Y1621100D02*
Y1624300D01*
G01X446600Y1621100D02*
X440400D01*
G01X446600Y1624300D02*
Y1621100D01*
G01X440400Y1624300D02*
X446600D01*
G01X440400Y1617100D02*
Y1620300D01*
G01X446600Y1617100D02*
X440400D01*
G01X446600Y1620300D02*
Y1617100D01*
G01X440400Y1620300D02*
X446600D01*
G01X444100Y1629800D02*
Y1625200D01*
G01X448253Y1639331D02*
X458747D01*
G01X455400Y1630669D02*
X453500Y1632869D01*
G01D02*
X451600Y1630669D01*
G01D02*
X448253D01*
G01D02*
Y1639331D01*
G01X444440Y1630800D02*
Y1637200D01*
G01X451485Y1642333D02*
Y1648533D01*
G01D02*
X454685D01*
G01Y1642333D02*
X451485D01*
G01X445976Y1649082D02*
X449176D01*
G01X445976Y1642882D02*
Y1649082D01*
G01X449176Y1642882D02*
X445976D01*
G01X449176Y1649082D02*
Y1642882D01*
G01X441994Y1649127D02*
X445194D01*
G01X441994Y1642927D02*
Y1649127D01*
G01X445194Y1642927D02*
X441994D01*
G01X445194Y1649127D02*
Y1642927D01*
G01X462000Y-630638D02*
Y-622638D01*
X460800Y-624238D01*
G01Y-630638D02*
X463200D01*
G01X469800D02*
X470000Y-628905D01*
X470300Y-627438D01*
X470700Y-626105D01*
X471200Y-624638D01*
X472000Y-622638D01*
X468000D01*
G01X478000Y-630905D02*
X477800Y-630771D01*
Y-630505D01*
X478000Y-630371D01*
X478200Y-630505D01*
Y-630771D01*
X478000Y-630905D01*
G01X484100Y-623971D02*
X484700Y-623171D01*
X485400Y-622771D01*
X486200Y-622638D01*
X487200Y-622905D01*
X487900Y-623571D01*
X488100Y-624371D01*
X488000Y-625172D01*
X487600Y-625838D01*
X485600Y-627171D01*
X484700Y-628105D01*
X484100Y-629438D01*
X483900Y-630638D01*
X488100D01*
G01X459269Y52673D02*
Y72359D01*
G01X461128Y71616D02*
X467328D01*
G01D02*
Y68416D01*
G01D02*
X461128D01*
G01D02*
Y71616D01*
G01X462003Y108201D02*
Y106094D01*
G01D02*
X459896D01*
G01X465000Y147475D02*
X468200D01*
G01X465000Y141275D02*
Y147475D01*
G01X468200D02*
Y141275D01*
G01D02*
X465000D01*
G01X459896Y141920D02*
X462003D01*
G01D02*
Y139813D01*
G01X455597Y165225D02*
Y159025D01*
G01X456397D02*
Y165225D01*
G01D02*
X459597D01*
G01D02*
Y159025D01*
G01D02*
X456397D01*
G01X463597Y165225D02*
Y159025D01*
G01D02*
X460397D01*
G01D02*
Y165225D01*
G01D02*
X463597D01*
G01X464397Y159025D02*
Y165225D01*
G01D02*
X467597D01*
G01D02*
Y159025D01*
G01D02*
X464397D01*
G01X471597D02*
X468397D01*
G01D02*
Y165225D01*
G01D02*
X471597D01*
G01X470099Y209020D02*
X463899D01*
G01D02*
Y212220D01*
G01X470099Y205020D02*
X463899D01*
G01D02*
Y208220D01*
G01D02*
X470099D01*
G01X455899D02*
Y205020D01*
G01Y212220D02*
Y209020D01*
G01X460331Y213578D02*
Y219778D01*
G01D02*
X463531D01*
G01D02*
Y213578D01*
G01D02*
X460331D01*
G01X459531Y219778D02*
Y213578D01*
G01D02*
X456331D01*
G01D02*
Y219778D01*
G01D02*
X459531D01*
G01X470496Y221164D02*
X464296D01*
G01D02*
Y224364D01*
G01D02*
X470496D01*
G01X463899Y212220D02*
X470099D01*
G01X456515Y239428D02*
Y245628D01*
G01X459715D02*
Y239428D01*
G01D02*
X456515D01*
G01X470496Y238164D02*
X464296D01*
G01D02*
Y241364D01*
G01Y229364D02*
X470496D01*
G01Y226164D02*
X464296D01*
G01D02*
Y229364D01*
G01Y233364D02*
X470496D01*
G01Y230164D02*
X464296D01*
G01D02*
Y233364D01*
G01X470496Y234164D02*
X464296D01*
G01D02*
Y237364D01*
G01D02*
X470496D01*
G01X456515Y245628D02*
X459715D01*
G01X464296Y241364D02*
X470496D01*
G01Y242164D02*
X464296D01*
G01D02*
Y245364D01*
G01D02*
X470496D01*
G01X464296Y249364D02*
X470496D01*
G01Y246164D02*
X464296D01*
G01D02*
Y249364D01*
G01X455952Y284918D02*
Y281718D01*
G01X467299Y290160D02*
Y283960D01*
G01D02*
X464099D01*
G01D02*
Y290160D01*
G01X467438Y299038D02*
Y305238D01*
G01X470638Y299038D02*
X467438D01*
G01X464099Y290160D02*
X467299D01*
G01X466751Y309101D02*
Y297101D01*
G01D02*
X460751D01*
G01D02*
Y309101D01*
G01X459871Y309161D02*
Y297161D01*
G01X458268Y296158D02*
Y286158D01*
G01X467438Y305238D02*
X470638D01*
G01X460751Y309101D02*
X466751D01*
G01X459386Y315081D02*
Y318181D01*
X460306D01*
X460613Y318026D01*
X460843Y317664D01*
X460920Y317251D01*
X460843Y316838D01*
X460651Y316528D01*
X460306Y316373D01*
X459386D01*
G01X462410Y318181D02*
Y315959D01*
X462563Y315494D01*
X462870Y315184D01*
X463253Y315081D01*
X463636Y315184D01*
X463943Y315494D01*
X464096Y315959D01*
Y318181D01*
G01X465625Y316373D02*
X465893Y316734D01*
X466123Y316941D01*
X466430Y317044D01*
X466698Y316941D01*
X466890Y316734D01*
X467043Y316424D01*
X467081Y316063D01*
X467043Y315753D01*
X466890Y315443D01*
X466660Y315184D01*
X466391Y315081D01*
X466085Y315184D01*
X465816Y315494D01*
X465663Y315959D01*
X465625Y316476D01*
X465701Y317148D01*
X465816Y317509D01*
X466008Y317871D01*
X466276Y318129D01*
X466545Y318181D01*
X466813Y318078D01*
X467005Y317819D01*
G01X469453Y318181D02*
X469146Y318078D01*
X468916Y317819D01*
X468763Y317509D01*
X468648Y317096D01*
X468610Y316631D01*
X468648Y316166D01*
X468763Y315753D01*
X468916Y315443D01*
X469146Y315184D01*
X469453Y315081D01*
X469760Y315184D01*
X469990Y315443D01*
X470143Y315753D01*
X470258Y316166D01*
X470296Y316631D01*
X470258Y317096D01*
X470143Y317509D01*
X469990Y317819D01*
X469760Y318078D01*
X469453Y318181D01*
G01X472553D02*
X472246Y318078D01*
X472016Y317819D01*
X471863Y317509D01*
X471748Y317096D01*
X471710Y316631D01*
X471748Y316166D01*
X471863Y315753D01*
X472016Y315443D01*
X472246Y315184D01*
X472553Y315081D01*
X472860Y315184D01*
X473090Y315443D01*
X473243Y315753D01*
X473358Y316166D01*
X473396Y316631D01*
X473358Y317096D01*
X473243Y317509D01*
X473090Y317819D01*
X472860Y318078D01*
X472553Y318181D01*
G01X475653Y315081D02*
Y318181D01*
X475193Y317561D01*
G01Y315081D02*
X476113D01*
G01X466900Y488400D02*
Y494600D01*
G01X470100Y488400D02*
X466900D01*
G01X464928Y499406D02*
Y487594D01*
G01X466900Y494600D02*
X470100D01*
G01X454770Y595831D02*
Y571815D01*
G01D02*
X460881D01*
G01Y595831D02*
X454770D01*
G01X467661Y660840D02*
Y654640D01*
G01D02*
X464461D01*
G01D02*
Y660840D01*
G01X468281Y646937D02*
Y653137D01*
G01D02*
X471481D01*
G01Y646937D02*
X468281D01*
G01X463691Y657946D02*
Y654746D01*
G01D02*
X457491D01*
G01D02*
Y657946D01*
G01X464461Y660840D02*
X467661D01*
G01X471555Y663271D02*
X468355D01*
G01D02*
Y665000D01*
G01Y669471D02*
X471555D01*
G01X468355Y667500D02*
Y669471D01*
G01X457491Y657946D02*
X463691D01*
G01X465298Y666907D02*
Y665053D01*
G01D02*
X464290D01*
G01X468355Y673771D02*
Y679971D01*
G01D02*
X471555D01*
G01Y673771D02*
X468355D01*
G01X473098Y687092D02*
X466898D01*
G01D02*
Y690292D01*
G01X471532Y680592D02*
X468332D01*
G01D02*
Y686792D01*
G01D02*
X471532D01*
G01X465298Y688675D02*
Y686075D01*
G01Y679464D02*
Y677766D01*
G01X466898Y690292D02*
X473098D01*
G01X464505Y688675D02*
X465298D01*
G01X471854Y691892D02*
X466513D01*
G01X460549Y736758D02*
Y739858D01*
X461469D01*
X461776Y739703D01*
X462006Y739341D01*
X462083Y738928D01*
X462006Y738515D01*
X461814Y738205D01*
X461469Y738050D01*
X460549D01*
G01X463649Y739858D02*
Y736758D01*
X465183D01*
G01X466673Y737378D02*
X466903Y737016D01*
X467209Y736810D01*
X467554Y736758D01*
X467861Y736810D01*
X468168Y737068D01*
X468359Y737378D01*
X468398Y737688D01*
X468321Y738050D01*
X468053Y738308D01*
X467784Y738411D01*
X467439D01*
G01X467784D02*
X468014Y738566D01*
X468206Y738825D01*
X468283Y739135D01*
X468206Y739445D01*
X468014Y739703D01*
X467669Y739858D01*
X467324Y739806D01*
X466979Y739600D01*
G01X469773Y737223D02*
X470003Y736965D01*
X470271Y736810D01*
X470616Y736758D01*
X470961Y736861D01*
X471229Y737068D01*
X471421Y737430D01*
X471459Y737843D01*
X471383Y738256D01*
X471191Y738515D01*
X470923Y738721D01*
X470654Y738773D01*
X470386Y738721D01*
X470041Y738515D01*
X470156Y739858D01*
X471191D01*
G01X466513Y735200D02*
X471854D01*
G01X468417Y1034962D02*
Y1003466D01*
G01X455982Y1004823D02*
Y1011023D01*
X459182D01*
Y1004823D01*
X455982D01*
G01X467256Y1012004D02*
X461056D01*
Y1015204D01*
X467256D01*
Y1012004D01*
G01Y1008264D02*
X461056D01*
Y1011464D01*
X467256D01*
Y1008264D01*
G01Y1004523D02*
X461056D01*
Y1007723D01*
X467256D01*
Y1004523D01*
G01X459187Y1033604D02*
Y1027404D01*
X455987D01*
Y1033604D01*
X459187D01*
G01X467256Y1015744D02*
X461056D01*
Y1018944D01*
X467256D01*
Y1015744D01*
G01Y1023224D02*
X461056D01*
Y1026424D01*
X467256D01*
Y1023224D01*
G01Y1026964D02*
X461056D01*
Y1030164D01*
X467256D01*
Y1026964D01*
G01Y1019484D02*
X461056D01*
Y1022684D01*
X467256D01*
Y1019484D01*
G01Y1030704D02*
X461056D01*
Y1033904D01*
X467256D01*
Y1030704D01*
G01X467588Y1406290D02*
X461588D01*
G01D02*
Y1412290D01*
G01X471754Y1440359D02*
X472127Y1440734D01*
X472407Y1441359D01*
X472594Y1442234D01*
X472407Y1442984D01*
X472034Y1443484D01*
X471380Y1443859D01*
X468860D01*
Y1436359D01*
X471940D01*
X472594Y1436859D01*
X472967Y1437609D01*
X473154Y1438484D01*
X472967Y1439359D01*
X472407Y1440109D01*
X471754Y1440359D01*
X468860D01*
G01X477387Y1443859D02*
X479627D01*
G01X478507D02*
Y1436359D01*
G01X477387D02*
X479627D01*
G01X486007D02*
X485260Y1436484D01*
X484607Y1436984D01*
X484047Y1437734D01*
X483674Y1438609D01*
X483487Y1439609D01*
Y1440609D01*
X483674Y1441609D01*
X484047Y1442484D01*
X484607Y1443234D01*
X485260Y1443734D01*
X486007Y1443859D01*
X486754Y1443734D01*
X487407Y1443234D01*
X487967Y1442484D01*
X488340Y1441609D01*
X488527Y1440609D01*
Y1439609D01*
X488340Y1438609D01*
X487967Y1437734D01*
X487407Y1436984D01*
X486754Y1436484D01*
X486007Y1436359D01*
G01X491547Y1437359D02*
X492294Y1436734D01*
X493134Y1436359D01*
X493880D01*
X494627Y1436734D01*
X495187Y1437359D01*
X495467Y1438234D01*
X495280Y1439109D01*
X494814Y1439859D01*
X493974Y1440359D01*
X492854Y1440609D01*
X492200Y1441109D01*
X491920Y1441984D01*
X492107Y1442859D01*
X492574Y1443484D01*
X493227Y1443859D01*
X493880D01*
X494534Y1443609D01*
X495094Y1442984D01*
G01X461588Y1441629D02*
Y1447629D01*
G01D02*
X467588D01*
G01X462464Y1558092D02*
Y1555870D01*
X462617Y1555405D01*
X462924Y1555095D01*
X463307Y1554992D01*
X463690Y1555095D01*
X463997Y1555405D01*
X464150Y1555870D01*
Y1558092D01*
G01X465679Y1556284D02*
X465947Y1556645D01*
X466177Y1556852D01*
X466484Y1556955D01*
X466752Y1556852D01*
X466944Y1556645D01*
X467097Y1556335D01*
X467135Y1555974D01*
X467097Y1555664D01*
X466944Y1555354D01*
X466714Y1555095D01*
X466445Y1554992D01*
X466139Y1555095D01*
X465870Y1555405D01*
X465717Y1555870D01*
X465679Y1556387D01*
X465755Y1557059D01*
X465870Y1557420D01*
X466062Y1557782D01*
X466330Y1558040D01*
X466599Y1558092D01*
X466867Y1557989D01*
X467059Y1557730D01*
G01X469507Y1558092D02*
X469200Y1557989D01*
X468970Y1557730D01*
X468817Y1557420D01*
X468702Y1557007D01*
X468664Y1556542D01*
X468702Y1556077D01*
X468817Y1555664D01*
X468970Y1555354D01*
X469200Y1555095D01*
X469507Y1554992D01*
X469814Y1555095D01*
X470044Y1555354D01*
X470197Y1555664D01*
X470312Y1556077D01*
X470350Y1556542D01*
X470312Y1557007D01*
X470197Y1557420D01*
X470044Y1557730D01*
X469814Y1557989D01*
X469507Y1558092D01*
G01X472607Y1554992D02*
Y1558092D01*
X472147Y1557472D01*
G01Y1554992D02*
X473067D01*
G01X475630D02*
X475707Y1555664D01*
X475822Y1556232D01*
X475975Y1556749D01*
X476167Y1557317D01*
X476474Y1558092D01*
X474940D01*
G01X458358Y1585190D02*
Y1575076D01*
G01X467778Y1631384D02*
X467726Y1631077D01*
X467520Y1630809D01*
X467210Y1630579D01*
X466848Y1630426D01*
X466435Y1630349D01*
X466021D01*
X465608Y1630426D01*
X465246Y1630579D01*
X464936Y1630809D01*
X464730Y1631077D01*
X464678Y1631384D01*
X464730Y1631691D01*
X464936Y1631959D01*
X465246Y1632189D01*
X465608Y1632342D01*
X466021Y1632419D01*
X466435D01*
X466848Y1632342D01*
X467210Y1632189D01*
X467520Y1631959D01*
X467726Y1631691D01*
X467778Y1631384D01*
G01X466951Y1631691D02*
X467778Y1632151D01*
G01Y1634407D02*
X467106Y1634484D01*
X466538Y1634599D01*
X466021Y1634752D01*
X465453Y1634944D01*
X464678Y1635251D01*
Y1633717D01*
G01X467313Y1636741D02*
X467571Y1636971D01*
X467726Y1637239D01*
X467778Y1637584D01*
X467675Y1637929D01*
X467468Y1638197D01*
X467106Y1638389D01*
X466693Y1638427D01*
X466280Y1638351D01*
X466021Y1638159D01*
X465815Y1637891D01*
X465763Y1637622D01*
X465815Y1637354D01*
X466021Y1637009D01*
X464678Y1637124D01*
Y1638159D01*
G01X458747Y1639331D02*
Y1630669D01*
G01D02*
X455400D01*
G01X469600Y1653900D02*
X463400D01*
G01D02*
Y1657100D01*
G01X459400Y1642400D02*
Y1648600D01*
G01D02*
X462600D01*
G01D02*
Y1642400D01*
G01D02*
X459400D01*
G01X454685Y1648533D02*
Y1642333D01*
G01X455400Y1648600D02*
X458600D01*
G01X455400Y1642400D02*
Y1648600D01*
G01X458600Y1642400D02*
X455400D01*
G01X458600Y1648600D02*
Y1642400D01*
G01X463400Y1652100D02*
X466600D01*
G01X463400Y1645900D02*
Y1652100D01*
G01X466600Y1645900D02*
X463400D01*
G01X466600Y1652100D02*
Y1645900D01*
G01X468669Y1652247D02*
X477331D01*
G01X468669Y1641753D02*
Y1652247D01*
G01X477331Y1641753D02*
X468669D01*
G01X463400Y1657100D02*
X469600D01*
G01X463400Y1670400D02*
Y1673600D01*
G01X469600Y1670400D02*
X463400D01*
G01Y1666400D02*
Y1669600D01*
G01X469600Y1666400D02*
X463400D01*
G01Y1669600D02*
X469600D01*
G01X463400Y1657900D02*
Y1661100D01*
G01X469600Y1657900D02*
X463400D01*
G01Y1661100D02*
X469600D01*
G01X454921Y1656969D02*
Y1736120D01*
G01X468400Y1681600D02*
X474600D01*
G01X468400Y1678400D02*
Y1681600D01*
G01X474600Y1678400D02*
X468400D01*
G01X463400Y1673600D02*
X469600D01*
G01X463400Y1674400D02*
Y1677600D01*
G01X469600Y1674400D02*
X463400D01*
G01Y1677600D02*
X469600D01*
G01X461591Y1683329D02*
X463813D01*
X464278Y1683482D01*
X464588Y1683789D01*
X464691Y1684172D01*
X464588Y1684555D01*
X464278Y1684862D01*
X463813Y1685015D01*
X461591D01*
G01X462108Y1686544D02*
X461798Y1686774D01*
X461643Y1687042D01*
X461591Y1687349D01*
X461694Y1687732D01*
X461953Y1688000D01*
X462263Y1688077D01*
X462573Y1688039D01*
X462831Y1687885D01*
X463348Y1687119D01*
X463709Y1686774D01*
X464226Y1686544D01*
X464691Y1686467D01*
Y1688077D01*
G01X464226Y1689529D02*
X464484Y1689759D01*
X464639Y1690027D01*
X464691Y1690372D01*
X464588Y1690717D01*
X464381Y1690985D01*
X464019Y1691177D01*
X463606Y1691215D01*
X463193Y1691139D01*
X462934Y1690947D01*
X462728Y1690679D01*
X462676Y1690410D01*
X462728Y1690142D01*
X462934Y1689797D01*
X461591Y1689912D01*
Y1690947D01*
G01X464071Y1692629D02*
X464433Y1692859D01*
X464639Y1693165D01*
X464691Y1693510D01*
X464639Y1693817D01*
X464381Y1694124D01*
X464071Y1694315D01*
X463761Y1694354D01*
X463399Y1694277D01*
X463141Y1694009D01*
X463038Y1693740D01*
Y1693395D01*
G01Y1693740D02*
X462883Y1693970D01*
X462624Y1694162D01*
X462314Y1694239D01*
X462004Y1694162D01*
X461746Y1693970D01*
X461591Y1693625D01*
X461643Y1693280D01*
X461849Y1692935D01*
G01X465978Y1683178D02*
Y1693778D01*
G01X474640Y1683178D02*
X465978D01*
G01X463900Y1698600D02*
X470100D01*
G01X463900Y1695400D02*
Y1698600D01*
G01X470100Y1695400D02*
X463900D01*
G01Y1699400D02*
Y1702600D01*
G01X470100Y1699400D02*
X463900D01*
G01X465978Y1693778D02*
X474640D01*
G01X466900Y1709900D02*
Y1716100D01*
G01X470100Y1709900D02*
X466900D01*
G01X463900Y1702600D02*
X470100D01*
G01X466900Y1716100D02*
X470100D01*
G01X461358Y1718714D02*
X463580D01*
X464045Y1718867D01*
X464355Y1719174D01*
X464458Y1719557D01*
X464355Y1719940D01*
X464045Y1720247D01*
X463580Y1720400D01*
X461358D01*
G01X461875Y1721929D02*
X461565Y1722159D01*
X461410Y1722427D01*
X461358Y1722734D01*
X461461Y1723117D01*
X461720Y1723385D01*
X462030Y1723462D01*
X462340Y1723424D01*
X462598Y1723270D01*
X463115Y1722504D01*
X463476Y1722159D01*
X463993Y1721929D01*
X464458Y1721852D01*
Y1723462D01*
G01X463993Y1724914D02*
X464251Y1725144D01*
X464406Y1725412D01*
X464458Y1725757D01*
X464355Y1726102D01*
X464148Y1726370D01*
X463786Y1726562D01*
X463373Y1726600D01*
X462960Y1726524D01*
X462701Y1726332D01*
X462495Y1726064D01*
X462443Y1725795D01*
X462495Y1725527D01*
X462701Y1725182D01*
X461358Y1725297D01*
Y1726332D01*
G01X464458Y1728780D02*
X463786Y1728857D01*
X463218Y1728972D01*
X462701Y1729125D01*
X462133Y1729317D01*
X461358Y1729624D01*
Y1728090D01*
G01X474306Y1729233D02*
X465644D01*
G01Y1718353D02*
X474306D01*
G01X465644Y1729233D02*
Y1718353D01*
G01X463900Y1735100D02*
X470100D01*
G01X463900Y1731900D02*
Y1735100D01*
G01X470100Y1731900D02*
X463900D01*
G01X486200Y-598305D02*
X485600Y-597905D01*
X484900Y-597638D01*
X484100D01*
X483200Y-598038D01*
X482500Y-598705D01*
X482000Y-599505D01*
X481600Y-600838D01*
X481500Y-602038D01*
X481700Y-603238D01*
X482000Y-604038D01*
X482600Y-604838D01*
X483300Y-605371D01*
X484000Y-605638D01*
X484700D01*
X485400Y-605371D01*
X486000Y-604971D01*
X486500Y-604438D01*
G01X470753Y58429D02*
Y61629D01*
G01X476953Y58429D02*
X470753D01*
G01X476953Y61629D02*
Y58429D01*
G01X470683Y56735D02*
X476883D01*
G01X470683Y53535D02*
Y56735D01*
G01X476883Y53535D02*
X470683D01*
G01X476883Y56735D02*
Y53535D01*
G01X484173Y66565D02*
X490373D01*
G01X484173Y63365D02*
Y66565D01*
G01X490373Y63365D02*
X484173D01*
G01X470753Y63375D02*
Y66575D01*
G01X476953Y63375D02*
X470753D01*
G01X476953Y66575D02*
Y63375D01*
G01X470753Y66575D02*
X476953D01*
G01X470753Y61629D02*
X476953D01*
G01X478225Y92174D02*
Y88974D01*
G01D02*
X472025D01*
G01D02*
Y92174D01*
G01D02*
X478225D01*
G01Y103974D02*
X472025D01*
G01X478225Y107174D02*
Y103974D01*
G01X472025D02*
Y107174D01*
G01Y102174D02*
X478225D01*
G01D02*
Y98974D01*
G01D02*
X472025D01*
G01D02*
Y102174D01*
G01Y97174D02*
X478225D01*
G01D02*
Y93974D01*
G01D02*
X472025D01*
G01D02*
Y97174D01*
G01X478290Y121244D02*
Y118044D01*
G01D02*
X472090D01*
G01D02*
Y121244D01*
G01Y117244D02*
X478290D01*
G01D02*
Y114044D01*
G01D02*
X472090D01*
G01D02*
Y117244D01*
G01X472025Y112174D02*
X478225D01*
G01D02*
Y108974D01*
G01D02*
X472025D01*
G01D02*
Y112174D01*
G01Y107174D02*
X478225D01*
G01X472090Y125244D02*
X478290D01*
G01D02*
Y122044D01*
G01D02*
X472090D01*
G01D02*
Y125244D01*
G01Y121244D02*
X478290D01*
G01X488755Y142792D02*
X482555D01*
Y145992D01*
X488755D01*
Y142792D01*
G01Y137892D02*
X482555D01*
Y141092D01*
X488755D01*
Y137892D01*
G01X479405Y141092D02*
X485605D01*
Y137892D01*
X479405D01*
Y141092D01*
G01Y145992D02*
X485605D01*
Y142792D01*
X479405D01*
Y145992D01*
G01X471597Y165225D02*
Y159025D01*
G01X475597Y165225D02*
Y159025D01*
G01D02*
X472397D01*
G01D02*
Y165225D01*
G01D02*
X475597D01*
G01X483597D02*
Y159025D01*
G01D02*
X480397D01*
G01D02*
Y165225D01*
G01D02*
X483597D01*
G01X479597D02*
Y159025D01*
G01D02*
X476397D01*
G01D02*
Y165225D01*
G01D02*
X479597D01*
G01X481653Y208427D02*
X482300D01*
G01X487853Y205227D02*
X481653D01*
G01D02*
Y208427D01*
G01X473835Y205035D02*
Y211235D01*
G01X477035D02*
Y205035D01*
G01D02*
X473835D01*
G01X470099Y212220D02*
Y209020D01*
G01Y208220D02*
Y205020D01*
G01X483154Y221852D02*
Y228052D01*
G01X486354Y221852D02*
X483154D01*
G01X470496Y224364D02*
Y221164D01*
G01X473835Y211235D02*
X477035D01*
G01X474487Y218629D02*
X476709D01*
X477174Y218782D01*
X477484Y219089D01*
X477587Y219472D01*
X477484Y219855D01*
X477174Y220162D01*
X476709Y220315D01*
X474487D01*
G01X477587Y222572D02*
X474487D01*
X475107Y222112D01*
G01X477587D02*
Y223032D01*
G01Y226132D02*
X474487D01*
X476709Y224714D01*
Y226630D01*
G01X476295Y228044D02*
X475934Y228312D01*
X475727Y228542D01*
X475624Y228849D01*
X475727Y229117D01*
X475934Y229309D01*
X476244Y229462D01*
X476605Y229500D01*
X476915Y229462D01*
X477225Y229309D01*
X477484Y229079D01*
X477587Y228810D01*
X477484Y228504D01*
X477174Y228235D01*
X476709Y228082D01*
X476192Y228044D01*
X475520Y228120D01*
X475159Y228235D01*
X474797Y228427D01*
X474539Y228695D01*
X474487Y228964D01*
X474590Y229232D01*
X474849Y229424D01*
G01X479062Y220556D02*
X490446D01*
G01Y210748D02*
X479062D01*
G01D02*
Y220556D01*
G01X483154Y228052D02*
X486354D01*
G01X470496Y241364D02*
Y238164D01*
G01Y229364D02*
Y226164D01*
G01Y233364D02*
Y230164D01*
G01Y237364D02*
Y234164D01*
G01Y245364D02*
Y242164D01*
G01Y249364D02*
Y246164D01*
G01X478028Y286338D02*
Y283138D01*
G01D02*
X471828D01*
G01D02*
Y286338D01*
G01Y282458D02*
X478028D01*
G01D02*
Y279258D01*
G01D02*
X471828D01*
G01D02*
Y282458D01*
G01X470638Y305238D02*
Y299038D01*
G01X471828Y286338D02*
X478028D01*
G01X484900Y286869D02*
X478700D01*
G01D02*
Y290069D01*
G01D02*
X484900D01*
G01X471830Y290171D02*
X478030Y290165D01*
G01D02*
X478026Y286965D01*
G01D02*
X471826Y286971D01*
G01D02*
X471830Y290171D01*
G01X475826Y293117D02*
X473676D01*
G01D02*
Y294282D01*
G01X481944D02*
Y293117D01*
G01D02*
X479794D01*
G01X480905Y308209D02*
X474705D01*
G01D02*
Y311409D01*
G01D02*
X480905D01*
G01D02*
Y308209D01*
G01X485663Y306872D02*
X482463D01*
G01D02*
Y313072D01*
G01D02*
X485663D01*
G01X473676Y304156D02*
Y305321D01*
G01D02*
X475826D01*
G01X479794D02*
X481944D01*
G01D02*
Y304156D01*
G01X470100Y494600D02*
Y488400D01*
G01X480365Y580172D02*
X486565D01*
G01Y576972D02*
X480365D01*
G01D02*
Y580172D01*
G01X478392Y571815D02*
Y595831D01*
G01X472281Y571815D02*
X478392D01*
G01X483622Y586470D02*
X480522D01*
Y587390D01*
X480677Y587697D01*
X481039Y587927D01*
X481452Y588004D01*
X481865Y587927D01*
X482175Y587735D01*
X482330Y587390D01*
Y586470D01*
G01X480522Y589570D02*
X483622D01*
Y591104D01*
G01X483002Y592594D02*
X483364Y592824D01*
X483570Y593130D01*
X483622Y593475D01*
X483570Y593782D01*
X483312Y594089D01*
X483002Y594280D01*
X482692Y594319D01*
X482330Y594242D01*
X482072Y593974D01*
X481969Y593705D01*
Y593360D01*
G01Y593705D02*
X481814Y593935D01*
X481555Y594127D01*
X481245Y594204D01*
X480935Y594127D01*
X480677Y593935D01*
X480522Y593590D01*
X480574Y593245D01*
X480780Y592900D01*
G01X483622Y596460D02*
X482950Y596537D01*
X482382Y596652D01*
X481865Y596805D01*
X481297Y596997D01*
X480522Y597304D01*
Y595770D01*
G01X478392Y595831D02*
X472281D01*
G01X478290Y621096D02*
Y624196D01*
X479210D01*
X479517Y624041D01*
X479747Y623679D01*
X479824Y623266D01*
X479747Y622853D01*
X479555Y622543D01*
X479210Y622388D01*
X478290D01*
G01X481314Y624196D02*
Y621974D01*
X481467Y621509D01*
X481774Y621199D01*
X482157Y621096D01*
X482540Y621199D01*
X482847Y621509D01*
X483000Y621974D01*
Y624196D01*
G01X484414Y621716D02*
X484644Y621354D01*
X484950Y621148D01*
X485295Y621096D01*
X485602Y621148D01*
X485909Y621406D01*
X486100Y621716D01*
X486139Y622026D01*
X486062Y622388D01*
X485794Y622646D01*
X485525Y622749D01*
X485180D01*
G01X485525D02*
X485755Y622904D01*
X485947Y623163D01*
X486024Y623473D01*
X485947Y623783D01*
X485755Y624041D01*
X485410Y624196D01*
X485065Y624144D01*
X484720Y623938D01*
G01X488357Y621096D02*
Y624196D01*
X487897Y623576D01*
G01Y621096D02*
X488817D01*
G01X479424Y628950D02*
Y635150D01*
G01D02*
X482624D01*
G01D02*
Y628950D01*
G01D02*
X479424D01*
G01X486666D02*
X483466D01*
G01D02*
Y635150D01*
G01D02*
X486666D01*
G01X478945Y638553D02*
X478212D01*
G01D02*
Y640744D01*
G01X472132Y646939D02*
Y653139D01*
G01D02*
X475332D01*
G01D02*
Y646939D01*
G01D02*
X472132D01*
G01X471481Y653137D02*
Y646937D01*
G01X471555Y669471D02*
Y663271D01*
G01X478212Y659575D02*
Y662175D01*
G01D02*
X479005D01*
G01X474698Y708700D02*
Y665392D01*
G01D02*
X480039D01*
G01X471555Y679971D02*
Y673771D01*
G01X473098Y690292D02*
Y687092D01*
G01X471532Y686792D02*
Y680592D01*
G01X471854Y735200D02*
Y691892D01*
G01X480039Y708700D02*
X474698D01*
G01X481900Y1263262D02*
Y1269462D01*
G01X483300Y1263262D02*
X481900D01*
G01X480100Y1263400D02*
X478400D01*
G01X480100Y1269600D02*
Y1263400D01*
G01X476900Y1265000D02*
Y1268100D01*
G01X472900Y1263400D02*
Y1269600D01*
G01X476100Y1268100D02*
Y1265000D01*
G01X474400Y1263400D02*
X472900D01*
G01X481900Y1269462D02*
X483300D01*
G01X478500Y1269600D02*
X480100D01*
G01X472900D02*
X474200D01*
G01X474204Y1414259D02*
X474577Y1414634D01*
X474857Y1415259D01*
X475044Y1416134D01*
X474857Y1416884D01*
X474484Y1417384D01*
X473830Y1417759D01*
X471310D01*
Y1410259D01*
X474390D01*
X475044Y1410759D01*
X475417Y1411509D01*
X475604Y1412384D01*
X475417Y1413259D01*
X474857Y1414009D01*
X474204Y1414259D01*
X471310D01*
G01X478530Y1410259D02*
Y1417759D01*
X480957Y1411509D01*
X483384Y1417759D01*
Y1410259D01*
G01X490510Y1417134D02*
X489950Y1417509D01*
X489297Y1417759D01*
X488550D01*
X487710Y1417384D01*
X487057Y1416759D01*
X486590Y1416009D01*
X486217Y1414759D01*
X486124Y1413634D01*
X486310Y1412509D01*
X486590Y1411759D01*
X487150Y1411009D01*
X487804Y1410509D01*
X488457Y1410259D01*
X489110D01*
X489764Y1410509D01*
X490324Y1410884D01*
X490790Y1411384D01*
G01X483657Y1422559D02*
X478990Y1430059D01*
Y1431309D01*
X479924Y1432559D01*
X480857D01*
X481790Y1431309D01*
Y1430059D01*
X480857Y1428809D01*
X478990Y1427559D01*
X478057Y1426309D01*
Y1423809D01*
X478990Y1422559D01*
X481790D01*
X483657Y1425059D01*
G01X484531Y1627418D02*
Y1634918D01*
X486771D01*
X487518Y1634543D01*
X488078Y1633668D01*
X488265Y1632668D01*
X488078Y1631668D01*
X487611Y1630918D01*
X486771Y1630543D01*
X484531D01*
G01X492031Y1627418D02*
Y1634918D01*
X494365D01*
X495111Y1634543D01*
X495578Y1634043D01*
X495765Y1633043D01*
X495578Y1632043D01*
X495018Y1631418D01*
X494365Y1631043D01*
X492031D01*
G01X494365D02*
X495765Y1627418D01*
G01X503265D02*
X499531D01*
Y1634918D01*
X503265D01*
G01X501771Y1631293D02*
X499531D01*
G01X506938Y1628418D02*
X507685Y1627793D01*
X508525Y1627418D01*
X509271D01*
X510018Y1627793D01*
X510578Y1628418D01*
X510858Y1629293D01*
X510671Y1630168D01*
X510205Y1630918D01*
X509365Y1631418D01*
X508245Y1631668D01*
X507591Y1632168D01*
X507311Y1633043D01*
X507498Y1633918D01*
X507965Y1634543D01*
X508618Y1634918D01*
X509271D01*
X509925Y1634668D01*
X510485Y1634043D01*
G01X514438Y1628418D02*
X515185Y1627793D01*
X516025Y1627418D01*
X516771D01*
X517518Y1627793D01*
X518078Y1628418D01*
X518358Y1629293D01*
X518171Y1630168D01*
X517705Y1630918D01*
X516865Y1631418D01*
X515745Y1631668D01*
X515091Y1632168D01*
X514811Y1633043D01*
X514998Y1633918D01*
X515465Y1634543D01*
X516118Y1634918D01*
X516771D01*
X517425Y1634668D01*
X517985Y1634043D01*
G01X522685Y1629918D02*
X525111D01*
G01X529625Y1627418D02*
Y1634918D01*
X533171D01*
G01X531865Y1631293D02*
X529625D01*
G01X537778Y1634918D02*
X540018D01*
G01X538898D02*
Y1627418D01*
G01X537778D02*
X540018D01*
G01X546398Y1634918D02*
Y1627418D01*
G01X544251Y1634918D02*
X548545D01*
G01X476735Y1629997D02*
X476683Y1629690D01*
X476477Y1629422D01*
X476167Y1629192D01*
X475805Y1629039D01*
X475392Y1628962D01*
X474978D01*
X474565Y1629039D01*
X474203Y1629192D01*
X473893Y1629422D01*
X473687Y1629690D01*
X473635Y1629997D01*
X473687Y1630304D01*
X473893Y1630572D01*
X474203Y1630802D01*
X474565Y1630955D01*
X474978Y1631032D01*
X475392D01*
X475805Y1630955D01*
X476167Y1630802D01*
X476477Y1630572D01*
X476683Y1630304D01*
X476735Y1629997D01*
G01X475908Y1630304D02*
X476735Y1630764D01*
G01Y1633097D02*
X473635D01*
X474255Y1632637D01*
G01X476735D02*
Y1633557D01*
G01X473635Y1636197D02*
X473738Y1635890D01*
X473997Y1635660D01*
X474307Y1635507D01*
X474720Y1635392D01*
X475185Y1635354D01*
X475650Y1635392D01*
X476063Y1635507D01*
X476373Y1635660D01*
X476632Y1635890D01*
X476735Y1636197D01*
X476632Y1636504D01*
X476373Y1636734D01*
X476063Y1636887D01*
X475650Y1637002D01*
X475185Y1637040D01*
X474720Y1637002D01*
X474307Y1636887D01*
X473997Y1636734D01*
X473738Y1636504D01*
X473635Y1636197D01*
G01X476115Y1638454D02*
X476477Y1638684D01*
X476683Y1638990D01*
X476735Y1639335D01*
X476683Y1639642D01*
X476425Y1639949D01*
X476115Y1640140D01*
X475805Y1640179D01*
X475443Y1640102D01*
X475185Y1639834D01*
X475082Y1639565D01*
Y1639220D01*
G01Y1639565D02*
X474927Y1639795D01*
X474668Y1639987D01*
X474358Y1640064D01*
X474048Y1639987D01*
X473790Y1639795D01*
X473635Y1639450D01*
X473687Y1639105D01*
X473893Y1638760D01*
G01X478101Y1641519D02*
X478293Y1641209D01*
X478523Y1641002D01*
X478791Y1640899D01*
X479098Y1641002D01*
X479328Y1641209D01*
X479558Y1641519D01*
X479635Y1641932D01*
Y1643999D01*
G01X481968Y1640899D02*
Y1643999D01*
X481508Y1643379D01*
G01Y1640899D02*
X482428D01*
G01X485068D02*
Y1643999D01*
X484608Y1643379D01*
G01Y1640899D02*
X485528D01*
G01X488168Y1643999D02*
X487861Y1643896D01*
X487631Y1643637D01*
X487478Y1643327D01*
X487363Y1642914D01*
X487325Y1642449D01*
X487363Y1641984D01*
X487478Y1641571D01*
X487631Y1641261D01*
X487861Y1641002D01*
X488168Y1640899D01*
X488475Y1641002D01*
X488705Y1641261D01*
X488858Y1641571D01*
X488973Y1641984D01*
X489011Y1642449D01*
X488973Y1642914D01*
X488858Y1643327D01*
X488705Y1643637D01*
X488475Y1643896D01*
X488168Y1643999D01*
G01X469600Y1657100D02*
Y1653900D01*
G01X477100Y1657100D02*
Y1653900D01*
G01D02*
X470900D01*
G01D02*
Y1657100D01*
G01X477331Y1652247D02*
Y1648900D01*
G01D02*
X475131Y1647000D01*
G01D02*
X477331Y1645100D01*
G01D02*
Y1641753D01*
G01X478346Y1646023D02*
Y1736118D01*
G01X568503Y1646023D02*
X478346D01*
G01X470900Y1657100D02*
X477100D01*
G01X469600Y1673600D02*
Y1670400D01*
G01X477100Y1666400D02*
X470900D01*
G01X477100Y1669600D02*
Y1666400D01*
G01X470900Y1669600D02*
X477100D01*
G01X470900Y1666400D02*
Y1669600D01*
G01X469600D02*
Y1666400D01*
G01X470900Y1670400D02*
Y1673600D01*
G01X477100Y1670400D02*
X470900D01*
G01X477100Y1673600D02*
Y1670400D01*
G01Y1661100D02*
Y1657900D01*
G01X470900Y1661100D02*
X477100D01*
G01X470900Y1657900D02*
Y1661100D01*
G01X477100Y1657900D02*
X470900D01*
G01X469600Y1661100D02*
Y1657900D01*
G01X474600Y1681600D02*
Y1678400D01*
G01X477100Y1677600D02*
Y1674400D01*
G01X470900Y1677600D02*
X477100D01*
G01X470900Y1674400D02*
Y1677600D01*
G01X477100Y1674400D02*
X470900D01*
G01Y1673600D02*
X477100D01*
G01X469600Y1677600D02*
Y1674400D01*
G01X474640Y1685840D02*
Y1683178D01*
G01X471809Y1688478D02*
X474640Y1685840D01*
G01X477100Y1698600D02*
Y1695400D01*
G01X470900Y1698600D02*
X477100D01*
G01X470900Y1695400D02*
Y1698600D01*
G01X477100Y1695400D02*
X470900D01*
G01Y1699400D02*
Y1702600D01*
G01X477100Y1699400D02*
X470900D01*
G01X477100Y1702600D02*
Y1699400D01*
G01X470100Y1698600D02*
Y1695400D01*
G01Y1702600D02*
Y1699400D01*
G01X474640Y1691116D02*
X471809Y1688478D01*
G01X474640Y1693778D02*
Y1691116D01*
G01X470100Y1716100D02*
Y1709900D01*
G01X470900Y1704900D02*
Y1708100D01*
G01X477100Y1704900D02*
X470900D01*
G01X477100Y1708100D02*
Y1704900D01*
G01X470900Y1708100D02*
X477100D01*
G01X470900Y1702600D02*
X477100D01*
G01X470900Y1708900D02*
Y1712100D01*
G01X477100D02*
Y1708900D01*
G01X470900Y1712100D02*
X477100D01*
G01Y1708900D02*
X470900D01*
G01Y1712900D02*
Y1716100D01*
G01X477100Y1712900D02*
X470900D01*
G01X477100Y1716100D02*
Y1712900D01*
G01X470900Y1716100D02*
X477100D01*
G01X474306Y1721462D02*
X471975Y1723793D01*
G01X474306Y1726124D02*
Y1729233D01*
G01X471975Y1723793D02*
X474306Y1726124D01*
G01Y1718353D02*
Y1721462D01*
G01X470100Y1735100D02*
Y1731900D01*
G01X470900D02*
Y1735100D01*
G01X477100D02*
Y1731900D01*
G01X470900Y1735100D02*
X477100D01*
G01Y1731900D02*
X470900D01*
G01X509544Y64566D02*
X498354D01*
Y20866D01*
X764654D01*
Y64566D01*
G01X517300Y71929D02*
X496228D01*
Y18267D01*
X766780D01*
Y71929D01*
G01X490483Y61705D02*
Y58505D01*
G01X484283D02*
Y61705D01*
G01X490483Y58505D02*
X484283D01*
G01X490643Y56695D02*
Y53495D01*
G01X484443Y56695D02*
X490643D01*
G01X484443Y53495D02*
Y56695D01*
G01X490643Y53495D02*
X484443D01*
G01X490373Y66565D02*
Y63365D01*
G01X484283Y61705D02*
X490483D01*
G01X485730Y100456D02*
Y101851D01*
X484963Y103556D01*
G01X486497D02*
X485730Y101851D01*
G01X488178Y100818D02*
X488447Y100559D01*
X488753Y100456D01*
X489060Y100559D01*
X489328Y100869D01*
X489520Y101334D01*
X489597Y101799D01*
Y102368D01*
X489520Y102833D01*
X489328Y103246D01*
X489098Y103453D01*
X488830Y103556D01*
X488523Y103453D01*
X488293Y103246D01*
X488140Y102936D01*
X488063Y102523D01*
X488140Y102161D01*
X488332Y101799D01*
X488562Y101593D01*
X488830Y101541D01*
X489137Y101644D01*
X489367Y101903D01*
X489597Y102368D01*
G01X496714Y113818D02*
Y120018D01*
G01D02*
X499914D01*
G01Y113818D02*
X496714D01*
G01X499985Y106599D02*
X496785D01*
G01D02*
Y112799D01*
G01D02*
X499985D01*
G01X484566Y107383D02*
X495434D01*
G01D02*
Y119819D01*
G01D02*
X484566D01*
G01D02*
Y107383D01*
G01X495230Y127342D02*
X492080D01*
G01Y130542D02*
X495230D01*
G01Y132342D02*
X492080D01*
G01Y135542D02*
X495230D01*
G01X488930Y130542D02*
X492080D01*
G01Y127342D02*
X488930D01*
G01Y135542D02*
X492080D01*
G01Y132342D02*
X488930D01*
G01X484397Y159025D02*
Y165225D01*
G01D02*
X487597D01*
G01D02*
Y159025D01*
G01D02*
X484397D01*
G01X488397D02*
Y165225D01*
G01D02*
X491597D01*
G01D02*
Y159025D01*
G01D02*
X488397D01*
G01Y173225D02*
X494597D01*
G01D02*
Y170025D01*
G01D02*
X488397D01*
G01D02*
Y173225D01*
G01X494597Y166025D02*
X488397D01*
G01D02*
Y169225D01*
G01D02*
X494597D01*
G01D02*
Y166025D01*
G01X493782Y191916D02*
X487582D01*
G01D02*
Y195116D01*
G01X493782D02*
Y191916D01*
G01X487582Y195116D02*
X493782D01*
G01X487582Y187916D02*
Y191116D01*
G01X493782Y187916D02*
X487582D01*
G01X493782Y191116D02*
Y187916D01*
G01X487582Y191116D02*
X493782D01*
G01X496132Y195116D02*
X502332D01*
G01Y191916D02*
X496132D01*
G01D02*
Y195116D01*
G01Y187116D02*
X502332D01*
G01Y183916D02*
X496132D01*
G01D02*
Y187116D01*
G01Y191116D02*
X502332D01*
G01Y187916D02*
X496132D01*
G01D02*
Y191116D01*
G01X493782Y203116D02*
Y199916D01*
G01X487582Y203116D02*
X493782D01*
G01X487582Y199916D02*
Y203116D01*
G01X493782Y199916D02*
X487582D01*
G01X487853Y208427D02*
Y205227D01*
G01X485500Y208427D02*
X487853D01*
G01X493782Y199116D02*
Y195916D01*
G01X487582Y199116D02*
X493782D01*
G01X487582Y195916D02*
Y199116D01*
G01X493782Y195916D02*
X487582D01*
G01X502332D02*
X496132D01*
G01D02*
Y199116D01*
G01D02*
X502332D01*
G01X486354Y228052D02*
Y221852D01*
G01X492544Y214127D02*
Y220327D01*
G01D02*
X495744D01*
G01D02*
Y214127D01*
G01D02*
X492544D01*
G01X490446Y220556D02*
Y210748D01*
G01X484584Y234600D02*
X490784D01*
G01D02*
Y231400D01*
G01D02*
X484584D01*
G01D02*
Y234600D01*
G01X492934Y239719D02*
X499134D01*
G01D02*
Y236519D01*
G01D02*
X492934D01*
G01D02*
Y239719D01*
G01X499134Y231400D02*
X492934D01*
G01D02*
Y234600D01*
G01D02*
X499134D01*
G01D02*
Y231400D01*
G01Y241578D02*
X492934D01*
G01D02*
Y244778D01*
G01D02*
X499134D01*
G01D02*
Y241578D01*
G01X494647Y268072D02*
X494267Y268322D01*
X493824Y268489D01*
X493317D01*
X492747Y268239D01*
X492304Y267822D01*
X491987Y267322D01*
X491734Y266489D01*
X491671Y265739D01*
X491797Y264989D01*
X491987Y264489D01*
X492367Y263989D01*
X492811Y263656D01*
X493254Y263489D01*
X493697D01*
X494141Y263656D01*
X494521Y263906D01*
X494837Y264239D01*
G01X497087Y263489D02*
Y268489D01*
X498607D01*
X499114Y268239D01*
X499494Y267656D01*
X499621Y266989D01*
X499494Y266322D01*
X499177Y265822D01*
X498607Y265572D01*
X497087D01*
G01X502187Y268489D02*
Y263489D01*
X504721D01*
G01X507161D02*
Y268489D01*
X508427D01*
X508934Y268239D01*
X509314Y267906D01*
X509631Y267406D01*
X509884Y266822D01*
X509947Y265989D01*
X509884Y265156D01*
X509631Y264572D01*
X509314Y264072D01*
X508934Y263739D01*
X508427Y263489D01*
X507161D01*
G01X517487D02*
Y268489D01*
X519007D01*
X519514Y268239D01*
X519894Y267656D01*
X520021Y266989D01*
X519894Y266322D01*
X519577Y265822D01*
X519007Y265572D01*
X517487D01*
G01X522967Y263489D02*
Y266822D01*
G01Y266156D02*
X523284Y266489D01*
X523601Y266739D01*
X524044Y266822D01*
X524361Y266739D01*
X524741Y266489D01*
G01X528954Y263489D02*
X528574Y263572D01*
X528194Y263906D01*
X527941Y264489D01*
X527814Y265156D01*
X527941Y265822D01*
X528194Y266406D01*
X528574Y266739D01*
X528954Y266822D01*
X529334Y266739D01*
X529714Y266406D01*
X529967Y265822D01*
X530031Y265156D01*
X529967Y264489D01*
X529714Y263906D01*
X529334Y263572D01*
X528954Y263489D01*
G01X533167Y262239D02*
X533611Y261906D01*
X534117Y261822D01*
X534561Y261906D01*
X534941Y262322D01*
X535194Y262906D01*
Y266822D01*
G01Y266156D02*
X534941Y266489D01*
X534561Y266739D01*
X534117Y266822D01*
X533611Y266656D01*
X533294Y266322D01*
X533041Y265739D01*
X532914Y265156D01*
X532977Y264656D01*
X533231Y264072D01*
X533611Y263656D01*
X534117Y263489D01*
X534497Y263572D01*
X534941Y263906D01*
X535194Y264239D01*
G01X538267Y263489D02*
Y266822D01*
G01Y266156D02*
X538584Y266489D01*
X538901Y266739D01*
X539344Y266822D01*
X539661Y266739D01*
X540041Y266489D01*
G01X545394Y263489D02*
Y266822D01*
G01Y266239D02*
X545141Y266572D01*
X544761Y266739D01*
X544317Y266822D01*
X543874Y266656D01*
X543494Y266322D01*
X543241Y265822D01*
X543114Y265156D01*
X543241Y264489D01*
X543494Y263989D01*
X543874Y263656D01*
X544317Y263489D01*
X544761Y263572D01*
X545141Y263822D01*
X545394Y264156D01*
G01X547454Y263489D02*
Y266822D01*
G01Y265906D02*
X547644Y266322D01*
X547961Y266656D01*
X548404Y266822D01*
X548847Y266656D01*
X549164Y266322D01*
X549354Y265906D01*
Y263489D01*
G01Y265906D02*
X549544Y266322D01*
X549861Y266656D01*
X550304Y266822D01*
X550747Y266656D01*
X551064Y266322D01*
X551254Y265822D01*
Y263489D01*
G01X552554D02*
Y266822D01*
G01Y265906D02*
X552744Y266322D01*
X553061Y266656D01*
X553504Y266822D01*
X553947Y266656D01*
X554264Y266322D01*
X554454Y265906D01*
Y263489D01*
G01Y265906D02*
X554644Y266322D01*
X554961Y266656D01*
X555404Y266822D01*
X555847Y266656D01*
X556164Y266322D01*
X556354Y265822D01*
Y263489D01*
G01X559554Y266822D02*
Y263489D01*
G01Y268156D02*
X559427Y268239D01*
Y268406D01*
X559554Y268489D01*
X559681Y268406D01*
Y268239D01*
X559554Y268156D01*
G01X563577Y263489D02*
Y266822D01*
G01Y265989D02*
X563831Y266406D01*
X564211Y266739D01*
X564717Y266822D01*
X565161Y266739D01*
X565541Y266406D01*
X565731Y265822D01*
Y263489D01*
G01X568867Y262239D02*
X569311Y261906D01*
X569817Y261822D01*
X570261Y261906D01*
X570641Y262322D01*
X570894Y262906D01*
Y266822D01*
G01Y266156D02*
X570641Y266489D01*
X570261Y266739D01*
X569817Y266822D01*
X569311Y266656D01*
X568994Y266322D01*
X568741Y265739D01*
X568614Y265156D01*
X568677Y264656D01*
X568931Y264072D01*
X569311Y263656D01*
X569817Y263489D01*
X570197Y263572D01*
X570641Y263906D01*
X570894Y264239D01*
G01X485507Y283629D02*
Y289829D01*
G01X488707D02*
Y283629D01*
G01D02*
X485507D01*
G01X522578Y283925D02*
X493838D01*
G01D02*
Y289914D01*
G01X486938Y297103D02*
Y303303D01*
G01X490138D02*
Y297103D01*
G01D02*
X486938D01*
G01X484900Y290069D02*
Y286869D01*
G01X485507Y289829D02*
X488707D01*
G01X490144Y290424D02*
X486944D01*
G01X490144Y296624D02*
Y290424D01*
G01X486944Y296624D02*
X490144D01*
G01X486944Y290424D02*
Y296624D01*
G01X486938Y303303D02*
X490138D01*
G01X485663Y313072D02*
Y306872D01*
G01X493838Y304214D02*
Y310303D01*
G01X493808D02*
X522578D01*
G01X488079Y316402D02*
Y319502D01*
X488999D01*
X489306Y319347D01*
X489536Y318985D01*
X489613Y318572D01*
X489536Y318159D01*
X489344Y317849D01*
X488999Y317694D01*
X488079D01*
G01X491179Y319502D02*
Y316402D01*
X492713D01*
G01X494318Y317694D02*
X494586Y318055D01*
X494816Y318262D01*
X495123Y318365D01*
X495391Y318262D01*
X495583Y318055D01*
X495736Y317745D01*
X495774Y317384D01*
X495736Y317074D01*
X495583Y316764D01*
X495353Y316505D01*
X495084Y316402D01*
X494778Y316505D01*
X494509Y316815D01*
X494356Y317280D01*
X494318Y317797D01*
X494394Y318469D01*
X494509Y318830D01*
X494701Y319192D01*
X494969Y319450D01*
X495238Y319502D01*
X495506Y319399D01*
X495698Y319140D01*
G01X498146Y319502D02*
X497839Y319399D01*
X497609Y319140D01*
X497456Y318830D01*
X497341Y318417D01*
X497303Y317952D01*
X497341Y317487D01*
X497456Y317074D01*
X497609Y316764D01*
X497839Y316505D01*
X498146Y316402D01*
X498453Y316505D01*
X498683Y316764D01*
X498836Y317074D01*
X498951Y317487D01*
X498989Y317952D01*
X498951Y318417D01*
X498836Y318830D01*
X498683Y319140D01*
X498453Y319399D01*
X498146Y319502D01*
G01X501246D02*
X500939Y319399D01*
X500709Y319140D01*
X500556Y318830D01*
X500441Y318417D01*
X500403Y317952D01*
X500441Y317487D01*
X500556Y317074D01*
X500709Y316764D01*
X500939Y316505D01*
X501246Y316402D01*
X501553Y316505D01*
X501783Y316764D01*
X501936Y317074D01*
X502051Y317487D01*
X502089Y317952D01*
X502051Y318417D01*
X501936Y318830D01*
X501783Y319140D01*
X501553Y319399D01*
X501246Y319502D01*
G01X504346Y316402D02*
Y319502D01*
X503886Y318882D01*
G01Y316402D02*
X504806D01*
G01X497984Y410644D02*
Y425356D01*
G01X486016Y410644D02*
X497984D01*
G01X486016Y425356D02*
Y410644D01*
G01X497984Y425356D02*
X486016D01*
G01X499231Y559329D02*
Y562429D01*
G01X500841D02*
Y559329D01*
G01Y560879D02*
X499231D01*
G01X503136Y559329D02*
X503404Y559381D01*
X503711Y559536D01*
X503903Y559794D01*
X503979Y560156D01*
X503903Y560517D01*
X503673Y560827D01*
X503328Y560982D01*
X502944D01*
X502714Y561086D01*
X502523Y561344D01*
X502446Y561706D01*
X502561Y562067D01*
X502829Y562326D01*
X503136Y562429D01*
X503443Y562326D01*
X503711Y562067D01*
X503826Y561706D01*
X503749Y561344D01*
X503558Y561086D01*
X503328Y560982D01*
X502944D01*
X502599Y560827D01*
X502369Y560517D01*
X502293Y560156D01*
X502369Y559794D01*
X502561Y559536D01*
X502868Y559381D01*
X503136Y559329D01*
G01X506236Y562429D02*
X505929Y562326D01*
X505699Y562067D01*
X505546Y561757D01*
X505431Y561344D01*
X505393Y560879D01*
X505431Y560414D01*
X505546Y560001D01*
X505699Y559691D01*
X505929Y559432D01*
X506236Y559329D01*
X506543Y559432D01*
X506773Y559691D01*
X506926Y560001D01*
X507041Y560414D01*
X507079Y560879D01*
X507041Y561344D01*
X506926Y561757D01*
X506773Y562067D01*
X506543Y562326D01*
X506236Y562429D01*
G01X508608Y561912D02*
X508838Y562222D01*
X509106Y562377D01*
X509413Y562429D01*
X509796Y562326D01*
X510064Y562067D01*
X510141Y561757D01*
X510103Y561447D01*
X509949Y561189D01*
X509183Y560672D01*
X508838Y560311D01*
X508608Y559794D01*
X508531Y559329D01*
X510141D01*
G01X512359D02*
X512436Y560001D01*
X512551Y560569D01*
X512704Y561086D01*
X512896Y561654D01*
X513203Y562429D01*
X511669D01*
G01X486565Y580172D02*
Y576972D01*
G01X497774Y594689D02*
Y597789D01*
X498694D01*
X499001Y597634D01*
X499231Y597272D01*
X499308Y596859D01*
X499231Y596446D01*
X499039Y596136D01*
X498694Y595981D01*
X497774D01*
G01X500798Y597789D02*
Y595567D01*
X500951Y595102D01*
X501258Y594792D01*
X501641Y594689D01*
X502024Y594792D01*
X502331Y595102D01*
X502484Y595567D01*
Y597789D01*
G01X503898Y595309D02*
X504128Y594947D01*
X504434Y594741D01*
X504779Y594689D01*
X505086Y594741D01*
X505393Y594999D01*
X505584Y595309D01*
X505623Y595619D01*
X505546Y595981D01*
X505278Y596239D01*
X505009Y596342D01*
X504664D01*
G01X505009D02*
X505239Y596497D01*
X505431Y596756D01*
X505508Y597066D01*
X505431Y597376D01*
X505239Y597634D01*
X504894Y597789D01*
X504549Y597737D01*
X504204Y597531D01*
G01X507113Y597272D02*
X507343Y597582D01*
X507611Y597737D01*
X507918Y597789D01*
X508301Y597686D01*
X508569Y597427D01*
X508646Y597117D01*
X508608Y596807D01*
X508454Y596549D01*
X507688Y596032D01*
X507343Y595671D01*
X507113Y595154D01*
X507036Y594689D01*
X508646D01*
G01X500261Y628140D02*
X497061D01*
G01D02*
Y634340D01*
G01D02*
X500261D01*
G01X490091Y631446D02*
X496291D01*
G01D02*
Y628246D01*
G01D02*
X490091D01*
G01D02*
Y631446D01*
G01X486666Y635150D02*
Y628950D01*
G01X497898Y640407D02*
Y638553D01*
G01D02*
X496890D01*
G01X497898Y652964D02*
Y651266D01*
G01X497105Y662175D02*
X497898D01*
G01D02*
Y659575D01*
G01X504226Y665392D02*
X498885D01*
G01X492887Y709888D02*
Y712988D01*
X493807D01*
X494114Y712833D01*
X494344Y712471D01*
X494421Y712058D01*
X494344Y711645D01*
X494152Y711335D01*
X493807Y711180D01*
X492887D01*
G01X495987Y712988D02*
Y709888D01*
X497521D01*
G01X499011Y710508D02*
X499241Y710146D01*
X499547Y709940D01*
X499892Y709888D01*
X500199Y709940D01*
X500506Y710198D01*
X500697Y710508D01*
X500736Y710818D01*
X500659Y711180D01*
X500391Y711438D01*
X500122Y711541D01*
X499777D01*
G01X500122D02*
X500352Y711696D01*
X500544Y711955D01*
X500621Y712265D01*
X500544Y712575D01*
X500352Y712833D01*
X500007Y712988D01*
X499662Y712936D01*
X499317Y712730D01*
G01X502226Y711180D02*
X502494Y711541D01*
X502724Y711748D01*
X503031Y711851D01*
X503299Y711748D01*
X503491Y711541D01*
X503644Y711231D01*
X503682Y710870D01*
X503644Y710560D01*
X503491Y710250D01*
X503261Y709991D01*
X502992Y709888D01*
X502686Y709991D01*
X502417Y710301D01*
X502264Y710766D01*
X502226Y711283D01*
X502302Y711955D01*
X502417Y712316D01*
X502609Y712678D01*
X502877Y712936D01*
X503146Y712988D01*
X503414Y712885D01*
X503606Y712626D01*
G01X498885Y708700D02*
X504226D01*
G01X489100Y1263262D02*
X487600D01*
G01X489100Y1269462D02*
Y1263262D01*
G01X485900Y1264700D02*
Y1268000D01*
G01X490900Y1263262D02*
Y1269462D01*
G01X494100Y1267900D02*
Y1264900D01*
G01X492300Y1263262D02*
X490900D01*
G01X498100D02*
X496600D01*
G01X498100Y1269462D02*
Y1263262D01*
G01X494900Y1264900D02*
Y1267900D01*
G01X485100Y1268000D02*
Y1264700D01*
G01X498400Y1256025D02*
X624519D01*
G01X487600Y1269462D02*
X489100D01*
G01X490900D02*
X492700D01*
G01X496500D02*
X498100D01*
G01X496927Y1406290D02*
X502927D01*
G01Y1447629D02*
X496927D01*
G01X495756Y1643734D02*
X495196Y1644109D01*
X494543Y1644359D01*
X493796D01*
X492956Y1643984D01*
X492303Y1643359D01*
X491836Y1642609D01*
X491463Y1641359D01*
X491370Y1640234D01*
X491556Y1639109D01*
X491836Y1638359D01*
X492396Y1637609D01*
X493050Y1637109D01*
X493703Y1636859D01*
X494356D01*
X495010Y1637109D01*
X495570Y1637484D01*
X496036Y1637984D01*
G01X499336Y1636859D02*
Y1644359D01*
X501576D01*
X502323Y1643984D01*
X502883Y1643109D01*
X503070Y1642109D01*
X502883Y1641109D01*
X502416Y1640359D01*
X501576Y1639984D01*
X499336D01*
G01X506650Y1644359D02*
Y1638984D01*
X507023Y1637859D01*
X507770Y1637109D01*
X508703Y1636859D01*
X509636Y1637109D01*
X510383Y1637859D01*
X510756Y1638984D01*
Y1644359D01*
G01X516203Y1636859D02*
Y1644359D01*
X515083Y1642859D01*
G01Y1636859D02*
X517323D01*
G01X536836D02*
Y1644359D01*
X539076D01*
X539823Y1643984D01*
X540383Y1643109D01*
X540570Y1642109D01*
X540383Y1641109D01*
X539916Y1640359D01*
X539076Y1639984D01*
X536836D01*
G01X548256Y1643734D02*
X547696Y1644109D01*
X547043Y1644359D01*
X546296D01*
X545456Y1643984D01*
X544803Y1643359D01*
X544336Y1642609D01*
X543963Y1641359D01*
X543870Y1640234D01*
X544056Y1639109D01*
X544336Y1638359D01*
X544896Y1637609D01*
X545550Y1637109D01*
X546203Y1636859D01*
X546856D01*
X547510Y1637109D01*
X548070Y1637484D01*
X548536Y1637984D01*
G01X552583Y1644359D02*
X554823D01*
G01X553703D02*
Y1636859D01*
G01X552583D02*
X554823D01*
G01X559803Y1640234D02*
X562790D01*
X562510Y1641109D01*
X562043Y1641609D01*
X561390Y1641859D01*
X560736Y1641734D01*
X560176Y1641359D01*
X559803Y1640484D01*
X559616Y1639734D01*
Y1638984D01*
X559803Y1638234D01*
X560270Y1637484D01*
X560830Y1636984D01*
X561483Y1636859D01*
X562136Y1637109D01*
X562790Y1637859D01*
G01X581836Y1636859D02*
Y1644359D01*
X584076D01*
X584823Y1643984D01*
X585383Y1643109D01*
X585570Y1642109D01*
X585383Y1641109D01*
X584916Y1640359D01*
X584076Y1639984D01*
X581836D01*
G01X589430Y1643109D02*
X589990Y1643859D01*
X590643Y1644234D01*
X591390Y1644359D01*
X592323Y1644109D01*
X592976Y1643484D01*
X593163Y1642734D01*
X593070Y1641984D01*
X592696Y1641359D01*
X590830Y1640109D01*
X589990Y1639234D01*
X589430Y1637984D01*
X589243Y1636859D01*
X593163D01*
G01X606016Y1635484D02*
X606390Y1637109D01*
G01X619336Y1636859D02*
Y1644359D01*
X621576D01*
X622323Y1643984D01*
X622883Y1643109D01*
X623070Y1642109D01*
X622883Y1641109D01*
X622416Y1640359D01*
X621576Y1639984D01*
X619336D01*
G01X626650Y1638359D02*
X627210Y1637484D01*
X627956Y1636984D01*
X628796Y1636859D01*
X629543Y1636984D01*
X630290Y1637609D01*
X630756Y1638359D01*
X630850Y1639109D01*
X630663Y1639984D01*
X630010Y1640609D01*
X629356Y1640859D01*
X628516D01*
G01X629356D02*
X629916Y1641234D01*
X630383Y1641859D01*
X630570Y1642609D01*
X630383Y1643359D01*
X629916Y1643984D01*
X629076Y1644359D01*
X628236Y1644234D01*
X627396Y1643734D01*
G01X496911Y1656012D02*
X493811D01*
X494431Y1655552D01*
G01X496911D02*
Y1656472D01*
G01X490157Y1736118D02*
Y1657834D01*
G01D02*
X556692D01*
G01X487600Y1686125D02*
X484500D01*
G01Y1687581D02*
X486412Y1686125D01*
G01X487600Y1687811D02*
X485533Y1686776D01*
G01X484500Y1681476D02*
X487600D01*
Y1683010D01*
G01Y1676522D02*
X484500D01*
X487083Y1677519D01*
X484500Y1678516D01*
X487600D01*
G01Y1671913D02*
X484500D01*
X487600Y1673677D01*
X484500D01*
G01X486980Y1690925D02*
X487290Y1691117D01*
X487497Y1691347D01*
X487600Y1691615D01*
X487497Y1691922D01*
X487290Y1692152D01*
X486980Y1692382D01*
X486567Y1692459D01*
X484500D01*
G01X487600Y1700336D02*
X484500D01*
G01Y1701946D02*
X487600D01*
G01X486050D02*
Y1700336D01*
G01X484500Y1695957D02*
Y1696877D01*
G01Y1696417D02*
X487600D01*
G01Y1695957D02*
Y1696877D01*
G01Y1716081D02*
Y1714547D01*
X484500D01*
Y1716081D01*
G01X485998Y1715467D02*
Y1714547D01*
G01X487600Y1709862D02*
X484500D01*
Y1711318D01*
G01X485998Y1710782D02*
Y1709862D01*
G01X486050Y1706096D02*
Y1706863D01*
X486980D01*
X487290Y1706633D01*
X487497Y1706364D01*
X487600Y1705981D01*
X487497Y1705598D01*
X487290Y1705329D01*
X486980Y1705099D01*
X486618Y1704946D01*
X486205Y1704869D01*
X485843D01*
X485533Y1704946D01*
X485172Y1705099D01*
X484862Y1705329D01*
X484655Y1705559D01*
X484500Y1705866D01*
Y1706134D01*
X484603Y1706441D01*
X484810Y1706671D01*
G01X487600Y1719196D02*
X484500D01*
Y1719962D01*
X484655Y1720269D01*
X484862Y1720499D01*
X485172Y1720691D01*
X485533Y1720844D01*
X486050Y1720882D01*
X486567Y1720844D01*
X486928Y1720691D01*
X487238Y1720499D01*
X487445Y1720269D01*
X487600Y1719962D01*
Y1719196D01*
G01X485947Y1729795D02*
X485792Y1729948D01*
X485533Y1730063D01*
X485172Y1730140D01*
X484862Y1730063D01*
X484655Y1729910D01*
X484500Y1729641D01*
Y1728606D01*
X487600D01*
Y1729871D01*
X487393Y1730140D01*
X487083Y1730293D01*
X486722Y1730370D01*
X486360Y1730293D01*
X486050Y1730063D01*
X485947Y1729795D01*
Y1728606D01*
G01X484758Y1725606D02*
X484603Y1725376D01*
X484500Y1725108D01*
Y1724801D01*
X484655Y1724456D01*
X484913Y1724188D01*
X485223Y1723996D01*
X485740Y1723843D01*
X486205Y1723805D01*
X486670Y1723881D01*
X486980Y1723996D01*
X487290Y1724226D01*
X487497Y1724495D01*
X487600Y1724763D01*
Y1725031D01*
X487497Y1725300D01*
X487342Y1725530D01*
X487135Y1725721D01*
G01X490157Y1740118D02*
X556692D01*
G01X497178Y1736412D02*
X502178D01*
G01X497178Y1739812D02*
Y1736412D01*
G01X499178Y1737812D02*
X497178Y1739812D01*
G01X495178Y1737812D02*
X499178D01*
G01X497178Y1739812D02*
X495178Y1737812D01*
G01X513939Y81042D02*
Y87242D01*
G01D02*
X517139D01*
G01Y81042D02*
X513939D01*
G01X499914Y120018D02*
Y113818D01*
G01X499985Y112799D02*
Y106599D01*
G01X508507Y125548D02*
X508347Y125756D01*
X508160Y125881D01*
X507920Y125923D01*
X507680Y125840D01*
X507493Y125673D01*
X507360Y125381D01*
X507333Y125048D01*
X507387Y124715D01*
X507520Y124506D01*
X507707Y124340D01*
X507893Y124298D01*
X508080Y124340D01*
X508320Y124506D01*
X508240Y123423D01*
X507520D01*
G01X506227Y123840D02*
X506067Y123590D01*
X505880Y123465D01*
X505667Y123423D01*
X505400Y123506D01*
X505213Y123715D01*
X505160Y123965D01*
X505187Y124215D01*
X505293Y124423D01*
X505827Y124840D01*
X506067Y125131D01*
X506227Y125548D01*
X506280Y125923D01*
X505160D01*
G01X502145Y129660D02*
X501937Y129500D01*
X501812Y129313D01*
X501770Y129073D01*
X501853Y128833D01*
X502020Y128646D01*
X502312Y128513D01*
X502645Y128486D01*
X502978Y128540D01*
X503187Y128673D01*
X503353Y128860D01*
X503395Y129046D01*
X503353Y129233D01*
X503187Y129473D01*
X504270Y129393D01*
Y128673D01*
G01X501770Y126873D02*
X504270D01*
X503770Y127193D01*
G01X501770D02*
Y126553D01*
G01X504018Y134171D02*
X501018D01*
G01X506473Y131671D02*
Y129226D01*
G01D02*
X508918D01*
G01X503968Y142071D02*
X502268D01*
G01X504018Y149871D02*
X501018D01*
G01X501770Y163256D02*
X501478Y163096D01*
X501312Y162882D01*
X501270Y162642D01*
X501312Y162429D01*
X501520Y162216D01*
X501770Y162082D01*
X502020Y162056D01*
X502312Y162109D01*
X502520Y162296D01*
X502603Y162482D01*
Y162722D01*
G01Y162482D02*
X502728Y162322D01*
X502937Y162189D01*
X503187Y162136D01*
X503437Y162189D01*
X503645Y162322D01*
X503770Y162562D01*
X503728Y162802D01*
X503562Y163042D01*
G01X501645Y161056D02*
X501437Y160896D01*
X501312Y160709D01*
X501270Y160469D01*
X501353Y160229D01*
X501520Y160042D01*
X501812Y159909D01*
X502145Y159882D01*
X502478Y159936D01*
X502687Y160069D01*
X502853Y160256D01*
X502895Y160442D01*
X502853Y160629D01*
X502687Y160869D01*
X503770Y160789D01*
Y160069D01*
G01X507407Y167019D02*
X507247Y167311D01*
X507033Y167477D01*
X506793Y167519D01*
X506580Y167477D01*
X506367Y167269D01*
X506233Y167019D01*
X506207Y166769D01*
X506260Y166477D01*
X506447Y166269D01*
X506633Y166186D01*
X506873D01*
G01X506633D02*
X506473Y166061D01*
X506340Y165852D01*
X506287Y165602D01*
X506340Y165352D01*
X506473Y165144D01*
X506713Y165019D01*
X506953Y165061D01*
X507193Y165227D01*
G01X504300Y167519D02*
Y165019D01*
X505287Y166811D01*
X503953D01*
G01X503968Y157771D02*
X502268D01*
G01X508918Y161116D02*
X506473D01*
Y158671D01*
G01X502332Y195116D02*
Y191916D01*
G01Y187116D02*
Y183916D01*
G01X504407Y187116D02*
X510607D01*
G01D02*
Y183916D01*
G01D02*
X504407D01*
G01D02*
Y187116D01*
G01X502332Y191116D02*
Y187916D01*
G01X505876Y207685D02*
X499676D01*
G01D02*
Y210885D01*
G01X505876D02*
Y207685D01*
G01X499676Y206885D02*
X505876D01*
G01D02*
Y203685D01*
G01D02*
X499676D01*
G01D02*
Y206885D01*
G01X506676Y204004D02*
X512876D01*
G01D02*
Y200804D01*
G01D02*
X506676D01*
G01D02*
Y204004D01*
G01X502332Y199116D02*
Y195916D01*
G01X507172Y207593D02*
Y218977D01*
G01X516980Y207593D02*
X507172D01*
G01X505876Y211685D02*
X499676D01*
G01D02*
Y214885D01*
G01D02*
X505876D01*
G01D02*
Y211685D01*
G01X499676Y210885D02*
X505876D01*
G01Y218566D02*
X499676D01*
G01D02*
Y221766D01*
G01D02*
X505876D01*
G01D02*
Y218566D01*
G01X507172Y218977D02*
X516980D01*
G01X510145Y224241D02*
Y244319D01*
G01X526777Y224241D02*
X510145D01*
G01Y244319D02*
X515689D01*
G01X515823Y279121D02*
X509623D01*
G01D02*
Y282321D01*
G01D02*
X515823D01*
G01X503100Y417900D02*
X499900D01*
G01X503100Y424100D02*
Y417900D01*
G01X499900D02*
Y424100D01*
G01X505413Y410416D02*
X507635D01*
X508100Y410569D01*
X508410Y410876D01*
X508513Y411259D01*
X508410Y411642D01*
X508100Y411949D01*
X507635Y412102D01*
X505413D01*
G01X508513Y414359D02*
X508461Y414627D01*
X508306Y414934D01*
X508048Y415126D01*
X507686Y415202D01*
X507325Y415126D01*
X507015Y414896D01*
X506860Y414551D01*
Y414167D01*
X506756Y413937D01*
X506498Y413746D01*
X506136Y413669D01*
X505775Y413784D01*
X505516Y414052D01*
X505413Y414359D01*
X505516Y414666D01*
X505775Y414934D01*
X506136Y415049D01*
X506498Y414972D01*
X506756Y414781D01*
X506860Y414551D01*
Y414167D01*
X507015Y413822D01*
X507325Y413592D01*
X507686Y413516D01*
X508048Y413592D01*
X508306Y413784D01*
X508461Y414091D01*
X508513Y414359D01*
G01X505413Y417459D02*
X505516Y417152D01*
X505775Y416922D01*
X506085Y416769D01*
X506498Y416654D01*
X506963Y416616D01*
X507428Y416654D01*
X507841Y416769D01*
X508151Y416922D01*
X508410Y417152D01*
X508513Y417459D01*
X508410Y417766D01*
X508151Y417996D01*
X507841Y418149D01*
X507428Y418264D01*
X506963Y418302D01*
X506498Y418264D01*
X506085Y418149D01*
X505775Y417996D01*
X505516Y417766D01*
X505413Y417459D01*
G01Y420559D02*
X505516Y420252D01*
X505775Y420022D01*
X506085Y419869D01*
X506498Y419754D01*
X506963Y419716D01*
X507428Y419754D01*
X507841Y419869D01*
X508151Y420022D01*
X508410Y420252D01*
X508513Y420559D01*
X508410Y420866D01*
X508151Y421096D01*
X507841Y421249D01*
X507428Y421364D01*
X506963Y421402D01*
X506498Y421364D01*
X506085Y421249D01*
X505775Y421096D01*
X505516Y420866D01*
X505413Y420559D01*
G01X508513Y423582D02*
X507841Y423659D01*
X507273Y423774D01*
X506756Y423927D01*
X506188Y424119D01*
X505413Y424426D01*
Y422892D01*
G01X503100Y424900D02*
X499900D01*
G01X503100Y431100D02*
Y424900D01*
G01X499900Y431100D02*
X503100D01*
G01X499900Y424900D02*
Y431100D01*
G01X513600Y427900D02*
X510400D01*
G01X513600Y434100D02*
Y427900D01*
G01X510400D02*
Y434100D01*
G01X499900Y424100D02*
X503100D01*
G01X510400Y434100D02*
X513600D01*
G01X511924Y456691D02*
Y454469D01*
X512077Y454004D01*
X512384Y453694D01*
X512767Y453591D01*
X513150Y453694D01*
X513457Y454004D01*
X513610Y454469D01*
Y456691D01*
G01X515867Y453591D02*
X516135Y453643D01*
X516442Y453798D01*
X516634Y454056D01*
X516710Y454418D01*
X516634Y454779D01*
X516404Y455089D01*
X516059Y455244D01*
X515675D01*
X515445Y455348D01*
X515254Y455606D01*
X515177Y455968D01*
X515292Y456329D01*
X515560Y456588D01*
X515867Y456691D01*
X516174Y456588D01*
X516442Y456329D01*
X516557Y455968D01*
X516480Y455606D01*
X516289Y455348D01*
X516059Y455244D01*
X515675D01*
X515330Y455089D01*
X515100Y454779D01*
X515024Y454418D01*
X515100Y454056D01*
X515292Y453798D01*
X515599Y453643D01*
X515867Y453591D01*
G01X518967Y456691D02*
X518660Y456588D01*
X518430Y456329D01*
X518277Y456019D01*
X518162Y455606D01*
X518124Y455141D01*
X518162Y454676D01*
X518277Y454263D01*
X518430Y453953D01*
X518660Y453694D01*
X518967Y453591D01*
X519274Y453694D01*
X519504Y453953D01*
X519657Y454263D01*
X519772Y454676D01*
X519810Y455141D01*
X519772Y455606D01*
X519657Y456019D01*
X519504Y456329D01*
X519274Y456588D01*
X518967Y456691D01*
G01X522067D02*
X521760Y456588D01*
X521530Y456329D01*
X521377Y456019D01*
X521262Y455606D01*
X521224Y455141D01*
X521262Y454676D01*
X521377Y454263D01*
X521530Y453953D01*
X521760Y453694D01*
X522067Y453591D01*
X522374Y453694D01*
X522604Y453953D01*
X522757Y454263D01*
X522872Y454676D01*
X522910Y455141D01*
X522872Y455606D01*
X522757Y456019D01*
X522604Y456329D01*
X522374Y456588D01*
X522067Y456691D01*
G01X525167Y453591D02*
X525435Y453643D01*
X525742Y453798D01*
X525934Y454056D01*
X526010Y454418D01*
X525934Y454779D01*
X525704Y455089D01*
X525359Y455244D01*
X524975D01*
X524745Y455348D01*
X524554Y455606D01*
X524477Y455968D01*
X524592Y456329D01*
X524860Y456588D01*
X525167Y456691D01*
X525474Y456588D01*
X525742Y456329D01*
X525857Y455968D01*
X525780Y455606D01*
X525589Y455348D01*
X525359Y455244D01*
X524975D01*
X524630Y455089D01*
X524400Y454779D01*
X524324Y454418D01*
X524400Y454056D01*
X524592Y453798D01*
X524899Y453643D01*
X525167Y453591D01*
G01X512724Y594850D02*
Y601050D01*
G01X515924Y594850D02*
X512724D01*
G01Y601050D02*
X515924D01*
G01X512245Y604453D02*
X511512D01*
G01D02*
Y606644D01*
G01X501398Y612813D02*
Y619013D01*
G01D02*
X504598D01*
G01D02*
Y612813D01*
G01D02*
X501398D01*
G01X505364Y612821D02*
Y619021D01*
G01D02*
X508564D01*
G01D02*
Y612821D01*
G01D02*
X505364D01*
G01X511512Y625475D02*
Y628075D01*
G01X500261Y634340D02*
Y628140D01*
G01X504155Y642971D02*
Y636771D01*
G01D02*
X500955D01*
G01D02*
Y638500D01*
G01Y641000D02*
Y642971D01*
G01X511512Y628075D02*
X512305D01*
G01X507298Y674600D02*
Y631292D01*
G01D02*
X512639D01*
G01X500955Y642971D02*
X504155D01*
G01X500955Y647271D02*
Y653471D01*
G01D02*
X504155D01*
G01D02*
Y647271D01*
G01D02*
X500955D01*
G01X504132Y660292D02*
Y654092D01*
G01D02*
X500932D01*
G01D02*
Y660292D01*
G01X499498Y663792D02*
X505698D01*
G01D02*
Y660592D01*
G01D02*
X499498D01*
G01D02*
Y663792D01*
G01X500932Y660292D02*
X504132D01*
G01X504226Y708700D02*
Y665392D01*
G01X512639Y674600D02*
X507298D01*
G01X533700Y870789D02*
X511500D01*
G01X506100Y1393820D02*
X604500D01*
G01X502927Y1406290D02*
Y1412290D01*
G01Y1441629D02*
Y1447629D01*
G01X508670Y1576413D02*
X506244D01*
G01X547298Y1569365D02*
X511558D01*
Y1586295D01*
X547298D01*
Y1569365D01*
G01X512039Y1655169D02*
X512401Y1655399D01*
X512607Y1655705D01*
X512659Y1656050D01*
X512607Y1656357D01*
X512349Y1656664D01*
X512039Y1656855D01*
X511729Y1656894D01*
X511367Y1656817D01*
X511109Y1656549D01*
X511006Y1656280D01*
Y1655935D01*
G01Y1656280D02*
X510851Y1656510D01*
X510592Y1656702D01*
X510282Y1656779D01*
X509972Y1656702D01*
X509714Y1656510D01*
X509559Y1656165D01*
X509611Y1655820D01*
X509817Y1655475D01*
G01X502202Y1655284D02*
X501892Y1655514D01*
X501737Y1655782D01*
X501685Y1656089D01*
X501788Y1656472D01*
X502047Y1656740D01*
X502357Y1656817D01*
X502667Y1656779D01*
X502925Y1656625D01*
X503442Y1655859D01*
X503803Y1655514D01*
X504320Y1655284D01*
X504785Y1655207D01*
Y1656817D01*
G01X505261Y1736629D02*
X504195D01*
Y1739129D01*
X505261D01*
G01X504835Y1737921D02*
X504195D01*
G01X506341Y1736629D02*
Y1739129D01*
X506875D01*
X507088Y1739004D01*
X507248Y1738837D01*
X507381Y1738587D01*
X507488Y1738296D01*
X507515Y1737879D01*
X507488Y1737462D01*
X507381Y1737171D01*
X507248Y1736921D01*
X507088Y1736754D01*
X506875Y1736629D01*
X506341D01*
G01X509288Y1737879D02*
X509821D01*
Y1737129D01*
X509661Y1736879D01*
X509475Y1736712D01*
X509208Y1736629D01*
X508941Y1736712D01*
X508755Y1736879D01*
X508595Y1737129D01*
X508488Y1737421D01*
X508435Y1737754D01*
Y1738046D01*
X508488Y1738296D01*
X508595Y1738587D01*
X508755Y1738837D01*
X508915Y1739004D01*
X509128Y1739129D01*
X509315D01*
X509528Y1739046D01*
X509688Y1738879D01*
G01X511861Y1736629D02*
X510795D01*
Y1739129D01*
X511861D01*
G01X511435Y1737921D02*
X510795D01*
G01X515728Y1736629D02*
X515515Y1736671D01*
X515328Y1736837D01*
X515168Y1737087D01*
X515061Y1737379D01*
X515008Y1737712D01*
Y1738046D01*
X515061Y1738379D01*
X515168Y1738671D01*
X515328Y1738921D01*
X515515Y1739087D01*
X515728Y1739129D01*
X515941Y1739087D01*
X516128Y1738921D01*
X516288Y1738671D01*
X516395Y1738379D01*
X516448Y1738046D01*
Y1737712D01*
X516395Y1737379D01*
X516288Y1737087D01*
X516128Y1736837D01*
X515941Y1736671D01*
X515728Y1736629D01*
G01X517421D02*
Y1739129D01*
X518435D01*
G01X518061Y1737921D02*
X517421D01*
G01X521741Y1736629D02*
Y1739129D01*
X522275D01*
X522488Y1739004D01*
X522648Y1738837D01*
X522781Y1738587D01*
X522888Y1738296D01*
X522915Y1737879D01*
X522888Y1737462D01*
X522781Y1737171D01*
X522648Y1736921D01*
X522488Y1736754D01*
X522275Y1736629D01*
X521741D01*
G01X523861D02*
X524528Y1739129D01*
X525195Y1736629D01*
G01X524955Y1737504D02*
X524101D01*
G01X526141Y1739129D02*
Y1737337D01*
X526248Y1736962D01*
X526461Y1736712D01*
X526728Y1736629D01*
X526995Y1736712D01*
X527208Y1736962D01*
X527315Y1737337D01*
Y1739129D01*
G01X529088Y1737879D02*
X529621D01*
Y1737129D01*
X529461Y1736879D01*
X529275Y1736712D01*
X529008Y1736629D01*
X528741Y1736712D01*
X528555Y1736879D01*
X528395Y1737129D01*
X528288Y1737421D01*
X528235Y1737754D01*
Y1738046D01*
X528288Y1738296D01*
X528395Y1738587D01*
X528555Y1738837D01*
X528715Y1739004D01*
X528928Y1739129D01*
X529115D01*
X529328Y1739046D01*
X529488Y1738879D01*
G01X530568Y1736629D02*
Y1739129D01*
G01X531688D02*
Y1736629D01*
G01Y1737879D02*
X530568D01*
G01X533328Y1739129D02*
Y1736629D01*
G01X532715Y1739129D02*
X533941D01*
G01X536061Y1736629D02*
X534995D01*
Y1739129D01*
X536061D01*
G01X535635Y1737921D02*
X534995D01*
G01X537195Y1736629D02*
Y1739129D01*
X537861D01*
X538075Y1739004D01*
X538208Y1738837D01*
X538261Y1738504D01*
X538208Y1738171D01*
X538048Y1737962D01*
X537861Y1737837D01*
X537195D01*
G01X537861D02*
X538261Y1736629D01*
G01X542715Y1738921D02*
X542555Y1739046D01*
X542368Y1739129D01*
X542155D01*
X541915Y1739004D01*
X541728Y1738796D01*
X541595Y1738546D01*
X541488Y1738129D01*
X541461Y1737754D01*
X541515Y1737379D01*
X541595Y1737129D01*
X541755Y1736879D01*
X541941Y1736712D01*
X542128Y1736629D01*
X542315D01*
X542501Y1736712D01*
X542661Y1736837D01*
X542795Y1737004D01*
G01X543661Y1736629D02*
X544328Y1739129D01*
X544995Y1736629D01*
G01X544755Y1737504D02*
X543901D01*
G01X545995Y1736629D02*
Y1739129D01*
X546661D01*
X546875Y1739004D01*
X547008Y1738837D01*
X547061Y1738504D01*
X547008Y1738171D01*
X546848Y1737962D01*
X546661Y1737837D01*
X545995D01*
G01X546661D02*
X547061Y1736629D01*
G01X548141D02*
Y1739129D01*
X548675D01*
X548888Y1739004D01*
X549048Y1738837D01*
X549181Y1738587D01*
X549288Y1738296D01*
X549315Y1737879D01*
X549288Y1737462D01*
X549181Y1737171D01*
X549048Y1736921D01*
X548888Y1736754D01*
X548675Y1736629D01*
X548141D01*
G01X502178Y1736412D02*
X503078Y1737312D01*
G01X533100Y71929D02*
X525400D01*
G01X517139Y87242D02*
Y81042D01*
G01X514618Y126821D02*
Y125121D01*
G01X522418Y123771D02*
Y126771D01*
G01X516118Y163571D02*
Y166571D01*
G01X523918Y163521D02*
Y165221D01*
G01X520488Y202760D02*
Y208960D01*
G01D02*
X523688D01*
G01D02*
Y202760D01*
G01D02*
X520488D01*
G01X529904Y209397D02*
X526704D01*
G01D02*
Y215597D01*
G01X521899Y201125D02*
Y198903D01*
X522052Y198438D01*
X522359Y198128D01*
X522742Y198025D01*
X523125Y198128D01*
X523432Y198438D01*
X523585Y198903D01*
Y201125D01*
G01X525842Y198025D02*
Y201125D01*
X525382Y200505D01*
G01Y198025D02*
X526302D01*
G01X528099Y198490D02*
X528329Y198232D01*
X528597Y198077D01*
X528942Y198025D01*
X529287Y198128D01*
X529555Y198335D01*
X529747Y198697D01*
X529785Y199110D01*
X529709Y199523D01*
X529517Y199782D01*
X529249Y199988D01*
X528980Y200040D01*
X528712Y199988D01*
X528367Y199782D01*
X528482Y201125D01*
X529517D01*
G01X531314Y200608D02*
X531544Y200918D01*
X531812Y201073D01*
X532119Y201125D01*
X532502Y201022D01*
X532770Y200763D01*
X532847Y200453D01*
X532809Y200143D01*
X532655Y199885D01*
X531889Y199368D01*
X531544Y199007D01*
X531314Y198490D01*
X531237Y198025D01*
X532847D01*
G01X516980Y218977D02*
Y207593D01*
G01X526704Y215597D02*
X529904D01*
G01X526777Y244319D02*
Y224241D01*
G01X515415Y249748D02*
Y247526D01*
X515568Y247061D01*
X515875Y246751D01*
X516258Y246648D01*
X516641Y246751D01*
X516948Y247061D01*
X517101Y247526D01*
Y249748D01*
G01X518630Y249231D02*
X518860Y249541D01*
X519128Y249696D01*
X519435Y249748D01*
X519818Y249645D01*
X520086Y249386D01*
X520163Y249076D01*
X520125Y248766D01*
X519971Y248508D01*
X519205Y247991D01*
X518860Y247630D01*
X518630Y247113D01*
X518553Y246648D01*
X520163D01*
G01X522458D02*
Y249748D01*
X521998Y249128D01*
G01Y246648D02*
X522918D01*
G01X524830Y249231D02*
X525060Y249541D01*
X525328Y249696D01*
X525635Y249748D01*
X526018Y249645D01*
X526286Y249386D01*
X526363Y249076D01*
X526325Y248766D01*
X526171Y248508D01*
X525405Y247991D01*
X525060Y247630D01*
X524830Y247113D01*
X524753Y246648D01*
X526363D01*
G01X518461Y241547D02*
X521233Y244319D01*
G01X515689D02*
X518461Y241547D01*
G01X521233Y244319D02*
X526777D01*
G01X515823Y282321D02*
Y279121D01*
G01X522578Y290014D02*
Y283925D01*
G01Y310303D02*
Y304214D01*
G01X516900Y427900D02*
Y434100D01*
G01X520100Y427900D02*
X516900D01*
G01X520100Y434100D02*
Y427900D01*
G01X524900Y430900D02*
Y434100D01*
G01X531100Y430900D02*
X524900D01*
G01X520900Y427900D02*
Y434100D01*
G01X524100Y427900D02*
X520900D01*
G01X524100Y434100D02*
Y427900D01*
G01X516900Y434100D02*
X520100D01*
G01X524900D02*
X531100D01*
G01X520900D02*
X524100D01*
G01X526500Y448102D02*
X532500D01*
G01X524500Y445000D02*
X526500Y448102D01*
G01X522500D02*
X524500Y445000D01*
G01X516500Y448102D02*
X522500D01*
G01X516500Y435898D02*
Y448102D01*
G01X532500Y435898D02*
X516500D01*
G01X515924Y601050D02*
Y594850D01*
G01X523391Y597346D02*
X529591D01*
G01Y594146D02*
X523391D01*
G01D02*
Y597346D01*
G01X519966Y601050D02*
Y594850D01*
G01D02*
X516766D01*
G01D02*
Y601050D01*
G01D02*
X519966D01*
G01X525347Y680158D02*
Y683258D01*
X526267D01*
X526574Y683103D01*
X526804Y682741D01*
X526881Y682328D01*
X526804Y681915D01*
X526612Y681605D01*
X526267Y681450D01*
X525347D01*
G01X528447Y683258D02*
Y680158D01*
X529981D01*
G01X531471Y680778D02*
X531701Y680416D01*
X532007Y680210D01*
X532352Y680158D01*
X532659Y680210D01*
X532966Y680468D01*
X533157Y680778D01*
X533196Y681088D01*
X533119Y681450D01*
X532851Y681708D01*
X532582Y681811D01*
X532237D01*
G01X532582D02*
X532812Y681966D01*
X533004Y682225D01*
X533081Y682535D01*
X533004Y682845D01*
X532812Y683103D01*
X532467Y683258D01*
X532122Y683206D01*
X531777Y683000D01*
G01X535414Y680158D02*
X535682Y680210D01*
X535989Y680365D01*
X536181Y680623D01*
X536257Y680985D01*
X536181Y681346D01*
X535951Y681656D01*
X535606Y681811D01*
X535222D01*
X534992Y681915D01*
X534801Y682173D01*
X534724Y682535D01*
X534839Y682896D01*
X535107Y683155D01*
X535414Y683258D01*
X535721Y683155D01*
X535989Y682896D01*
X536104Y682535D01*
X536027Y682173D01*
X535836Y681915D01*
X535606Y681811D01*
X535222D01*
X534877Y681656D01*
X534647Y681346D01*
X534571Y680985D01*
X534647Y680623D01*
X534839Y680365D01*
X535146Y680210D01*
X535414Y680158D01*
G01X527472Y1167639D02*
Y1180631D01*
G01X529441Y1182600D02*
G03X527472Y1180631I-1J-1968D01*
G01X531370Y1507451D02*
X524200D01*
G01Y1542491D02*
X531370D01*
G01X520533Y1656472D02*
X517433D01*
X519655Y1655054D01*
Y1656970D01*
G01X527942Y1655169D02*
X528200Y1655399D01*
X528355Y1655667D01*
X528407Y1656012D01*
X528304Y1656357D01*
X528097Y1656625D01*
X527735Y1656817D01*
X527322Y1656855D01*
X526909Y1656779D01*
X526650Y1656587D01*
X526444Y1656319D01*
X526392Y1656050D01*
X526444Y1655782D01*
X526650Y1655437D01*
X525307Y1655552D01*
Y1656587D01*
G01X541531Y121730D02*
Y127930D01*
G01D02*
X544731D01*
G01Y121730D02*
X541531D01*
G01X539923Y125381D02*
X539736Y125090D01*
X539576Y124923D01*
X539363Y124840D01*
X539176Y124923D01*
X539043Y125090D01*
X538936Y125340D01*
X538909Y125631D01*
X538936Y125881D01*
X539043Y126131D01*
X539203Y126340D01*
X539389Y126423D01*
X539603Y126340D01*
X539789Y126090D01*
X539896Y125715D01*
X539923Y125298D01*
X539869Y124756D01*
X539789Y124465D01*
X539656Y124173D01*
X539469Y123965D01*
X539283Y123923D01*
X539096Y124006D01*
X538963Y124215D01*
G01X537216Y126423D02*
X537029Y126381D01*
X536816Y126256D01*
X536683Y126048D01*
X536629Y125756D01*
X536683Y125465D01*
X536843Y125215D01*
X537083Y125090D01*
X537349D01*
X537509Y125006D01*
X537643Y124798D01*
X537696Y124506D01*
X537616Y124215D01*
X537429Y124006D01*
X537216Y123923D01*
X537003Y124006D01*
X536816Y124215D01*
X536736Y124506D01*
X536789Y124798D01*
X536923Y125006D01*
X537083Y125090D01*
X537349D01*
X537589Y125215D01*
X537749Y125465D01*
X537803Y125756D01*
X537749Y126048D01*
X537616Y126256D01*
X537403Y126381D01*
X537216Y126423D01*
G01X530318Y126821D02*
Y125121D01*
G01X535918Y129226D02*
X538363D01*
Y131671D01*
G01X543818Y146771D02*
X540818D01*
G01X542468Y138971D02*
X540768D01*
G01X540216Y166019D02*
Y163519D01*
X540536Y164019D01*
G01Y166019D02*
X539896D01*
G01X538016D02*
X537829Y165977D01*
X537616Y165852D01*
X537483Y165644D01*
X537429Y165352D01*
X537483Y165061D01*
X537643Y164811D01*
X537883Y164686D01*
X538149D01*
X538309Y164602D01*
X538443Y164394D01*
X538496Y164102D01*
X538416Y163811D01*
X538229Y163602D01*
X538016Y163519D01*
X537803Y163602D01*
X537616Y163811D01*
X537536Y164102D01*
X537589Y164394D01*
X537723Y164602D01*
X537883Y164686D01*
X538149D01*
X538389Y164811D01*
X538549Y165061D01*
X538603Y165352D01*
X538549Y165644D01*
X538416Y165852D01*
X538203Y165977D01*
X538016Y166019D01*
G01X541466Y161569D02*
X543966D01*
X543466Y161889D01*
G01X541466D02*
Y161249D01*
G01Y159422D02*
X542008Y159369D01*
X542466Y159289D01*
X542883Y159182D01*
X543341Y159049D01*
X543966Y158836D01*
Y159902D01*
G01X531818Y163571D02*
Y166571D01*
G01X542568Y154671D02*
X540868D01*
G01X538363Y158671D02*
Y161116D01*
X535918D01*
G01X539229Y170666D02*
Y168444D01*
X539382Y167979D01*
X539689Y167669D01*
X540072Y167566D01*
X540455Y167669D01*
X540762Y167979D01*
X540915Y168444D01*
Y170666D01*
G01X542444Y168858D02*
X542712Y169219D01*
X542942Y169426D01*
X543249Y169529D01*
X543517Y169426D01*
X543709Y169219D01*
X543862Y168909D01*
X543900Y168548D01*
X543862Y168238D01*
X543709Y167928D01*
X543479Y167669D01*
X543210Y167566D01*
X542904Y167669D01*
X542635Y167979D01*
X542482Y168444D01*
X542444Y168961D01*
X542520Y169633D01*
X542635Y169994D01*
X542827Y170356D01*
X543095Y170614D01*
X543364Y170666D01*
X543632Y170563D01*
X543824Y170304D01*
G01X546272Y170666D02*
X545965Y170563D01*
X545735Y170304D01*
X545582Y169994D01*
X545467Y169581D01*
X545429Y169116D01*
X545467Y168651D01*
X545582Y168238D01*
X545735Y167928D01*
X545965Y167669D01*
X546272Y167566D01*
X546579Y167669D01*
X546809Y167928D01*
X546962Y168238D01*
X547077Y168651D01*
X547115Y169116D01*
X547077Y169581D01*
X546962Y169994D01*
X546809Y170304D01*
X546579Y170563D01*
X546272Y170666D01*
G01X549372D02*
X549065Y170563D01*
X548835Y170304D01*
X548682Y169994D01*
X548567Y169581D01*
X548529Y169116D01*
X548567Y168651D01*
X548682Y168238D01*
X548835Y167928D01*
X549065Y167669D01*
X549372Y167566D01*
X549679Y167669D01*
X549909Y167928D01*
X550062Y168238D01*
X550177Y168651D01*
X550215Y169116D01*
X550177Y169581D01*
X550062Y169994D01*
X549909Y170304D01*
X549679Y170563D01*
X549372Y170666D01*
G01X552472Y167566D02*
Y170666D01*
X552012Y170046D01*
G01Y167566D02*
X552932D01*
G01X546296Y193656D02*
X540096D01*
G01D02*
Y196856D01*
G01X546296Y188656D02*
X540096D01*
G01D02*
Y191856D01*
G01D02*
X546296D01*
G01X529904Y215597D02*
Y209397D01*
G01X546296Y197656D02*
X540096D01*
G01D02*
Y200856D01*
G01D02*
X546296D01*
G01X540096Y196856D02*
X546296D01*
G01X541888Y220041D02*
X548088D01*
G01Y216841D02*
X541888D01*
G01D02*
Y220041D01*
G01X548088Y220841D02*
X541888D01*
G01D02*
Y224041D01*
G01D02*
X548088D01*
G01Y224841D02*
X541888D01*
G01D02*
Y228041D01*
G01Y232041D02*
X548088D01*
G01Y228841D02*
X541888D01*
G01D02*
Y232041D01*
G01X548088Y233960D02*
X541888D01*
G01D02*
Y237160D01*
G01D02*
X548088D01*
G01Y237966D02*
X541888D01*
G01D02*
Y241166D01*
G01Y228041D02*
X548088D01*
G01X534577Y242105D02*
Y248305D01*
G01D02*
X537777D01*
G01D02*
Y242105D01*
G01D02*
X534577D01*
G01X541888Y241166D02*
X548088D01*
G01X614016Y269410D02*
X534016D01*
G01D02*
Y279134D01*
G01X538616Y280306D02*
X538884Y280358D01*
X539191Y280513D01*
X539383Y280771D01*
X539459Y281133D01*
X539383Y281494D01*
X539153Y281804D01*
X538808Y281959D01*
X538424D01*
X538194Y282063D01*
X538003Y282321D01*
X537926Y282683D01*
X538041Y283044D01*
X538309Y283303D01*
X538616Y283406D01*
X538923Y283303D01*
X539191Y283044D01*
X539306Y282683D01*
X539229Y282321D01*
X539038Y282063D01*
X538808Y281959D01*
X538424D01*
X538079Y281804D01*
X537849Y281494D01*
X537773Y281133D01*
X537849Y280771D01*
X538041Y280513D01*
X538348Y280358D01*
X538616Y280306D01*
G01X534016Y279134D02*
X614016D01*
G01X543242Y290668D02*
X537042D01*
G01D02*
Y293868D01*
G01D02*
X543242D01*
G01D02*
Y290668D01*
G01X545508Y295168D02*
X540908D01*
G01X541008D02*
X540908D01*
G01D02*
Y305168D01*
G01X546871Y306161D02*
X540871D01*
G01D02*
Y318161D01*
G01X545508Y305168D02*
X540908D01*
G01X540871Y318161D02*
X546871D01*
G01X542525Y323784D02*
Y326884D01*
X543445D01*
X543752Y326729D01*
X543982Y326367D01*
X544059Y325954D01*
X543982Y325541D01*
X543790Y325231D01*
X543445Y325076D01*
X542525D01*
G01X545549Y326884D02*
Y324662D01*
X545702Y324197D01*
X546009Y323887D01*
X546392Y323784D01*
X546775Y323887D01*
X547082Y324197D01*
X547235Y324662D01*
Y326884D01*
G01X548764Y325076D02*
X549032Y325437D01*
X549262Y325644D01*
X549569Y325747D01*
X549837Y325644D01*
X550029Y325437D01*
X550182Y325127D01*
X550220Y324766D01*
X550182Y324456D01*
X550029Y324146D01*
X549799Y323887D01*
X549530Y323784D01*
X549224Y323887D01*
X548955Y324197D01*
X548802Y324662D01*
X548764Y325179D01*
X548840Y325851D01*
X548955Y326212D01*
X549147Y326574D01*
X549415Y326832D01*
X549684Y326884D01*
X549952Y326781D01*
X550144Y326522D01*
G01X552592Y326884D02*
X552285Y326781D01*
X552055Y326522D01*
X551902Y326212D01*
X551787Y325799D01*
X551749Y325334D01*
X551787Y324869D01*
X551902Y324456D01*
X552055Y324146D01*
X552285Y323887D01*
X552592Y323784D01*
X552899Y323887D01*
X553129Y324146D01*
X553282Y324456D01*
X553397Y324869D01*
X553435Y325334D01*
X553397Y325799D01*
X553282Y326212D01*
X553129Y326522D01*
X552899Y326781D01*
X552592Y326884D01*
G01X555692D02*
X555385Y326781D01*
X555155Y326522D01*
X555002Y326212D01*
X554887Y325799D01*
X554849Y325334D01*
X554887Y324869D01*
X555002Y324456D01*
X555155Y324146D01*
X555385Y323887D01*
X555692Y323784D01*
X555999Y323887D01*
X556229Y324146D01*
X556382Y324456D01*
X556497Y324869D01*
X556535Y325334D01*
X556497Y325799D01*
X556382Y326212D01*
X556229Y326522D01*
X555999Y326781D01*
X555692Y326884D01*
G01X558792D02*
X558485Y326781D01*
X558255Y326522D01*
X558102Y326212D01*
X557987Y325799D01*
X557949Y325334D01*
X557987Y324869D01*
X558102Y324456D01*
X558255Y324146D01*
X558485Y323887D01*
X558792Y323784D01*
X559099Y323887D01*
X559329Y324146D01*
X559482Y324456D01*
X559597Y324869D01*
X559635Y325334D01*
X559597Y325799D01*
X559482Y326212D01*
X559329Y326522D01*
X559099Y326781D01*
X558792Y326884D01*
G01X531100Y434100D02*
Y430900D01*
G01X534900Y443900D02*
Y447100D01*
G01X541100Y443900D02*
X534900D01*
G01X541100Y447100D02*
Y443900D01*
G01X534900Y447100D02*
X541100D01*
G01X532500Y448102D02*
Y435898D01*
G01X535457Y469600D02*
Y467378D01*
X535610Y466913D01*
X535917Y466603D01*
X536300Y466500D01*
X536683Y466603D01*
X536990Y466913D01*
X537143Y467378D01*
Y469600D01*
G01X539400Y466500D02*
X539668Y466552D01*
X539975Y466707D01*
X540167Y466965D01*
X540243Y467327D01*
X540167Y467688D01*
X539937Y467998D01*
X539592Y468153D01*
X539208D01*
X538978Y468257D01*
X538787Y468515D01*
X538710Y468877D01*
X538825Y469238D01*
X539093Y469497D01*
X539400Y469600D01*
X539707Y469497D01*
X539975Y469238D01*
X540090Y468877D01*
X540013Y468515D01*
X539822Y468257D01*
X539592Y468153D01*
X539208D01*
X538863Y467998D01*
X538633Y467688D01*
X538557Y467327D01*
X538633Y466965D01*
X538825Y466707D01*
X539132Y466552D01*
X539400Y466500D01*
G01X542500Y469600D02*
X542193Y469497D01*
X541963Y469238D01*
X541810Y468928D01*
X541695Y468515D01*
X541657Y468050D01*
X541695Y467585D01*
X541810Y467172D01*
X541963Y466862D01*
X542193Y466603D01*
X542500Y466500D01*
X542807Y466603D01*
X543037Y466862D01*
X543190Y467172D01*
X543305Y467585D01*
X543343Y468050D01*
X543305Y468515D01*
X543190Y468928D01*
X543037Y469238D01*
X542807Y469497D01*
X542500Y469600D01*
G01X545600Y466500D02*
Y469600D01*
X545140Y468980D01*
G01Y466500D02*
X546060D01*
G01X548700Y469600D02*
X548393Y469497D01*
X548163Y469238D01*
X548010Y468928D01*
X547895Y468515D01*
X547857Y468050D01*
X547895Y467585D01*
X548010Y467172D01*
X548163Y466862D01*
X548393Y466603D01*
X548700Y466500D01*
X549007Y466603D01*
X549237Y466862D01*
X549390Y467172D01*
X549505Y467585D01*
X549543Y468050D01*
X549505Y468515D01*
X549390Y468928D01*
X549237Y469238D01*
X549007Y469497D01*
X548700Y469600D01*
G01X533561Y600240D02*
Y594040D01*
G01D02*
X530361D01*
G01D02*
Y600240D01*
G01X541103Y600016D02*
Y593816D01*
G01D02*
X537903D01*
G01D02*
Y600016D01*
G01X529591Y597346D02*
Y594146D01*
G01X544971Y593828D02*
X541771D01*
G01D02*
Y600028D01*
G01X530361Y600240D02*
X533561D01*
G01X537455Y608871D02*
Y602671D01*
G01D02*
X534255D01*
G01D02*
Y604600D01*
G01Y608871D02*
X537455D01*
G01X534255Y606900D02*
Y608871D01*
G01X537903Y600016D02*
X541103D01*
G01X541771Y600028D02*
X544971D01*
G01X531198Y606307D02*
Y604453D01*
G01D02*
X530190D01*
G01X534255Y613171D02*
Y619371D01*
G01D02*
X537455D01*
G01D02*
Y613171D01*
G01D02*
X534255D01*
G01X538998Y629692D02*
Y626492D01*
G01D02*
X532798D01*
G01D02*
Y629692D01*
G01X537432Y626192D02*
Y619992D01*
G01D02*
X534232D01*
G01D02*
Y626192D01*
G01D02*
X537432D01*
G01X544987Y618716D02*
X540992D01*
G01D02*
Y644306D01*
G01X531198Y628075D02*
Y625475D01*
G01Y618864D02*
Y617166D01*
G01X532798Y629692D02*
X538998D01*
G01X530405Y628075D02*
X531198D01*
G01X536826Y674600D02*
Y631292D01*
G01D02*
X531485D01*
G01X541574Y645690D02*
Y648790D01*
X542494D01*
X542801Y648635D01*
X543031Y648273D01*
X543108Y647860D01*
X543031Y647447D01*
X542839Y647137D01*
X542494Y646982D01*
X541574D01*
G01X544674Y648790D02*
Y645690D01*
X546208D01*
G01X547698Y646310D02*
X547928Y645948D01*
X548234Y645742D01*
X548579Y645690D01*
X548886Y645742D01*
X549193Y646000D01*
X549384Y646310D01*
X549423Y646620D01*
X549346Y646982D01*
X549078Y647240D01*
X548809Y647343D01*
X548464D01*
G01X548809D02*
X549039Y647498D01*
X549231Y647757D01*
X549308Y648067D01*
X549231Y648377D01*
X549039Y648635D01*
X548694Y648790D01*
X548349Y648738D01*
X548004Y648532D01*
G01X552101Y645690D02*
Y648790D01*
X550683Y646568D01*
X552599D01*
G01X540992Y644306D02*
X544987D01*
G01X541706Y664400D02*
Y658200D01*
G01D02*
X538506D01*
G01D02*
Y664400D01*
G01D02*
X541706D01*
G01X542637Y665289D02*
X548837D01*
G01Y662089D02*
X542637D01*
G01D02*
Y665289D01*
G01X548837Y657889D02*
X542637D01*
G01D02*
Y661089D01*
G01D02*
X548837D01*
G01X531485Y674600D02*
X536826D01*
G01X533181Y857797D02*
G03X535149Y855828I1968J-1D01*
G01X533181Y857797D02*
Y870789D01*
G01X536000Y855828D02*
X535149D01*
G01X545100Y870789D02*
X541800D01*
G01X543220Y1180631D02*
Y1167639D01*
G01X529441Y1182600D02*
X541252D01*
G01X543220Y1180631D02*
G03X541252Y1182600I-1969J0D01*
G01X531370Y1542491D02*
Y1507451D01*
G01X539372Y1517620D02*
X545372D01*
Y1514620D01*
X539372D01*
Y1517620D01*
G01X536170Y1518320D02*
Y1524520D01*
X539370D01*
Y1518320D01*
X536170D01*
G01X542072D02*
Y1524520D01*
X545272D01*
Y1518320D01*
X542072D01*
G01X542322Y1510620D02*
X536122D01*
Y1513820D01*
X542322D01*
Y1510620D01*
G01X545472D02*
X539272D01*
Y1513820D01*
X545472D01*
Y1510620D01*
G01X542322Y1514520D02*
X536122D01*
Y1517720D01*
X542322D01*
Y1514520D01*
G01X543310Y1536503D02*
Y1539911D01*
G01X561026Y1536503D02*
X543310D01*
G01Y1550811D02*
Y1554219D01*
G01X543151Y1558758D02*
Y1555658D01*
X544685D01*
G01X547018D02*
X547286Y1555710D01*
X547593Y1555865D01*
X547785Y1556123D01*
X547861Y1556485D01*
X547785Y1556846D01*
X547555Y1557156D01*
X547210Y1557311D01*
X546826D01*
X546596Y1557415D01*
X546405Y1557673D01*
X546328Y1558035D01*
X546443Y1558396D01*
X546711Y1558655D01*
X547018Y1558758D01*
X547325Y1558655D01*
X547593Y1558396D01*
X547708Y1558035D01*
X547631Y1557673D01*
X547440Y1557415D01*
X547210Y1557311D01*
X546826D01*
X546481Y1557156D01*
X546251Y1556846D01*
X546175Y1556485D01*
X546251Y1556123D01*
X546443Y1555865D01*
X546750Y1555710D01*
X547018Y1555658D01*
G01X543310Y1554219D02*
X561026D01*
G01X535885Y1567819D02*
X535655Y1567974D01*
X535387Y1568077D01*
X535080D01*
X534735Y1567922D01*
X534467Y1567664D01*
X534275Y1567354D01*
X534122Y1566837D01*
X534084Y1566372D01*
X534160Y1565907D01*
X534275Y1565597D01*
X534505Y1565287D01*
X534774Y1565080D01*
X535042Y1564977D01*
X535310D01*
X535579Y1565080D01*
X535809Y1565235D01*
X536000Y1565442D01*
G01X538065Y1564977D02*
X538142Y1565649D01*
X538257Y1566217D01*
X538410Y1566734D01*
X538602Y1567302D01*
X538909Y1568077D01*
X537375D01*
G01X541242D02*
X540935Y1567974D01*
X540705Y1567715D01*
X540552Y1567405D01*
X540437Y1566992D01*
X540399Y1566527D01*
X540437Y1566062D01*
X540552Y1565649D01*
X540705Y1565339D01*
X540935Y1565080D01*
X541242Y1564977D01*
X541549Y1565080D01*
X541779Y1565339D01*
X541932Y1565649D01*
X542047Y1566062D01*
X542085Y1566527D01*
X542047Y1566992D01*
X541932Y1567405D01*
X541779Y1567715D01*
X541549Y1567974D01*
X541242Y1568077D01*
G01X544342D02*
X544035Y1567974D01*
X543805Y1567715D01*
X543652Y1567405D01*
X543537Y1566992D01*
X543499Y1566527D01*
X543537Y1566062D01*
X543652Y1565649D01*
X543805Y1565339D01*
X544035Y1565080D01*
X544342Y1564977D01*
X544649Y1565080D01*
X544879Y1565339D01*
X545032Y1565649D01*
X545147Y1566062D01*
X545185Y1566527D01*
X545147Y1566992D01*
X545032Y1567405D01*
X544879Y1567715D01*
X544649Y1567974D01*
X544342Y1568077D01*
G01X546599Y1565442D02*
X546829Y1565184D01*
X547097Y1565029D01*
X547442Y1564977D01*
X547787Y1565080D01*
X548055Y1565287D01*
X548247Y1565649D01*
X548285Y1566062D01*
X548209Y1566475D01*
X548017Y1566734D01*
X547749Y1566940D01*
X547480Y1566992D01*
X547212Y1566940D01*
X546867Y1566734D01*
X546982Y1568077D01*
X548017D01*
G01X544155Y1655935D02*
X543483Y1656012D01*
X542915Y1656127D01*
X542398Y1656280D01*
X541830Y1656472D01*
X541055Y1656779D01*
Y1655245D01*
G01X534989Y1655284D02*
X534628Y1655552D01*
X534421Y1655782D01*
X534318Y1656089D01*
X534421Y1656357D01*
X534628Y1656549D01*
X534938Y1656702D01*
X535299Y1656740D01*
X535609Y1656702D01*
X535919Y1656549D01*
X536178Y1656319D01*
X536281Y1656050D01*
X536178Y1655744D01*
X535868Y1655475D01*
X535403Y1655322D01*
X534886Y1655284D01*
X534214Y1655360D01*
X533853Y1655475D01*
X533491Y1655667D01*
X533233Y1655935D01*
X533181Y1656204D01*
X533284Y1656472D01*
X533543Y1656664D01*
G01X554680Y118265D02*
Y124465D01*
X557880D01*
Y118265D01*
X554680D01*
G01X549680D02*
Y124465D01*
X552880D01*
Y118265D01*
X549680D01*
G01X544731Y127930D02*
Y121730D01*
G01X557880Y126090D02*
Y122940D01*
G01X549680D02*
Y126090D01*
G01X549736Y154342D02*
X555936D01*
G01D02*
Y151142D01*
G01D02*
X549736D01*
G01D02*
Y154342D01*
G01X555936Y155067D02*
X549736D01*
G01D02*
Y158267D01*
G01D02*
X555936D01*
G01D02*
Y155067D01*
G01X554478Y195141D02*
X560678D01*
G01Y191941D02*
X554478D01*
G01D02*
Y195141D01*
G01X555796Y183156D02*
X552596D01*
G01X555796Y189356D02*
Y183156D01*
G01X552596Y189356D02*
X555796D01*
G01X552596Y183156D02*
Y189356D01*
G01X546296Y196856D02*
Y193656D01*
G01X551796Y189356D02*
Y183156D01*
G01D02*
X548596D01*
G01D02*
Y189356D01*
G01D02*
X551796D01*
G01X546296Y191856D02*
Y188656D01*
G01Y200856D02*
Y197656D01*
G01X563578Y196041D02*
X551578D01*
G01D02*
Y202041D01*
G01D02*
X563578D01*
G01X548088Y220041D02*
Y216841D01*
G01Y224041D02*
Y220841D01*
G01Y228041D02*
Y224841D01*
G01Y232041D02*
Y228841D01*
G01Y237160D02*
Y233960D01*
G01X556038Y237966D02*
X549838D01*
G01D02*
Y241166D01*
G01X556038D02*
Y237966D01*
G01X548088Y241166D02*
Y237966D01*
G01X549838Y241166D02*
X556038D01*
G01X554299Y299160D02*
Y292960D01*
G01D02*
X551099D01*
G01D02*
Y299160D01*
G01D02*
X554299D01*
G01X545508Y305168D02*
Y295168D01*
G01X554438Y308038D02*
Y314238D01*
G01D02*
X557638D01*
G01D02*
Y308038D01*
G01D02*
X554438D01*
G01X553751Y318101D02*
Y306101D01*
G01D02*
X547751D01*
G01D02*
Y318101D01*
G01X546871Y318161D02*
Y306161D01*
G01X547751Y318101D02*
X553751D01*
G01X557773Y401986D02*
X551573D01*
G01D02*
Y405186D01*
G01X557773D02*
Y401986D01*
G01X551573Y401186D02*
X557773D01*
G01D02*
Y397986D01*
G01D02*
X551573D01*
G01D02*
Y401186D01*
G01Y405186D02*
X557773D01*
G01X551573Y415874D02*
X557773D01*
G01D02*
Y412674D01*
G01D02*
X551573D01*
G01D02*
Y415874D01*
G01X555378Y418324D02*
X555071Y418376D01*
X554803Y418582D01*
X554573Y418892D01*
X554420Y419254D01*
X554343Y419667D01*
Y420081D01*
X554420Y420494D01*
X554573Y420856D01*
X554803Y421166D01*
X555071Y421372D01*
X555378Y421424D01*
X555685Y421372D01*
X555953Y421166D01*
X556183Y420856D01*
X556336Y420494D01*
X556413Y420081D01*
Y419667D01*
X556336Y419254D01*
X556183Y418892D01*
X555953Y418582D01*
X555685Y418376D01*
X555378Y418324D01*
G01X555685Y419151D02*
X556145Y418324D01*
G01X557826Y418686D02*
X558095Y418427D01*
X558401Y418324D01*
X558708Y418427D01*
X558976Y418737D01*
X559168Y419202D01*
X559245Y419667D01*
Y420236D01*
X559168Y420701D01*
X558976Y421114D01*
X558746Y421321D01*
X558478Y421424D01*
X558171Y421321D01*
X557941Y421114D01*
X557788Y420804D01*
X557711Y420391D01*
X557788Y420029D01*
X557980Y419667D01*
X558210Y419461D01*
X558478Y419409D01*
X558785Y419512D01*
X559015Y419771D01*
X559245Y420236D01*
G01X560735Y418789D02*
X560965Y418531D01*
X561233Y418376D01*
X561578Y418324D01*
X561923Y418427D01*
X562191Y418634D01*
X562383Y418996D01*
X562421Y419409D01*
X562345Y419822D01*
X562153Y420081D01*
X561885Y420287D01*
X561616Y420339D01*
X561348Y420287D01*
X561003Y420081D01*
X561118Y421424D01*
X562153D01*
G01X551573Y422349D02*
Y425549D01*
G01X557773Y422349D02*
X551573D01*
G01X557773Y425549D02*
Y422349D01*
G01X551573Y425549D02*
X557773D01*
G01X557984Y432144D02*
Y446856D01*
G01X546016Y432144D02*
X557984D01*
G01X546016Y446856D02*
Y432144D01*
G01X557984Y446856D02*
X546016D01*
G01X550600Y460600D02*
Y457400D01*
G01X544400Y460600D02*
X550600D01*
G01X544400Y457400D02*
Y460600D01*
G01X550600Y457400D02*
X544400D01*
G01X548900Y449400D02*
Y452600D01*
G01X555100Y449400D02*
X548900D01*
G01X555100Y452600D02*
Y449400D01*
G01X548900Y452600D02*
X555100D01*
G01X558500Y456398D02*
X552500D01*
G01X560500Y459500D02*
X558500Y456398D01*
G01X552500D02*
Y468602D01*
G01X557400Y475900D02*
Y479100D01*
G01X563600Y475900D02*
X557400D01*
G01Y475100D02*
X563600D01*
G01X557400Y471900D02*
Y475100D01*
G01X563600Y471900D02*
X557400D01*
G01X552500Y468602D02*
X568500D01*
G01X557400Y479100D02*
X563600D01*
G01X544971Y600028D02*
Y593828D01*
G01X548837Y665289D02*
Y662089D01*
G01Y661089D02*
Y657889D01*
G01X559600Y860722D02*
X553500D01*
G01X548929Y870789D02*
Y857797D01*
G01X548100Y856191D02*
G03X548929Y857797I-1140J1605D01*
G01X556000Y870789D02*
X552800D01*
G01X558602Y1450259D02*
Y1411259D01*
G01D02*
X623000D01*
G01X558602Y1424759D02*
X573602D01*
G01X648602Y1450259D02*
X558602D01*
G01X549400Y1588152D02*
X555400D01*
Y1576152D01*
X549400D01*
Y1588152D01*
G01X556348Y1588224D02*
X562348D01*
Y1576224D01*
X556348D01*
Y1588224D01*
G01X551573Y1572168D02*
X549333D01*
G01X550546Y1570543D02*
Y1573793D01*
G01X548498Y1569363D02*
X547298D01*
G01X548498D02*
X548492Y1586346D01*
G01X547898Y1569363D02*
X547902Y1586338D01*
G01X547298Y1569363D02*
X547301Y1586303D01*
G01X548448Y1586296D02*
X546939Y1586292D01*
G01X545276Y1646023D02*
Y1736118D01*
G01X635433Y1646023D02*
X545276D01*
G01X552029Y1656012D02*
X551977Y1656280D01*
X551822Y1656587D01*
X551564Y1656779D01*
X551202Y1656855D01*
X550841Y1656779D01*
X550531Y1656549D01*
X550376Y1656204D01*
Y1655820D01*
X550272Y1655590D01*
X550014Y1655399D01*
X549652Y1655322D01*
X549291Y1655437D01*
X549032Y1655705D01*
X548929Y1656012D01*
X549032Y1656319D01*
X549291Y1656587D01*
X549652Y1656702D01*
X550014Y1656625D01*
X550272Y1656434D01*
X550376Y1656204D01*
Y1655820D01*
X550531Y1655475D01*
X550841Y1655245D01*
X551202Y1655169D01*
X551564Y1655245D01*
X551822Y1655437D01*
X551977Y1655744D01*
X552029Y1656012D01*
G01X557087Y1669000D02*
Y1657834D01*
G01D02*
X623622D01*
G01X556692D02*
Y1669000D01*
G01X557087Y1740118D02*
X623622D01*
G01X629000Y71929D02*
X560800D01*
G01X569960Y124310D02*
Y118110D01*
X566760D01*
Y124310D01*
X569960D01*
G01X574960D02*
Y118110D01*
X571760D01*
Y124310D01*
X574960D01*
G01X571835Y124385D02*
X578035D01*
Y121185D01*
X571835D01*
Y124385D01*
G01X569885Y121185D02*
X563685D01*
Y124385D01*
X569885D01*
Y121185D01*
G01X566760Y121260D02*
Y127460D01*
X569960D01*
Y121260D01*
X566760D01*
G01X571760D02*
Y127460D01*
X574960D01*
Y121260D01*
X571760D01*
G01X564860Y155969D02*
Y162169D01*
G01D02*
X568060D01*
G01D02*
Y155969D01*
G01D02*
X564860D01*
G01X579103Y162756D02*
X572903D01*
G01D02*
Y165956D01*
G01D02*
X579103D01*
G01Y167815D02*
X572903D01*
G01D02*
Y171015D01*
G01D02*
X579103D01*
G01X560678Y195141D02*
Y191941D01*
G01X563578Y202041D02*
Y196041D01*
G01X575511Y213096D02*
X572311D01*
G01D02*
Y219296D01*
G01D02*
X575511D01*
G01X563278Y219881D02*
X565500D01*
X565965Y220034D01*
X566275Y220341D01*
X566378Y220724D01*
X566275Y221107D01*
X565965Y221414D01*
X565500Y221567D01*
X563278D01*
G01X566378Y223824D02*
X563278D01*
X563898Y223364D01*
G01X566378D02*
Y224284D01*
G01Y227384D02*
X563278D01*
X565500Y225966D01*
Y227882D01*
G01X566378Y229947D02*
X565706Y230024D01*
X565138Y230139D01*
X564621Y230292D01*
X564053Y230484D01*
X563278Y230791D01*
Y229257D01*
G01X581577Y220592D02*
X570193D01*
G01D02*
Y230400D01*
G01X569636Y237421D02*
X575836D01*
G01Y234221D02*
X569636D01*
G01D02*
Y237421D01*
G01X570193Y230400D02*
X581577D01*
G01X558828Y295338D02*
X565028D01*
G01D02*
Y292138D01*
G01D02*
X558828D01*
G01D02*
Y295338D01*
G01X571900Y295869D02*
X565700D01*
G01D02*
Y299069D01*
G01D02*
X571900D01*
G01D02*
Y295869D01*
G01X558828Y291458D02*
X565028D01*
G01D02*
Y288258D01*
G01D02*
X558828D01*
G01D02*
Y291458D01*
G01X558830Y299171D02*
X565030Y299165D01*
G01D02*
X565026Y295965D01*
G01D02*
X558826Y295971D01*
G01D02*
X558830Y299171D01*
G01X572507Y292629D02*
Y298829D01*
G01D02*
X575707D01*
G01Y292629D02*
X572507D01*
G01X560676Y313156D02*
Y314321D01*
G01D02*
X562826D01*
G01Y302117D02*
X560676D01*
G01D02*
Y303282D01*
G01X568944D02*
Y302117D01*
G01D02*
X566794D01*
G01Y314321D02*
X568944D01*
G01D02*
Y313156D01*
G01X567905Y317209D02*
X561705D01*
G01D02*
Y320409D01*
G01D02*
X567905D01*
G01D02*
Y317209D01*
G01X572663Y322072D02*
Y315872D01*
G01D02*
X569463D01*
G01D02*
Y322072D01*
G01D02*
X572663D01*
G01X564032Y370647D02*
Y368425D01*
X564185Y367960D01*
X564492Y367650D01*
X564875Y367547D01*
X565258Y367650D01*
X565565Y367960D01*
X565718Y368425D01*
Y370647D01*
G01X567247Y370130D02*
X567477Y370440D01*
X567745Y370595D01*
X568052Y370647D01*
X568435Y370544D01*
X568703Y370285D01*
X568780Y369975D01*
X568742Y369665D01*
X568588Y369407D01*
X567822Y368890D01*
X567477Y368529D01*
X567247Y368012D01*
X567170Y367547D01*
X568780D01*
G01X571535D02*
Y370647D01*
X570117Y368425D01*
X572033D01*
G01X573332Y368012D02*
X573562Y367754D01*
X573830Y367599D01*
X574175Y367547D01*
X574520Y367650D01*
X574788Y367857D01*
X574980Y368219D01*
X575018Y368632D01*
X574942Y369045D01*
X574750Y369304D01*
X574482Y369510D01*
X574213Y369562D01*
X573945Y369510D01*
X573600Y369304D01*
X573715Y370647D01*
X574750D01*
G01X576645Y372027D02*
X563045D01*
G01D02*
Y380827D01*
G01X568845D02*
X563045D01*
G01X576645D02*
X570845D01*
G01X569845Y379327D02*
X568845Y380827D01*
G01X570845D02*
X569845Y379327D01*
G01X563045Y382827D02*
Y391627D01*
G01X576645Y382827D02*
X563045D01*
G01X565002Y395737D02*
Y393515D01*
X565155Y393050D01*
X565462Y392740D01*
X565845Y392637D01*
X566228Y392740D01*
X566535Y393050D01*
X566688Y393515D01*
Y395737D01*
G01X568217Y395220D02*
X568447Y395530D01*
X568715Y395685D01*
X569022Y395737D01*
X569405Y395634D01*
X569673Y395375D01*
X569750Y395065D01*
X569712Y394755D01*
X569558Y394497D01*
X568792Y393980D01*
X568447Y393619D01*
X568217Y393102D01*
X568140Y392637D01*
X569750D01*
G01X572505D02*
Y395737D01*
X571087Y393515D01*
X573003D01*
G01X574417Y393929D02*
X574685Y394290D01*
X574915Y394497D01*
X575222Y394600D01*
X575490Y394497D01*
X575682Y394290D01*
X575835Y393980D01*
X575873Y393619D01*
X575835Y393309D01*
X575682Y392999D01*
X575452Y392740D01*
X575183Y392637D01*
X574877Y392740D01*
X574608Y393050D01*
X574455Y393515D01*
X574417Y394032D01*
X574493Y394704D01*
X574608Y395065D01*
X574800Y395427D01*
X575068Y395685D01*
X575337Y395737D01*
X575605Y395634D01*
X575797Y395375D01*
G01X570845Y391627D02*
X569845Y390127D01*
G01D02*
X568845Y391627D01*
G01X576645D02*
X570845D01*
G01X568845D02*
X563045D01*
G01X570845Y405558D02*
X569845Y404058D01*
G01D02*
X568845Y405558D01*
G01X563045Y396758D02*
Y405558D01*
G01X576645Y396758D02*
X563045D01*
G01X564401Y417618D02*
X567748D01*
G01D02*
X569648Y415418D01*
G01D02*
X571548Y417618D01*
G01D02*
X574895D01*
G01Y408956D02*
X564401D01*
G01D02*
Y417618D01*
G01X576645Y405558D02*
X570845D01*
G01X568845D02*
X563045D01*
G01X567982Y429188D02*
X567675Y429240D01*
X567407Y429446D01*
X567177Y429756D01*
X567024Y430118D01*
X566947Y430531D01*
Y430945D01*
X567024Y431358D01*
X567177Y431720D01*
X567407Y432030D01*
X567675Y432236D01*
X567982Y432288D01*
X568289Y432236D01*
X568557Y432030D01*
X568787Y431720D01*
X568940Y431358D01*
X569017Y430945D01*
Y430531D01*
X568940Y430118D01*
X568787Y429756D01*
X568557Y429446D01*
X568289Y429240D01*
X567982Y429188D01*
G01X568289Y430015D02*
X568749Y429188D01*
G01X570239Y429808D02*
X570469Y429446D01*
X570775Y429240D01*
X571120Y429188D01*
X571427Y429240D01*
X571734Y429498D01*
X571925Y429808D01*
X571964Y430118D01*
X571887Y430480D01*
X571619Y430738D01*
X571350Y430841D01*
X571005D01*
G01X571350D02*
X571580Y430996D01*
X571772Y431255D01*
X571849Y431565D01*
X571772Y431875D01*
X571580Y432133D01*
X571235Y432288D01*
X570890Y432236D01*
X570545Y432030D01*
G01X574105Y429188D02*
X574182Y429860D01*
X574297Y430428D01*
X574450Y430945D01*
X574642Y431513D01*
X574949Y432288D01*
X573415D01*
G01X574895Y419618D02*
X571548D01*
G01D02*
X569648Y421818D01*
G01D02*
X567748Y419618D01*
G01D02*
X564401D01*
G01D02*
Y428280D01*
G01D02*
X574895D01*
G01X559167Y433107D02*
X561389D01*
X561854Y433260D01*
X562164Y433567D01*
X562267Y433950D01*
X562164Y434333D01*
X561854Y434640D01*
X561389Y434793D01*
X559167D01*
G01X562267Y437050D02*
X562215Y437318D01*
X562060Y437625D01*
X561802Y437817D01*
X561440Y437893D01*
X561079Y437817D01*
X560769Y437587D01*
X560614Y437242D01*
Y436858D01*
X560510Y436628D01*
X560252Y436437D01*
X559890Y436360D01*
X559529Y436475D01*
X559270Y436743D01*
X559167Y437050D01*
X559270Y437357D01*
X559529Y437625D01*
X559890Y437740D01*
X560252Y437663D01*
X560510Y437472D01*
X560614Y437242D01*
Y436858D01*
X560769Y436513D01*
X561079Y436283D01*
X561440Y436207D01*
X561802Y436283D01*
X562060Y436475D01*
X562215Y436782D01*
X562267Y437050D01*
G01X559167Y440150D02*
X559270Y439843D01*
X559529Y439613D01*
X559839Y439460D01*
X560252Y439345D01*
X560717Y439307D01*
X561182Y439345D01*
X561595Y439460D01*
X561905Y439613D01*
X562164Y439843D01*
X562267Y440150D01*
X562164Y440457D01*
X561905Y440687D01*
X561595Y440840D01*
X561182Y440955D01*
X560717Y440993D01*
X560252Y440955D01*
X559839Y440840D01*
X559529Y440687D01*
X559270Y440457D01*
X559167Y440150D01*
G01Y443250D02*
X559270Y442943D01*
X559529Y442713D01*
X559839Y442560D01*
X560252Y442445D01*
X560717Y442407D01*
X561182Y442445D01*
X561595Y442560D01*
X561905Y442713D01*
X562164Y442943D01*
X562267Y443250D01*
X562164Y443557D01*
X561905Y443787D01*
X561595Y443940D01*
X561182Y444055D01*
X560717Y444093D01*
X560252Y444055D01*
X559839Y443940D01*
X559529Y443787D01*
X559270Y443557D01*
X559167Y443250D01*
G01X561905Y445698D02*
X562164Y445967D01*
X562267Y446273D01*
X562164Y446580D01*
X561854Y446848D01*
X561389Y447040D01*
X560924Y447117D01*
X560355D01*
X559890Y447040D01*
X559477Y446848D01*
X559270Y446618D01*
X559167Y446350D01*
X559270Y446043D01*
X559477Y445813D01*
X559787Y445660D01*
X560200Y445583D01*
X560562Y445660D01*
X560924Y445852D01*
X561130Y446082D01*
X561182Y446350D01*
X561079Y446657D01*
X560820Y446887D01*
X560355Y447117D01*
G01X558900Y449400D02*
Y452600D01*
G01X565100Y449400D02*
X558900D01*
G01X565100Y452600D02*
Y449400D01*
G01X558900Y452600D02*
X565100D01*
G01X570400Y456100D02*
X576600D01*
G01X570400Y452900D02*
Y456100D01*
G01X576600Y452900D02*
X570400D01*
G01Y460400D02*
Y463600D01*
G01X576600Y460400D02*
X570400D01*
G01Y463600D02*
X576600D01*
G01X562500Y456398D02*
X560500Y459500D01*
G01X568500Y456398D02*
X562500D01*
G01X568500Y468602D02*
Y456398D01*
G01X570400Y464400D02*
Y467600D01*
G01X576600Y464400D02*
X570400D01*
G01Y467600D02*
X576600D01*
G01X568400Y469900D02*
Y473100D01*
G01X574600Y469900D02*
X568400D01*
G01Y473100D02*
X574600D01*
G01X563600Y479100D02*
Y475900D01*
G01Y475100D02*
Y471900D01*
G01X568400Y473900D02*
Y477100D01*
G01X574600Y473900D02*
X568400D01*
G01Y477100D02*
X574600D01*
G01X566582Y644306D02*
Y618716D01*
G01D02*
X562587D01*
G01Y644306D02*
X566582D01*
G01X561527Y659368D02*
Y656268D01*
G01X560645Y659368D02*
X562409D01*
G01X563860Y656268D02*
Y659368D01*
X564780D01*
X565087Y659213D01*
X565317Y658851D01*
X565394Y658438D01*
X565317Y658025D01*
X565125Y657715D01*
X564780Y657560D01*
X563860D01*
G01X567727Y656268D02*
Y659368D01*
X567267Y658748D01*
G01Y656268D02*
X568187D01*
G01X570827D02*
Y659368D01*
X570367Y658748D01*
G01Y656268D02*
X571287D01*
G01X561277Y663868D02*
Y660768D01*
G01X560395Y663868D02*
X562159D01*
G01X563610Y660768D02*
Y663868D01*
X564530D01*
X564837Y663713D01*
X565067Y663351D01*
X565144Y662938D01*
X565067Y662525D01*
X564875Y662215D01*
X564530Y662060D01*
X563610D01*
G01X566749Y663351D02*
X566979Y663661D01*
X567247Y663816D01*
X567554Y663868D01*
X567937Y663765D01*
X568205Y663506D01*
X568282Y663196D01*
X568244Y662886D01*
X568090Y662628D01*
X567324Y662111D01*
X566979Y661750D01*
X566749Y661233D01*
X566672Y660768D01*
X568282D01*
G01X570577Y663868D02*
X570270Y663765D01*
X570040Y663506D01*
X569887Y663196D01*
X569772Y662783D01*
X569734Y662318D01*
X569772Y661853D01*
X569887Y661440D01*
X570040Y661130D01*
X570270Y660871D01*
X570577Y660768D01*
X570884Y660871D01*
X571114Y661130D01*
X571267Y661440D01*
X571382Y661853D01*
X571420Y662318D01*
X571382Y662783D01*
X571267Y663196D01*
X571114Y663506D01*
X570884Y663765D01*
X570577Y663868D01*
G01X571816Y762912D02*
X568616D01*
G01X571816Y769112D02*
Y762912D01*
G01X568616Y769112D02*
X571816D01*
G01X568616Y762912D02*
Y769112D01*
G01X576816Y762912D02*
X573616D01*
G01Y769112D02*
X576816D01*
G01X573616Y762912D02*
Y769112D01*
G01X584600Y860722D02*
X567100D01*
G01X582393Y870789D02*
X560600D01*
G01X566851Y1263418D02*
Y1269618D01*
G01X570051Y1263418D02*
X566851D01*
G01X570051Y1269618D02*
Y1263418D01*
G01X562909Y1263414D02*
Y1269614D01*
G01X566109Y1263414D02*
X562909D01*
G01X566109Y1269614D02*
Y1263414D01*
G01X566851Y1269618D02*
X570051D01*
G01X562909Y1269614D02*
X566109D01*
G01X565645Y1431302D02*
X565270Y1431675D01*
X564645Y1431955D01*
X563770Y1432142D01*
X563020Y1431955D01*
X562520Y1431582D01*
X562145Y1430928D01*
Y1428408D01*
X569645D01*
Y1431488D01*
X569145Y1432142D01*
X568395Y1432515D01*
X567520Y1432702D01*
X566645Y1432515D01*
X565895Y1431955D01*
X565645Y1431302D01*
Y1428408D01*
G01X566520Y1436282D02*
X565645Y1436935D01*
X565145Y1437495D01*
X564895Y1438242D01*
X565145Y1438895D01*
X565645Y1439362D01*
X566395Y1439735D01*
X567270Y1439828D01*
X568020Y1439735D01*
X568770Y1439362D01*
X569395Y1438802D01*
X569645Y1438148D01*
X569395Y1437402D01*
X568645Y1436748D01*
X567520Y1436375D01*
X566270Y1436282D01*
X564645Y1436468D01*
X563770Y1436748D01*
X562895Y1437215D01*
X562270Y1437868D01*
X562145Y1438522D01*
X562395Y1439175D01*
X563020Y1439642D01*
G01X588602Y1424759D02*
X573602D01*
G01D02*
Y1450259D01*
G01X569668Y1507451D02*
Y1524400D01*
G01X574500Y1507451D02*
X569668D01*
G01X561026Y1539911D02*
Y1536503D01*
G01X569668Y1528300D02*
Y1542491D01*
G01X561026Y1554219D02*
Y1550811D01*
G01X569668Y1542491D02*
X576000D01*
G01X569132Y1655284D02*
X568822Y1655514D01*
X568667Y1655782D01*
X568615Y1656089D01*
X568718Y1656472D01*
X568977Y1656740D01*
X569287Y1656817D01*
X569597Y1656779D01*
X569855Y1656625D01*
X570372Y1655859D01*
X570733Y1655514D01*
X571250Y1655284D01*
X571715Y1655207D01*
Y1656817D01*
G01X563841Y1656012D02*
X560741D01*
X561361Y1655552D01*
G01X563841D02*
Y1656472D01*
G01X568503Y1668810D02*
Y1646023D01*
G01X572191Y1736629D02*
X571125D01*
Y1739129D01*
X572191D01*
G01X571765Y1737921D02*
X571125D01*
G01X573271Y1736629D02*
Y1739129D01*
X573805D01*
X574018Y1739004D01*
X574178Y1738837D01*
X574311Y1738587D01*
X574418Y1738296D01*
X574445Y1737879D01*
X574418Y1737462D01*
X574311Y1737171D01*
X574178Y1736921D01*
X574018Y1736754D01*
X573805Y1736629D01*
X573271D01*
G01X576218Y1737879D02*
X576751D01*
Y1737129D01*
X576591Y1736879D01*
X576405Y1736712D01*
X576138Y1736629D01*
X575871Y1736712D01*
X575685Y1736879D01*
X575525Y1737129D01*
X575418Y1737421D01*
X575365Y1737754D01*
Y1738046D01*
X575418Y1738296D01*
X575525Y1738587D01*
X575685Y1738837D01*
X575845Y1739004D01*
X576058Y1739129D01*
X576245D01*
X576458Y1739046D01*
X576618Y1738879D01*
G01X578791Y1736629D02*
X577725D01*
Y1739129D01*
X578791D01*
G01X578365Y1737921D02*
X577725D01*
G01X582658Y1736629D02*
X582445Y1736671D01*
X582258Y1736837D01*
X582098Y1737087D01*
X581991Y1737379D01*
X581938Y1737712D01*
Y1738046D01*
X581991Y1738379D01*
X582098Y1738671D01*
X582258Y1738921D01*
X582445Y1739087D01*
X582658Y1739129D01*
X582871Y1739087D01*
X583058Y1738921D01*
X583218Y1738671D01*
X583325Y1738379D01*
X583378Y1738046D01*
Y1737712D01*
X583325Y1737379D01*
X583218Y1737087D01*
X583058Y1736837D01*
X582871Y1736671D01*
X582658Y1736629D01*
G01X584351D02*
Y1739129D01*
X585365D01*
G01X584991Y1737921D02*
X584351D01*
G01X588671Y1736629D02*
Y1739129D01*
X589205D01*
X589418Y1739004D01*
X589578Y1738837D01*
X589711Y1738587D01*
X589818Y1738296D01*
X589845Y1737879D01*
X589818Y1737462D01*
X589711Y1737171D01*
X589578Y1736921D01*
X589418Y1736754D01*
X589205Y1736629D01*
X588671D01*
G01X590791D02*
X591458Y1739129D01*
X592125Y1736629D01*
G01X591885Y1737504D02*
X591031D01*
G01X593071Y1739129D02*
Y1737337D01*
X593178Y1736962D01*
X593391Y1736712D01*
X593658Y1736629D01*
X593925Y1736712D01*
X594138Y1736962D01*
X594245Y1737337D01*
Y1739129D01*
G01X596018Y1737879D02*
X596551D01*
Y1737129D01*
X596391Y1736879D01*
X596205Y1736712D01*
X595938Y1736629D01*
X595671Y1736712D01*
X595485Y1736879D01*
X595325Y1737129D01*
X595218Y1737421D01*
X595165Y1737754D01*
Y1738046D01*
X595218Y1738296D01*
X595325Y1738587D01*
X595485Y1738837D01*
X595645Y1739004D01*
X595858Y1739129D01*
X596045D01*
X596258Y1739046D01*
X596418Y1738879D01*
G01X597498Y1736629D02*
Y1739129D01*
G01X598618D02*
Y1736629D01*
G01Y1737879D02*
X597498D01*
G01X600258Y1739129D02*
Y1736629D01*
G01X599645Y1739129D02*
X600871D01*
G01X602991Y1736629D02*
X601925D01*
Y1739129D01*
X602991D01*
G01X602565Y1737921D02*
X601925D01*
G01X604125Y1736629D02*
Y1739129D01*
X604791D01*
X605005Y1739004D01*
X605138Y1738837D01*
X605191Y1738504D01*
X605138Y1738171D01*
X604978Y1737962D01*
X604791Y1737837D01*
X604125D01*
G01X604791D02*
X605191Y1736629D01*
G01X609645Y1738921D02*
X609485Y1739046D01*
X609298Y1739129D01*
X609085D01*
X608845Y1739004D01*
X608658Y1738796D01*
X608525Y1738546D01*
X608418Y1738129D01*
X608391Y1737754D01*
X608445Y1737379D01*
X608525Y1737129D01*
X608685Y1736879D01*
X608871Y1736712D01*
X609058Y1736629D01*
X609245D01*
X609431Y1736712D01*
X609591Y1736837D01*
X609725Y1737004D01*
G01X610591Y1736629D02*
X611258Y1739129D01*
X611925Y1736629D01*
G01X611685Y1737504D02*
X610831D01*
G01X612925Y1736629D02*
Y1739129D01*
X613591D01*
X613805Y1739004D01*
X613938Y1738837D01*
X613991Y1738504D01*
X613938Y1738171D01*
X613778Y1737962D01*
X613591Y1737837D01*
X612925D01*
G01X613591D02*
X613991Y1736629D01*
G01X615071D02*
Y1739129D01*
X615605D01*
X615818Y1739004D01*
X615978Y1738837D01*
X616111Y1738587D01*
X616218Y1738296D01*
X616245Y1737879D01*
X616218Y1737462D01*
X616111Y1737171D01*
X615978Y1736921D01*
X615818Y1736754D01*
X615605Y1736629D01*
X615071D01*
G01X569108Y1736412D02*
X570008Y1737312D01*
G01X564108Y1736412D02*
X569108D01*
G01X564108Y1739812D02*
Y1736412D01*
G01X566108Y1737812D02*
X564108Y1739812D01*
G01X562108Y1737812D02*
X566108D01*
G01X564108Y1739812D02*
X562108Y1737812D01*
G01X592604Y64566D02*
X575864D01*
G01X580593Y88573D02*
Y94773D01*
G01X583793D02*
Y88573D01*
G01D02*
X580593D01*
G01X587994Y94773D02*
Y88573D01*
G01X584794D02*
Y94773D01*
G01X587994Y88573D02*
X584794D01*
G01X580593Y81573D02*
Y87773D01*
G01D02*
X583793D01*
G01D02*
Y81573D01*
G01D02*
X580593D01*
G01X576854Y87739D02*
X580054D01*
G01X576854Y81539D02*
Y87739D01*
G01X580054Y81539D02*
X576854D01*
G01X580054Y87739D02*
Y81539D01*
G01X580593Y94773D02*
X583793D01*
G01X584794D02*
X587994D01*
G01X578836Y112057D02*
X579583Y111432D01*
X580423Y111057D01*
X581169D01*
X581916Y111432D01*
X582476Y112057D01*
X582756Y112932D01*
X582569Y113807D01*
X582103Y114557D01*
X581263Y115057D01*
X580143Y115307D01*
X579489Y115807D01*
X579209Y116682D01*
X579396Y117557D01*
X579863Y118182D01*
X580516Y118557D01*
X581169D01*
X581823Y118307D01*
X582383Y117682D01*
G01X590349Y117932D02*
X589789Y118307D01*
X589136Y118557D01*
X588389D01*
X587549Y118182D01*
X586896Y117557D01*
X586429Y116807D01*
X586056Y115557D01*
X585963Y114432D01*
X586149Y113307D01*
X586429Y112557D01*
X586989Y111807D01*
X587643Y111307D01*
X588296Y111057D01*
X588949D01*
X589603Y111307D01*
X590163Y111682D01*
X590629Y112182D01*
G01X593369Y111057D02*
Y118557D01*
X595796Y112307D01*
X598223Y118557D01*
Y111057D01*
G01X612289Y115432D02*
X611636Y115932D01*
X611076Y116057D01*
X610329Y115807D01*
X609769Y115307D01*
X609396Y114432D01*
X609303Y113557D01*
X609396Y112682D01*
X609769Y111932D01*
X610329Y111307D01*
X611076Y111057D01*
X611729Y111307D01*
X612289Y111807D01*
G01X618296Y111057D02*
X617736Y111182D01*
X617176Y111682D01*
X616803Y112557D01*
X616616Y113557D01*
X616803Y114557D01*
X617176Y115432D01*
X617736Y115932D01*
X618296Y116057D01*
X618856Y115932D01*
X619416Y115432D01*
X619789Y114557D01*
X619883Y113557D01*
X619789Y112557D01*
X619416Y111682D01*
X618856Y111182D01*
X618296Y111057D01*
G01X624209D02*
Y116057D01*
G01Y114807D02*
X624583Y115432D01*
X625143Y115932D01*
X625889Y116057D01*
X626543Y115932D01*
X627103Y115432D01*
X627383Y114557D01*
Y111057D01*
G01X631709D02*
Y116057D01*
G01Y114807D02*
X632083Y115432D01*
X632643Y115932D01*
X633389Y116057D01*
X634043Y115932D01*
X634603Y115432D01*
X634883Y114557D01*
Y111057D01*
G01X575487Y145517D02*
Y143295D01*
X575640Y142830D01*
X575947Y142520D01*
X576330Y142417D01*
X576713Y142520D01*
X577020Y142830D01*
X577173Y143295D01*
Y145517D01*
G01X578702Y145000D02*
X578932Y145310D01*
X579200Y145465D01*
X579507Y145517D01*
X579890Y145414D01*
X580158Y145155D01*
X580235Y144845D01*
X580197Y144535D01*
X580043Y144277D01*
X579277Y143760D01*
X578932Y143399D01*
X578702Y142882D01*
X578625Y142417D01*
X580235D01*
G01X581687Y143037D02*
X581917Y142675D01*
X582223Y142469D01*
X582568Y142417D01*
X582875Y142469D01*
X583182Y142727D01*
X583373Y143037D01*
X583412Y143347D01*
X583335Y143709D01*
X583067Y143967D01*
X582798Y144070D01*
X582453D01*
G01X582798D02*
X583028Y144225D01*
X583220Y144484D01*
X583297Y144794D01*
X583220Y145104D01*
X583028Y145362D01*
X582683Y145517D01*
X582338Y145465D01*
X581993Y145259D01*
G01X584787Y142882D02*
X585017Y142624D01*
X585285Y142469D01*
X585630Y142417D01*
X585975Y142520D01*
X586243Y142727D01*
X586435Y143089D01*
X586473Y143502D01*
X586397Y143915D01*
X586205Y144174D01*
X585937Y144380D01*
X585668Y144432D01*
X585400Y144380D01*
X585055Y144174D01*
X585170Y145517D01*
X586205D01*
G01X586622Y159462D02*
Y147258D01*
G01D02*
X575098D01*
G01D02*
Y159462D01*
G01D02*
X577758D01*
G01D02*
X580860Y156360D01*
G01D02*
X583860Y159462D01*
G01D02*
X586622D01*
G01X588303Y165956D02*
Y162756D01*
G01D02*
X582103D01*
G01D02*
Y165956D01*
G01X579103D02*
Y162756D01*
G01X586594Y173450D02*
Y179650D01*
G01D02*
X589794D01*
G01Y173450D02*
X586594D01*
G01X582103Y165956D02*
X588303D01*
G01X579103Y171015D02*
Y167815D01*
G01X582103Y171015D02*
X588303D01*
G01D02*
Y167815D01*
G01D02*
X582103D01*
G01D02*
Y171015D01*
G01X573937Y195116D02*
X580137D01*
Y191916D01*
X573937D01*
Y195116D01*
G01X573952Y199081D02*
X580152D01*
Y195881D01*
X573952D01*
Y199081D01*
G01X579459Y219296D02*
Y213096D01*
G01D02*
X576259D01*
G01D02*
Y219296D01*
G01D02*
X579459D01*
G01X575511D02*
Y213096D01*
G01X581577Y230400D02*
Y220592D01*
G01X575836Y237421D02*
Y234221D01*
G01X600107Y251092D02*
X584753D01*
G01D02*
Y263770D01*
G01X576424Y262771D02*
X582624D01*
G01D02*
Y259571D01*
G01D02*
X576424D01*
G01D02*
Y262771D01*
G01X582624Y255571D02*
X576424D01*
G01D02*
Y258771D01*
G01D02*
X582624D01*
G01D02*
Y255571D01*
G01X583730Y265198D02*
X583423Y265250D01*
X583155Y265456D01*
X582925Y265766D01*
X582772Y266128D01*
X582695Y266541D01*
Y266955D01*
X582772Y267368D01*
X582925Y267730D01*
X583155Y268040D01*
X583423Y268246D01*
X583730Y268298D01*
X584037Y268246D01*
X584305Y268040D01*
X584535Y267730D01*
X584688Y267368D01*
X584765Y266955D01*
Y266541D01*
X584688Y266128D01*
X584535Y265766D01*
X584305Y265456D01*
X584037Y265250D01*
X583730Y265198D01*
G01X584037Y266025D02*
X584497Y265198D01*
G01X586102Y266490D02*
X586370Y266851D01*
X586600Y267058D01*
X586907Y267161D01*
X587175Y267058D01*
X587367Y266851D01*
X587520Y266541D01*
X587558Y266180D01*
X587520Y265870D01*
X587367Y265560D01*
X587137Y265301D01*
X586868Y265198D01*
X586562Y265301D01*
X586293Y265611D01*
X586140Y266076D01*
X586102Y266593D01*
X586178Y267265D01*
X586293Y267626D01*
X586485Y267988D01*
X586753Y268246D01*
X587022Y268298D01*
X587290Y268195D01*
X587482Y267936D01*
G01X589202Y267781D02*
X589432Y268091D01*
X589700Y268246D01*
X590007Y268298D01*
X590390Y268195D01*
X590658Y267936D01*
X590735Y267626D01*
X590697Y267316D01*
X590543Y267058D01*
X589777Y266541D01*
X589432Y266180D01*
X589202Y265663D01*
X589125Y265198D01*
X590735D01*
G01X584753Y263770D02*
X600107D01*
G01X575707Y298829D02*
Y292629D01*
G01X577167Y299568D02*
X573967D01*
G01X577167Y305768D02*
Y299568D01*
G01X573967D02*
Y305768D01*
G01X609578Y292925D02*
X580838D01*
G01D02*
Y298914D01*
G01X577138Y312303D02*
Y306103D01*
G01X573938D02*
Y312303D01*
G01D02*
X577138D01*
G01Y306103D02*
X573938D01*
G01X573967Y305768D02*
X577167D01*
G01X580838Y313214D02*
Y319303D01*
G01X574340Y324265D02*
Y327365D01*
X575260D01*
X575567Y327210D01*
X575797Y326848D01*
X575874Y326435D01*
X575797Y326022D01*
X575605Y325712D01*
X575260Y325557D01*
X574340D01*
G01X577440Y327365D02*
Y324265D01*
X578974D01*
G01X580579Y325557D02*
X580847Y325918D01*
X581077Y326125D01*
X581384Y326228D01*
X581652Y326125D01*
X581844Y325918D01*
X581997Y325608D01*
X582035Y325247D01*
X581997Y324937D01*
X581844Y324627D01*
X581614Y324368D01*
X581345Y324265D01*
X581039Y324368D01*
X580770Y324678D01*
X580617Y325143D01*
X580579Y325660D01*
X580655Y326332D01*
X580770Y326693D01*
X580962Y327055D01*
X581230Y327313D01*
X581499Y327365D01*
X581767Y327262D01*
X581959Y327003D01*
G01X584407Y327365D02*
X584100Y327262D01*
X583870Y327003D01*
X583717Y326693D01*
X583602Y326280D01*
X583564Y325815D01*
X583602Y325350D01*
X583717Y324937D01*
X583870Y324627D01*
X584100Y324368D01*
X584407Y324265D01*
X584714Y324368D01*
X584944Y324627D01*
X585097Y324937D01*
X585212Y325350D01*
X585250Y325815D01*
X585212Y326280D01*
X585097Y326693D01*
X584944Y327003D01*
X584714Y327262D01*
X584407Y327365D01*
G01X587507D02*
X587200Y327262D01*
X586970Y327003D01*
X586817Y326693D01*
X586702Y326280D01*
X586664Y325815D01*
X586702Y325350D01*
X586817Y324937D01*
X586970Y324627D01*
X587200Y324368D01*
X587507Y324265D01*
X587814Y324368D01*
X588044Y324627D01*
X588197Y324937D01*
X588312Y325350D01*
X588350Y325815D01*
X588312Y326280D01*
X588197Y326693D01*
X588044Y327003D01*
X587814Y327262D01*
X587507Y327365D01*
G01X590607D02*
X590300Y327262D01*
X590070Y327003D01*
X589917Y326693D01*
X589802Y326280D01*
X589764Y325815D01*
X589802Y325350D01*
X589917Y324937D01*
X590070Y324627D01*
X590300Y324368D01*
X590607Y324265D01*
X590914Y324368D01*
X591144Y324627D01*
X591297Y324937D01*
X591412Y325350D01*
X591450Y325815D01*
X591412Y326280D01*
X591297Y326693D01*
X591144Y327003D01*
X590914Y327262D01*
X590607Y327365D01*
G01X580808Y319303D02*
X609578D01*
G01X583985Y372952D02*
Y379152D01*
G01X587185D02*
Y372952D01*
G01D02*
X583985D01*
G01X584560Y365227D02*
X578360D01*
G01D02*
Y368427D01*
G01D02*
X584560D01*
G01D02*
Y365227D01*
G01X576645Y380827D02*
Y372027D01*
G01X577785Y374902D02*
Y381102D01*
G01D02*
X580985D01*
G01D02*
Y374902D01*
G01D02*
X577785D01*
G01Y385702D02*
Y391902D01*
G01X580985D02*
Y385702D01*
G01D02*
X577785D01*
G01X583985Y379152D02*
X587185D01*
G01X583985Y385702D02*
Y391902D01*
G01X587185D02*
Y385702D01*
G01D02*
X583985D01*
G01X576645Y391627D02*
Y382827D01*
G01X577785Y391902D02*
X580985D01*
G01X577785Y399633D02*
Y405833D01*
G01X580985D02*
Y399633D01*
G01D02*
X577785D01*
G01X583985Y391902D02*
X587185D01*
G01X588471Y395745D02*
Y393523D01*
X588624Y393058D01*
X588931Y392748D01*
X589314Y392645D01*
X589697Y392748D01*
X590004Y393058D01*
X590157Y393523D01*
Y395745D01*
G01X591686Y395228D02*
X591916Y395538D01*
X592184Y395693D01*
X592491Y395745D01*
X592874Y395642D01*
X593142Y395383D01*
X593219Y395073D01*
X593181Y394763D01*
X593027Y394505D01*
X592261Y393988D01*
X591916Y393627D01*
X591686Y393110D01*
X591609Y392645D01*
X593219D01*
G01X595974D02*
Y395745D01*
X594556Y393523D01*
X596472D01*
G01X597771Y393265D02*
X598001Y392903D01*
X598307Y392697D01*
X598652Y392645D01*
X598959Y392697D01*
X599266Y392955D01*
X599457Y393265D01*
X599496Y393575D01*
X599419Y393937D01*
X599151Y394195D01*
X598882Y394298D01*
X598537D01*
G01X598882D02*
X599112Y394453D01*
X599304Y394712D01*
X599381Y395022D01*
X599304Y395332D01*
X599112Y395590D01*
X598767Y395745D01*
X598422Y395693D01*
X598077Y395487D01*
G01X576645Y405558D02*
Y396758D01*
G01X577785Y405833D02*
X580985D01*
G01X581523Y413446D02*
X587723D01*
G01D02*
Y410246D01*
G01D02*
X581523D01*
G01D02*
Y413446D01*
G01X587723Y414246D02*
X581523D01*
G01D02*
Y417446D01*
G01D02*
X587723D01*
G01D02*
Y414246D01*
G01X574895Y417618D02*
Y408956D01*
G01X575952Y409518D02*
Y407296D01*
X576105Y406831D01*
X576412Y406521D01*
X576795Y406418D01*
X577178Y406521D01*
X577485Y406831D01*
X577638Y407296D01*
Y409518D01*
G01X579167Y409001D02*
X579397Y409311D01*
X579665Y409466D01*
X579972Y409518D01*
X580355Y409415D01*
X580623Y409156D01*
X580700Y408846D01*
X580662Y408536D01*
X580508Y408278D01*
X579742Y407761D01*
X579397Y407400D01*
X579167Y406883D01*
X579090Y406418D01*
X580700D01*
G01X582152Y406883D02*
X582382Y406625D01*
X582650Y406470D01*
X582995Y406418D01*
X583340Y406521D01*
X583608Y406728D01*
X583800Y407090D01*
X583838Y407503D01*
X583762Y407916D01*
X583570Y408175D01*
X583302Y408381D01*
X583033Y408433D01*
X582765Y408381D01*
X582420Y408175D01*
X582535Y409518D01*
X583570D01*
G01X585443Y406780D02*
X585712Y406521D01*
X586018Y406418D01*
X586325Y406521D01*
X586593Y406831D01*
X586785Y407296D01*
X586862Y407761D01*
Y408330D01*
X586785Y408795D01*
X586593Y409208D01*
X586363Y409415D01*
X586095Y409518D01*
X585788Y409415D01*
X585558Y409208D01*
X585405Y408898D01*
X585328Y408485D01*
X585405Y408123D01*
X585597Y407761D01*
X585827Y407555D01*
X586095Y407503D01*
X586402Y407606D01*
X586632Y407865D01*
X586862Y408330D01*
G01X587723Y429549D02*
Y426349D01*
G01X581523Y429549D02*
X587723D01*
G01X581523Y426349D02*
Y429549D01*
G01X587723Y426349D02*
X581523D01*
G01Y422349D02*
Y425549D01*
G01X587723Y422349D02*
X581523D01*
G01X587723Y425549D02*
Y422349D01*
G01X581523Y425549D02*
X587723D01*
G01X587742Y433576D02*
Y430376D01*
G01X581542Y433576D02*
X587742D01*
G01X581542Y430376D02*
Y433576D01*
G01X587742Y430376D02*
X581542D01*
G01X574895Y428280D02*
Y419618D01*
G01X581523Y437549D02*
X587723D01*
G01D02*
Y434349D01*
G01D02*
X581523D01*
G01D02*
Y437549D01*
G01X578615Y444688D02*
Y442466D01*
X578768Y442001D01*
X579075Y441691D01*
X579458Y441588D01*
X579841Y441691D01*
X580148Y442001D01*
X580301Y442466D01*
Y444688D01*
G01X581906Y441950D02*
X582175Y441691D01*
X582481Y441588D01*
X582788Y441691D01*
X583056Y442001D01*
X583248Y442466D01*
X583325Y442931D01*
Y443500D01*
X583248Y443965D01*
X583056Y444378D01*
X582826Y444585D01*
X582558Y444688D01*
X582251Y444585D01*
X582021Y444378D01*
X581868Y444068D01*
X581791Y443655D01*
X581868Y443293D01*
X582060Y442931D01*
X582290Y442725D01*
X582558Y442673D01*
X582865Y442776D01*
X583095Y443035D01*
X583325Y443500D01*
G01X584930Y444171D02*
X585160Y444481D01*
X585428Y444636D01*
X585735Y444688D01*
X586118Y444585D01*
X586386Y444326D01*
X586463Y444016D01*
X586425Y443706D01*
X586271Y443448D01*
X585505Y442931D01*
X585160Y442570D01*
X584930Y442053D01*
X584853Y441588D01*
X586463D01*
G01X584900Y462600D02*
X588100D01*
G01X584900Y456400D02*
Y462600D01*
G01X588100Y456400D02*
X584900D01*
G01X588100Y462600D02*
Y456400D01*
G01X584900Y462900D02*
Y469100D01*
G01X588100Y462900D02*
X584900D01*
G01X588100Y469100D02*
Y462900D01*
G01X576600Y456100D02*
Y452900D01*
G01Y463600D02*
Y460400D01*
G01X582106Y452642D02*
Y455842D01*
G01X588306Y452642D02*
X582106D01*
G01X588306Y455842D02*
Y452642D01*
G01X582106Y455842D02*
X588306D01*
G01X576600Y467600D02*
Y464400D01*
G01X584900Y469100D02*
X588100D01*
G01X574600Y473100D02*
Y469900D01*
G01X575400Y477900D02*
Y481100D01*
G01X581600Y477900D02*
X575400D01*
G01X581600Y481100D02*
Y477900D01*
G01X575400Y473900D02*
Y477100D01*
G01X581600Y473900D02*
X575400D01*
G01X581600Y477100D02*
Y473900D01*
G01X575400Y477100D02*
X581600D01*
G01X574600D02*
Y473900D01*
G01X575400Y481100D02*
X581600D01*
G01X576654Y489908D02*
Y493008D01*
X577420D01*
X577727Y492853D01*
X577957Y492646D01*
X578149Y492336D01*
X578302Y491975D01*
X578340Y491458D01*
X578302Y490941D01*
X578149Y490580D01*
X577957Y490270D01*
X577727Y490063D01*
X577420Y489908D01*
X576654D01*
G01X580597D02*
X580865Y489960D01*
X581172Y490115D01*
X581364Y490373D01*
X581440Y490735D01*
X581364Y491096D01*
X581134Y491406D01*
X580789Y491561D01*
X580405D01*
X580175Y491665D01*
X579984Y491923D01*
X579907Y492285D01*
X580022Y492646D01*
X580290Y492905D01*
X580597Y493008D01*
X580904Y492905D01*
X581172Y492646D01*
X581287Y492285D01*
X581210Y491923D01*
X581019Y491665D01*
X580789Y491561D01*
X580405D01*
X580060Y491406D01*
X579830Y491096D01*
X579754Y490735D01*
X579830Y490373D01*
X580022Y490115D01*
X580329Y489960D01*
X580597Y489908D01*
G01X583697Y493008D02*
X583390Y492905D01*
X583160Y492646D01*
X583007Y492336D01*
X582892Y491923D01*
X582854Y491458D01*
X582892Y490993D01*
X583007Y490580D01*
X583160Y490270D01*
X583390Y490011D01*
X583697Y489908D01*
X584004Y490011D01*
X584234Y490270D01*
X584387Y490580D01*
X584502Y490993D01*
X584540Y491458D01*
X584502Y491923D01*
X584387Y492336D01*
X584234Y492646D01*
X584004Y492905D01*
X583697Y493008D01*
G01X586797D02*
X586490Y492905D01*
X586260Y492646D01*
X586107Y492336D01*
X585992Y491923D01*
X585954Y491458D01*
X585992Y490993D01*
X586107Y490580D01*
X586260Y490270D01*
X586490Y490011D01*
X586797Y489908D01*
X587104Y490011D01*
X587334Y490270D01*
X587487Y490580D01*
X587602Y490993D01*
X587640Y491458D01*
X587602Y491923D01*
X587487Y492336D01*
X587334Y492646D01*
X587104Y492905D01*
X586797Y493008D01*
G01X589054Y490373D02*
X589284Y490115D01*
X589552Y489960D01*
X589897Y489908D01*
X590242Y490011D01*
X590510Y490218D01*
X590702Y490580D01*
X590740Y490993D01*
X590664Y491406D01*
X590472Y491665D01*
X590204Y491871D01*
X589935Y491923D01*
X589667Y491871D01*
X589322Y491665D01*
X589437Y493008D01*
X590472D01*
G01X575311Y486050D02*
X577737D01*
G01X588237Y486000D02*
X590205Y484031D01*
G01Y487969D02*
X588237Y486000D01*
G01X587843Y484031D02*
Y487969D01*
G01X579774Y488750D02*
X580274D01*
G01X579774Y483250D02*
Y488750D01*
G01X580524Y483250D02*
X579774D01*
G01X580524Y488500D02*
Y483250D01*
G01X580924Y488500D02*
X580524D01*
G01X580924Y488750D02*
Y488500D01*
G01X580224Y488750D02*
X580924D01*
G01X580224Y483250D02*
Y488750D01*
G01X580874Y483250D02*
X580224D01*
G01X580874Y483350D02*
Y483250D01*
G01X580926Y488756D02*
X597074D01*
G01X580926Y483244D02*
Y488756D01*
G01X597074Y483244D02*
X580926D01*
G01X584725Y750265D02*
X583200D01*
G01X584725Y756465D02*
Y750265D01*
G01X583300Y756465D02*
X584725D01*
G01X581525Y751700D02*
Y754700D01*
G01X577525Y756465D02*
X579200D01*
G01X577525Y750265D02*
Y756465D01*
G01X580725Y754700D02*
Y751700D01*
G01X579300Y750265D02*
X577525D01*
G01X585921Y756533D02*
X587300D01*
G01X585921Y750333D02*
Y756533D01*
G01X587700Y750333D02*
X585921D01*
G01X576816Y769112D02*
Y762912D01*
G01X582393Y886100D02*
Y870789D01*
G01Y910900D02*
Y896400D01*
G01Y931600D02*
Y920300D01*
G01Y951100D02*
Y939300D01*
G01Y969200D02*
Y958900D01*
G01Y1008500D02*
Y976600D01*
G01Y1064200D02*
Y1013100D01*
G01Y1083800D02*
Y1071300D01*
G01Y1102400D02*
Y1091300D01*
G01Y1122700D02*
Y1109100D01*
G01Y1142100D02*
Y1129400D01*
G01Y1167639D02*
Y1149400D01*
G01X586071Y1268268D02*
X592271D01*
G01X586071Y1265068D02*
Y1268268D01*
G01X592271Y1265068D02*
X586071D01*
G01Y1264268D02*
X592271D01*
G01X586071Y1261068D02*
Y1264268D01*
G01X592271Y1261068D02*
X586071D01*
G01X580645Y1431302D02*
X580270Y1431675D01*
X579645Y1431955D01*
X578770Y1432142D01*
X578020Y1431955D01*
X577520Y1431582D01*
X577145Y1430928D01*
Y1428408D01*
X584645D01*
Y1431488D01*
X584145Y1432142D01*
X583395Y1432515D01*
X582520Y1432702D01*
X581645Y1432515D01*
X580895Y1431955D01*
X580645Y1431302D01*
Y1428408D01*
G01X584645Y1437868D02*
X583020Y1438055D01*
X581645Y1438335D01*
X580395Y1438708D01*
X579020Y1439175D01*
X577145Y1439922D01*
Y1436188D01*
G01X583022Y1558466D02*
Y1556244D01*
X583175Y1555779D01*
X583482Y1555469D01*
X583865Y1555366D01*
X584248Y1555469D01*
X584555Y1555779D01*
X584708Y1556244D01*
Y1558466D01*
G01X586237Y1556658D02*
X586505Y1557019D01*
X586735Y1557226D01*
X587042Y1557329D01*
X587310Y1557226D01*
X587502Y1557019D01*
X587655Y1556709D01*
X587693Y1556348D01*
X587655Y1556038D01*
X587502Y1555728D01*
X587272Y1555469D01*
X587003Y1555366D01*
X586697Y1555469D01*
X586428Y1555779D01*
X586275Y1556244D01*
X586237Y1556761D01*
X586313Y1557433D01*
X586428Y1557794D01*
X586620Y1558156D01*
X586888Y1558414D01*
X587157Y1558466D01*
X587425Y1558363D01*
X587617Y1558104D01*
G01X590065Y1558466D02*
X589758Y1558363D01*
X589528Y1558104D01*
X589375Y1557794D01*
X589260Y1557381D01*
X589222Y1556916D01*
X589260Y1556451D01*
X589375Y1556038D01*
X589528Y1555728D01*
X589758Y1555469D01*
X590065Y1555366D01*
X590372Y1555469D01*
X590602Y1555728D01*
X590755Y1556038D01*
X590870Y1556451D01*
X590908Y1556916D01*
X590870Y1557381D01*
X590755Y1557794D01*
X590602Y1558104D01*
X590372Y1558363D01*
X590065Y1558466D01*
G01X593165Y1555366D02*
Y1558466D01*
X592705Y1557846D01*
G01Y1555366D02*
X593625D01*
G01X595537Y1556658D02*
X595805Y1557019D01*
X596035Y1557226D01*
X596342Y1557329D01*
X596610Y1557226D01*
X596802Y1557019D01*
X596955Y1556709D01*
X596993Y1556348D01*
X596955Y1556038D01*
X596802Y1555728D01*
X596572Y1555469D01*
X596303Y1555366D01*
X595997Y1555469D01*
X595728Y1555779D01*
X595575Y1556244D01*
X595537Y1556761D01*
X595613Y1557433D01*
X595728Y1557794D01*
X595920Y1558156D01*
X596188Y1558414D01*
X596457Y1558466D01*
X596725Y1558363D01*
X596917Y1558104D01*
G01X577031Y1626488D02*
Y1633988D01*
X579271D01*
X580018Y1633613D01*
X580578Y1632738D01*
X580765Y1631738D01*
X580578Y1630738D01*
X580111Y1629988D01*
X579271Y1629613D01*
X577031D01*
G01X584531Y1626488D02*
Y1633988D01*
X586865D01*
X587611Y1633613D01*
X588078Y1633113D01*
X588265Y1632113D01*
X588078Y1631113D01*
X587518Y1630488D01*
X586865Y1630113D01*
X584531D01*
G01X586865D02*
X588265Y1626488D01*
G01X595765D02*
X592031D01*
Y1633988D01*
X595765D01*
G01X594271Y1630363D02*
X592031D01*
G01X599438Y1627488D02*
X600185Y1626863D01*
X601025Y1626488D01*
X601771D01*
X602518Y1626863D01*
X603078Y1627488D01*
X603358Y1628363D01*
X603171Y1629238D01*
X602705Y1629988D01*
X601865Y1630488D01*
X600745Y1630738D01*
X600091Y1631238D01*
X599811Y1632113D01*
X599998Y1632988D01*
X600465Y1633613D01*
X601118Y1633988D01*
X601771D01*
X602425Y1633738D01*
X602985Y1633113D01*
G01X606938Y1627488D02*
X607685Y1626863D01*
X608525Y1626488D01*
X609271D01*
X610018Y1626863D01*
X610578Y1627488D01*
X610858Y1628363D01*
X610671Y1629238D01*
X610205Y1629988D01*
X609365Y1630488D01*
X608245Y1630738D01*
X607591Y1631238D01*
X607311Y1632113D01*
X607498Y1632988D01*
X607965Y1633613D01*
X608618Y1633988D01*
X609271D01*
X609925Y1633738D01*
X610485Y1633113D01*
G01X615185Y1628988D02*
X617611D01*
G01X622125Y1626488D02*
Y1633988D01*
X625671D01*
G01X624365Y1630363D02*
X622125D01*
G01X630278Y1633988D02*
X632518D01*
G01X631398D02*
Y1626488D01*
G01X630278D02*
X632518D01*
G01X638898Y1633988D02*
Y1626488D01*
G01X636751Y1633988D02*
X641045D01*
G01X587463Y1656472D02*
X584363D01*
X586585Y1655054D01*
Y1656970D01*
G01X578969Y1655169D02*
X579331Y1655399D01*
X579537Y1655705D01*
X579589Y1656050D01*
X579537Y1656357D01*
X579279Y1656664D01*
X578969Y1656855D01*
X578659Y1656894D01*
X578297Y1656817D01*
X578039Y1656549D01*
X577936Y1656280D01*
Y1655935D01*
G01Y1656280D02*
X577781Y1656510D01*
X577522Y1656702D01*
X577212Y1656779D01*
X576902Y1656702D01*
X576644Y1656510D01*
X576489Y1656165D01*
X576541Y1655820D01*
X576747Y1655475D01*
G01X592101Y94773D02*
Y88573D01*
G01D02*
X588901D01*
G01D02*
Y94773D01*
G01X603880Y88573D02*
X600680D01*
G01D02*
Y94773D01*
G01X603928Y101970D02*
X600728D01*
G01D02*
Y108170D01*
G01X592112D02*
Y101970D01*
G01D02*
X588912D01*
G01D02*
Y108170D01*
G01X588901Y94773D02*
X592101D01*
G01X600680D02*
X603880D01*
G01X600728Y108170D02*
X603928D01*
G01X588912D02*
X592112D01*
G01X598667Y134808D02*
Y138008D01*
G01X604867Y134808D02*
X598667D01*
G01X598670Y133870D02*
X604870D01*
Y130670D01*
X598670D01*
Y133870D01*
G01X604869Y144040D02*
X598669D01*
G01D02*
Y147240D01*
G01D02*
X604869D01*
G01Y148040D02*
X598669D01*
G01D02*
Y151240D01*
G01Y143240D02*
X604869D01*
G01Y140040D02*
X598669D01*
G01D02*
Y143240D01*
G01X598667Y138008D02*
X604867D01*
G01X593660Y155969D02*
Y162169D01*
G01D02*
X596860D01*
G01D02*
Y155969D01*
G01D02*
X593660D01*
G01X607378Y156040D02*
X601178D01*
G01D02*
Y159240D01*
G01D02*
X607378D01*
G01X604869Y152040D02*
X598669D01*
G01D02*
Y155240D01*
G01D02*
X604869D01*
G01X598669Y151240D02*
X604869D01*
G01X589794Y179650D02*
Y173450D01*
G01X598809Y181795D02*
Y179573D01*
X598962Y179108D01*
X599269Y178798D01*
X599652Y178695D01*
X600035Y178798D01*
X600342Y179108D01*
X600495Y179573D01*
Y181795D01*
G01X602100Y179057D02*
X602369Y178798D01*
X602675Y178695D01*
X602982Y178798D01*
X603250Y179108D01*
X603442Y179573D01*
X603519Y180038D01*
Y180607D01*
X603442Y181072D01*
X603250Y181485D01*
X603020Y181692D01*
X602752Y181795D01*
X602445Y181692D01*
X602215Y181485D01*
X602062Y181175D01*
X601985Y180762D01*
X602062Y180400D01*
X602254Y180038D01*
X602484Y179832D01*
X602752Y179780D01*
X603059Y179883D01*
X603289Y180142D01*
X603519Y180607D01*
G01X605852Y178695D02*
X606120Y178747D01*
X606427Y178902D01*
X606619Y179160D01*
X606695Y179522D01*
X606619Y179883D01*
X606389Y180193D01*
X606044Y180348D01*
X605660D01*
X605430Y180452D01*
X605239Y180710D01*
X605162Y181072D01*
X605277Y181433D01*
X605545Y181692D01*
X605852Y181795D01*
X606159Y181692D01*
X606427Y181433D01*
X606542Y181072D01*
X606465Y180710D01*
X606274Y180452D01*
X606044Y180348D01*
X605660D01*
X605315Y180193D01*
X605085Y179883D01*
X605009Y179522D01*
X605085Y179160D01*
X605277Y178902D01*
X605584Y178747D01*
X605852Y178695D01*
G01X609202Y165691D02*
X598802D01*
G01D02*
Y177699D01*
G01D02*
X602002D01*
G01D02*
X604002Y175632D01*
G01X603893Y204661D02*
X600693D01*
G01D02*
Y210861D01*
G01X595623Y210591D02*
Y207391D01*
G01X589423D02*
Y210591D01*
G01X595623Y207391D02*
X589423D01*
G01X596694Y196661D02*
Y202861D01*
G01D02*
X599894D01*
G01D02*
Y196661D01*
G01D02*
X596694D01*
G01X600694D02*
Y202861D01*
G01D02*
X603894D01*
G01Y196661D02*
X600694D01*
G01X595629Y222877D02*
Y219677D01*
G01X589429Y222877D02*
X595629D01*
G01X589429Y219677D02*
Y222877D01*
G01X595629Y219677D02*
X589429D01*
G01X600693Y210861D02*
X603893D01*
G01X595629Y218877D02*
Y215677D01*
G01X589429D02*
Y218877D01*
G01X595629Y215677D02*
X589429D01*
G01Y218877D02*
X595629D01*
G01X589423Y210591D02*
X595623D01*
G01X595629Y226877D02*
Y223677D01*
G01X589429D02*
Y226877D01*
G01X595629Y223677D02*
X589429D01*
G01X595629Y214877D02*
Y211677D01*
G01X589429Y214877D02*
X595629D01*
G01X589429Y211677D02*
Y214877D01*
G01X595629Y211677D02*
X589429D01*
G01X595629Y230877D02*
Y227677D01*
G01X589429D02*
Y230877D01*
G01X595629Y227677D02*
X589429D01*
G01Y230877D02*
X595629D01*
G01X589429Y226877D02*
X595629D01*
G01X600107Y263573D02*
Y251092D01*
G01X602823Y288121D02*
X596623D01*
G01D02*
Y291321D01*
G01D02*
X602823D01*
G01D02*
Y288121D01*
G01X600652Y370417D02*
Y368195D01*
X600805Y367730D01*
X601112Y367420D01*
X601495Y367317D01*
X601878Y367420D01*
X602185Y367730D01*
X602338Y368195D01*
Y370417D01*
G01X603867Y369900D02*
X604097Y370210D01*
X604365Y370365D01*
X604672Y370417D01*
X605055Y370314D01*
X605323Y370055D01*
X605400Y369745D01*
X605362Y369435D01*
X605208Y369177D01*
X604442Y368660D01*
X604097Y368299D01*
X603867Y367782D01*
X603790Y367317D01*
X605400D01*
G01X608155D02*
Y370417D01*
X606737Y368195D01*
X608653D01*
G01X611255Y367317D02*
Y370417D01*
X609837Y368195D01*
X611753D01*
G01X599045Y372027D02*
Y380827D01*
G01X612645Y372027D02*
X599045D01*
G01Y382827D02*
Y391627D01*
G01X612645Y382827D02*
X599045D01*
G01X604845Y380827D02*
X599045D01*
G01X588710Y401887D02*
X594910D01*
G01D02*
Y398687D01*
G01D02*
X588710D01*
G01D02*
Y401887D01*
G01X594910Y405887D02*
Y402687D01*
G01D02*
X588710D01*
G01D02*
Y405887D01*
G01X604845Y391627D02*
X599045D01*
G01X599401Y399180D02*
Y396958D01*
X599554Y396493D01*
X599861Y396183D01*
X600244Y396080D01*
X600627Y396183D01*
X600934Y396493D01*
X601087Y396958D01*
Y399180D01*
G01X602616Y398663D02*
X602846Y398973D01*
X603114Y399128D01*
X603421Y399180D01*
X603804Y399077D01*
X604072Y398818D01*
X604149Y398508D01*
X604111Y398198D01*
X603957Y397940D01*
X603191Y397423D01*
X602846Y397062D01*
X602616Y396545D01*
X602539Y396080D01*
X604149D01*
G01X605601Y396700D02*
X605831Y396338D01*
X606137Y396132D01*
X606482Y396080D01*
X606789Y396132D01*
X607096Y396390D01*
X607287Y396700D01*
X607326Y397010D01*
X607249Y397372D01*
X606981Y397630D01*
X606712Y397733D01*
X606367D01*
G01X606712D02*
X606942Y397888D01*
X607134Y398147D01*
X607211Y398457D01*
X607134Y398767D01*
X606942Y399025D01*
X606597Y399180D01*
X606252Y399128D01*
X605907Y398922D01*
G01X608892Y396442D02*
X609161Y396183D01*
X609467Y396080D01*
X609774Y396183D01*
X610042Y396493D01*
X610234Y396958D01*
X610311Y397423D01*
Y397992D01*
X610234Y398457D01*
X610042Y398870D01*
X609812Y399077D01*
X609544Y399180D01*
X609237Y399077D01*
X609007Y398870D01*
X608854Y398560D01*
X608777Y398147D01*
X608854Y397785D01*
X609046Y397423D01*
X609276Y397217D01*
X609544Y397165D01*
X609851Y397268D01*
X610081Y397527D01*
X610311Y397992D01*
G01X612497Y399956D02*
X601473D01*
G01D02*
Y408618D01*
G01X601400Y410400D02*
Y413600D01*
G01X607600Y410400D02*
X601400D01*
G01Y413600D02*
X607600D01*
G01X588710Y405887D02*
X594910D01*
G01X592158Y417105D02*
Y423305D01*
G01X595358Y417105D02*
X592158D01*
G01X595358Y423305D02*
Y417105D01*
G01X612497Y408618D02*
X601473D01*
G01X601898Y415398D02*
X604500Y418000D01*
G01X597676Y415398D02*
X601898D01*
G01X597676Y427602D02*
Y415398D01*
G01X592158Y423305D02*
X595358D01*
G01X607771Y429449D02*
X591571D01*
G01D02*
Y442449D01*
G01X611324Y427602D02*
X597676D01*
G01X591900Y443900D02*
Y447100D01*
G01X598100Y443900D02*
X591900D01*
G01Y447100D02*
X598100D01*
G01D02*
Y443900D01*
G01X591900Y447900D02*
Y451100D01*
G01X598100Y447900D02*
X591900D01*
G01X598100Y451100D02*
Y447900D01*
G01X591571Y442449D02*
X598171D01*
G01D02*
X599671Y439949D01*
G01D02*
X601171Y442449D01*
G01D02*
X607771D01*
G01X601598Y462749D02*
X595398D01*
G01D02*
Y465949D01*
G01X601598D02*
Y462749D01*
G01X589027Y460061D02*
X595227D01*
G01D02*
Y456861D01*
G01D02*
X589027D01*
G01D02*
Y460061D01*
G01X591900Y451100D02*
X598100D01*
G01X589106Y452642D02*
Y455842D01*
G01X595306Y452642D02*
X589106D01*
G01X595306Y455842D02*
Y452642D01*
G01X589106Y455842D02*
X595306D01*
G01X596339Y455081D02*
Y452859D01*
X596492Y452394D01*
X596799Y452084D01*
X597182Y451981D01*
X597565Y452084D01*
X597872Y452394D01*
X598025Y452859D01*
Y455081D01*
G01X599554Y454564D02*
X599784Y454874D01*
X600052Y455029D01*
X600359Y455081D01*
X600742Y454978D01*
X601010Y454719D01*
X601087Y454409D01*
X601049Y454099D01*
X600895Y453841D01*
X600129Y453324D01*
X599784Y452963D01*
X599554Y452446D01*
X599477Y451981D01*
X601087D01*
G01X603842D02*
Y455081D01*
X602424Y452859D01*
X604340D01*
G01X595398Y465949D02*
X601598D01*
G01X588903Y470493D02*
X595103D01*
G01D02*
Y467293D01*
G01D02*
X588903D01*
G01D02*
Y470493D01*
G01X595103Y472753D02*
X588903D01*
G01D02*
Y475953D01*
G01D02*
X595103D01*
G01D02*
Y472753D01*
G01X595121Y481231D02*
Y478031D01*
G01D02*
X588921D01*
G01D02*
Y481231D01*
G01D02*
X595121D01*
G01X592400Y491900D02*
Y495100D01*
G01X598600Y491900D02*
X592400D01*
G01X598600Y495100D02*
Y491900D01*
G01X601364Y488534D02*
Y486294D01*
G01X602989Y487507D02*
X599739D01*
G01X590205Y484031D02*
Y487969D01*
G01X597074Y488756D02*
Y483244D01*
G01X592400Y495100D02*
X598600D01*
G01X589121Y754800D02*
Y751700D01*
G01X601856Y756479D02*
X603700D01*
G01X601856Y750279D02*
Y756479D01*
G01X603700Y750279D02*
X601856D01*
G01X601089Y750265D02*
X599500D01*
G01X601089Y756465D02*
Y750265D01*
G01X599500Y756465D02*
X601089D01*
G01X597889Y751700D02*
Y755000D01*
G01X593889Y756465D02*
X595200D01*
G01X593889Y750265D02*
Y756465D01*
G01X597089Y755000D02*
Y751700D01*
G01X595700Y750265D02*
X593889D01*
G01X593121Y750333D02*
X591600D01*
G01X593121Y756533D02*
Y750333D01*
G01X591600Y756533D02*
X593121D01*
G01X589921Y751700D02*
Y754800D01*
G01X592460Y901300D02*
Y860721D01*
G01Y925800D02*
Y910700D01*
G01Y951300D02*
Y935300D01*
G01Y969300D02*
Y958900D01*
G01Y1008700D02*
Y976500D01*
G01Y1064200D02*
Y1013100D01*
G01Y1083800D02*
Y1071000D01*
G01Y1102600D02*
Y1091000D01*
G01Y1125000D02*
Y1108800D01*
G01Y1174700D02*
Y1135000D01*
G01X598671Y1264998D02*
Y1268198D01*
G01X604871Y1264998D02*
X598671D01*
G01Y1268198D02*
X604871D01*
G01X592271Y1268268D02*
Y1265068D01*
G01Y1264268D02*
Y1261068D01*
G01X598671Y1260998D02*
Y1264198D01*
G01X604871Y1260998D02*
X598671D01*
G01Y1264198D02*
X604871D01*
G01X598671Y1272198D02*
X604871D01*
G01X598671Y1268998D02*
Y1272198D01*
G01X604871Y1268998D02*
X598671D01*
G01Y1280198D02*
X604871D01*
G01X598671Y1276998D02*
Y1280198D01*
G01X604871Y1276998D02*
X598671D01*
G01Y1276198D02*
X604871D01*
G01X598671Y1272998D02*
Y1276198D01*
G01X604871Y1272998D02*
X598671D01*
G01X589988Y1413783D02*
Y1421283D01*
X591854D01*
X592601Y1420908D01*
X593161Y1420408D01*
X593628Y1419658D01*
X594001Y1418783D01*
X594094Y1417533D01*
X594001Y1416283D01*
X593628Y1415408D01*
X593161Y1414658D01*
X592601Y1414158D01*
X591854Y1413783D01*
X589988D01*
G01X598421Y1421283D02*
X600661D01*
G01X599541D02*
Y1413783D01*
G01X598421D02*
X600661D01*
G01X604614D02*
Y1421283D01*
X607041Y1415033D01*
X609468Y1421283D01*
Y1413783D01*
G01X612114D02*
Y1421283D01*
X614541Y1415033D01*
X616968Y1421283D01*
Y1413783D01*
G01X595645Y1431302D02*
X595270Y1431675D01*
X594645Y1431955D01*
X593770Y1432142D01*
X593020Y1431955D01*
X592520Y1431582D01*
X592145Y1430928D01*
Y1428408D01*
X599645D01*
Y1431488D01*
X599145Y1432142D01*
X598395Y1432515D01*
X597520Y1432702D01*
X596645Y1432515D01*
X595895Y1431955D01*
X595645Y1431302D01*
Y1428408D01*
G01X599645Y1438055D02*
X599520Y1438708D01*
X599145Y1439455D01*
X598520Y1439922D01*
X597645Y1440108D01*
X596770Y1439922D01*
X596020Y1439362D01*
X595645Y1438522D01*
Y1437588D01*
X595395Y1437028D01*
X594770Y1436562D01*
X593895Y1436375D01*
X593020Y1436655D01*
X592395Y1437308D01*
X592145Y1438055D01*
X592395Y1438802D01*
X593020Y1439455D01*
X593895Y1439735D01*
X594770Y1439548D01*
X595395Y1439082D01*
X595645Y1438522D01*
Y1437588D01*
X596020Y1436748D01*
X596770Y1436188D01*
X597645Y1436002D01*
X598520Y1436188D01*
X599145Y1436655D01*
X599520Y1437402D01*
X599645Y1438055D01*
G01X603602Y1424759D02*
X588602D01*
G01D02*
Y1450259D01*
G01X601919Y1655284D02*
X601558Y1655552D01*
X601351Y1655782D01*
X601248Y1656089D01*
X601351Y1656357D01*
X601558Y1656549D01*
X601868Y1656702D01*
X602229Y1656740D01*
X602539Y1656702D01*
X602849Y1656549D01*
X603108Y1656319D01*
X603211Y1656050D01*
X603108Y1655744D01*
X602798Y1655475D01*
X602333Y1655322D01*
X601816Y1655284D01*
X601144Y1655360D01*
X600783Y1655475D01*
X600421Y1655667D01*
X600163Y1655935D01*
X600111Y1656204D01*
X600214Y1656472D01*
X600473Y1656664D01*
G01X594872Y1655169D02*
X595130Y1655399D01*
X595285Y1655667D01*
X595337Y1656012D01*
X595234Y1656357D01*
X595027Y1656625D01*
X594665Y1656817D01*
X594252Y1656855D01*
X593839Y1656779D01*
X593580Y1656587D01*
X593374Y1656319D01*
X593322Y1656050D01*
X593374Y1655782D01*
X593580Y1655437D01*
X592237Y1655552D01*
Y1656587D01*
G01X619782Y88573D02*
X616582D01*
G01D02*
Y94773D01*
G01X603880D02*
Y88573D01*
G01X619856Y101970D02*
X616656D01*
G01D02*
Y108170D01*
G01X603928D02*
Y101970D01*
G01X616582Y94773D02*
X619782D01*
G01X616656Y108170D02*
X619856D01*
G01X604867Y138008D02*
Y134808D01*
G01X604869Y147240D02*
Y144040D01*
G01Y151240D02*
Y148040D01*
G01Y143240D02*
Y140040D01*
G01X607378Y159240D02*
Y156040D01*
G01X604869Y155240D02*
Y152040D01*
G01X617882Y178120D02*
X611682D01*
G01D02*
Y181320D01*
G01X617882D02*
Y178120D01*
G01X609202Y177699D02*
Y165691D01*
G01X604002Y175632D02*
X606002Y177699D01*
G01D02*
X609202D01*
G01X611682Y181320D02*
X617882D01*
G01X610394Y195861D02*
Y189661D01*
G01D02*
X607194D01*
G01D02*
Y195861D01*
G01X610393Y210861D02*
Y204661D01*
G01D02*
X607193D01*
G01D02*
Y210861D01*
G01X603893D02*
Y204661D01*
G01X607194Y195861D02*
X610394D01*
G01X607194Y196661D02*
Y202861D01*
G01D02*
X610394D01*
G01D02*
Y196661D01*
G01D02*
X607194D01*
G01X603894Y202861D02*
Y196661D01*
G01X607193Y210861D02*
X610393D01*
G01X616135Y218971D02*
X614182D01*
G01X616135Y220924D02*
Y218971D01*
G01X604323D02*
Y220924D01*
G01X606276Y218971D02*
X604323D01*
G01X616135Y230783D02*
Y228830D01*
G01X614182Y230783D02*
X616135D01*
G01X604323D02*
X606276D01*
G01X604323Y228830D02*
Y230783D01*
G01X610493Y258410D02*
X604293D01*
G01D02*
Y261610D01*
G01D02*
X610493D01*
G01D02*
Y258410D01*
G01X605461Y264073D02*
X605653Y263763D01*
X605883Y263556D01*
X606151Y263453D01*
X606458Y263556D01*
X606688Y263763D01*
X606918Y264073D01*
X606995Y264486D01*
Y266553D01*
G01X608485Y263918D02*
X608715Y263660D01*
X608983Y263505D01*
X609328Y263453D01*
X609673Y263556D01*
X609941Y263763D01*
X610133Y264125D01*
X610171Y264538D01*
X610095Y264951D01*
X609903Y265210D01*
X609635Y265416D01*
X609366Y265468D01*
X609098Y265416D01*
X608753Y265210D01*
X608868Y266553D01*
X609903D01*
G01X612351Y263453D02*
X612428Y264125D01*
X612543Y264693D01*
X612696Y265210D01*
X612888Y265778D01*
X613195Y266553D01*
X611661D01*
G01X614016Y279134D02*
Y269410D01*
G01X617105Y291205D02*
Y297405D01*
G01D02*
X620305D01*
G01Y291205D02*
X617105D01*
G01X609578Y299014D02*
Y292925D01*
G01Y319303D02*
Y313214D01*
G01X620560Y365227D02*
X614360D01*
G01D02*
Y368427D01*
G01D02*
X620560D01*
G01X612645Y380827D02*
Y372027D01*
G01X613785Y385702D02*
Y391902D01*
G01X616985D02*
Y385702D01*
G01D02*
X613785D01*
G01Y374902D02*
Y381102D01*
G01D02*
X616985D01*
G01D02*
Y374902D01*
G01D02*
X613785D01*
G01X612645Y391627D02*
Y382827D01*
G01X606845Y380827D02*
X605845Y379327D01*
G01D02*
X604845Y380827D01*
G01X612645D02*
X606845D01*
G01X613785Y391902D02*
X616985D01*
G01Y403253D02*
Y397053D01*
G01D02*
X613785D01*
G01D02*
Y403253D01*
G01D02*
X616985D01*
G01X606845Y391627D02*
X605845Y390127D01*
G01D02*
X604845Y391627D01*
G01X612645D02*
X606845D01*
G01X612497Y408618D02*
Y399956D01*
G01X613785Y405321D02*
Y411521D01*
G01D02*
X616985D01*
G01D02*
Y405321D01*
G01D02*
X613785D01*
G01X607600Y413600D02*
Y410400D01*
G01X613900Y416400D02*
Y419600D01*
G01X620100Y416400D02*
X613900D01*
G01X619435Y409223D02*
X619128Y409275D01*
X618860Y409481D01*
X618630Y409791D01*
X618477Y410153D01*
X618400Y410566D01*
Y410980D01*
X618477Y411393D01*
X618630Y411755D01*
X618860Y412065D01*
X619128Y412271D01*
X619435Y412323D01*
X619742Y412271D01*
X620010Y412065D01*
X620240Y411755D01*
X620393Y411393D01*
X620470Y410980D01*
Y410566D01*
X620393Y410153D01*
X620240Y409791D01*
X620010Y409481D01*
X619742Y409275D01*
X619435Y409223D01*
G01X619742Y410050D02*
X620202Y409223D01*
G01X621883Y409585D02*
X622152Y409326D01*
X622458Y409223D01*
X622765Y409326D01*
X623033Y409636D01*
X623225Y410101D01*
X623302Y410566D01*
Y411135D01*
X623225Y411600D01*
X623033Y412013D01*
X622803Y412220D01*
X622535Y412323D01*
X622228Y412220D01*
X621998Y412013D01*
X621845Y411703D01*
X621768Y411290D01*
X621845Y410928D01*
X622037Y410566D01*
X622267Y410360D01*
X622535Y410308D01*
X622842Y410411D01*
X623072Y410670D01*
X623302Y411135D01*
G01X625635Y412323D02*
X625328Y412220D01*
X625098Y411961D01*
X624945Y411651D01*
X624830Y411238D01*
X624792Y410773D01*
X624830Y410308D01*
X624945Y409895D01*
X625098Y409585D01*
X625328Y409326D01*
X625635Y409223D01*
X625942Y409326D01*
X626172Y409585D01*
X626325Y409895D01*
X626440Y410308D01*
X626478Y410773D01*
X626440Y411238D01*
X626325Y411651D01*
X626172Y411961D01*
X625942Y412220D01*
X625635Y412323D01*
G01X628735D02*
X628428Y412220D01*
X628198Y411961D01*
X628045Y411651D01*
X627930Y411238D01*
X627892Y410773D01*
X627930Y410308D01*
X628045Y409895D01*
X628198Y409585D01*
X628428Y409326D01*
X628735Y409223D01*
X629042Y409326D01*
X629272Y409585D01*
X629425Y409895D01*
X629540Y410308D01*
X629578Y410773D01*
X629540Y411238D01*
X629425Y411651D01*
X629272Y411961D01*
X629042Y412220D01*
X628735Y412323D01*
G01X630992Y409843D02*
X631222Y409481D01*
X631528Y409275D01*
X631873Y409223D01*
X632180Y409275D01*
X632487Y409533D01*
X632678Y409843D01*
X632717Y410153D01*
X632640Y410515D01*
X632372Y410773D01*
X632103Y410876D01*
X631758D01*
G01X632103D02*
X632333Y411031D01*
X632525Y411290D01*
X632602Y411600D01*
X632525Y411910D01*
X632333Y412168D01*
X631988Y412323D01*
X631643Y412271D01*
X631298Y412065D01*
G01X611324Y415398D02*
Y427602D01*
G01X607102Y415398D02*
X611324D01*
G01X604500Y418000D02*
X607102Y415398D01*
G01X613791Y428501D02*
X619991D01*
G01X613791Y425301D02*
Y428501D01*
G01X619991Y425301D02*
X613791D01*
G01X613900Y419600D02*
X620100D01*
G01X607771Y442449D02*
Y429449D01*
G01X610505Y432490D02*
Y430268D01*
X610658Y429803D01*
X610965Y429493D01*
X611348Y429390D01*
X611731Y429493D01*
X612038Y429803D01*
X612191Y430268D01*
Y432490D01*
G01X613720Y431973D02*
X613950Y432283D01*
X614218Y432438D01*
X614525Y432490D01*
X614908Y432387D01*
X615176Y432128D01*
X615253Y431818D01*
X615215Y431508D01*
X615061Y431250D01*
X614295Y430733D01*
X613950Y430372D01*
X613720Y429855D01*
X613643Y429390D01*
X615253D01*
G01X616705Y430010D02*
X616935Y429648D01*
X617241Y429442D01*
X617586Y429390D01*
X617893Y429442D01*
X618200Y429700D01*
X618391Y430010D01*
X618430Y430320D01*
X618353Y430682D01*
X618085Y430940D01*
X617816Y431043D01*
X617471D01*
G01X617816D02*
X618046Y431198D01*
X618238Y431457D01*
X618315Y431767D01*
X618238Y432077D01*
X618046Y432335D01*
X617701Y432490D01*
X617356Y432438D01*
X617011Y432232D01*
G01X610400Y441600D02*
X616600D01*
G01D02*
Y438400D01*
G01D02*
X610400D01*
G01D02*
Y441600D01*
G01X621100Y437400D02*
X617900D01*
G01Y443600D02*
X621100D01*
G01X617900Y437400D02*
Y443600D01*
G01X604823Y444661D02*
Y457339D01*
G01X620177Y444661D02*
X604823D01*
G01Y457339D02*
X620177D01*
G01X612047Y462088D02*
X613956Y459379D01*
G01D02*
X620104D01*
G01X603990Y470797D02*
Y459379D01*
G01D02*
X610138D01*
G01D02*
X612047Y462088D01*
G01X604211Y473464D02*
Y485945D01*
G01X619565Y473267D02*
X604211D01*
G01X620104Y470797D02*
X603990D01*
G01X607009Y489991D02*
Y487769D01*
X607162Y487304D01*
X607469Y486994D01*
X607852Y486891D01*
X608235Y486994D01*
X608542Y487304D01*
X608695Y487769D01*
Y489991D01*
G01X610109Y487511D02*
X610339Y487149D01*
X610645Y486943D01*
X610990Y486891D01*
X611297Y486943D01*
X611604Y487201D01*
X611795Y487511D01*
X611834Y487821D01*
X611757Y488183D01*
X611489Y488441D01*
X611220Y488544D01*
X610875D01*
G01X611220D02*
X611450Y488699D01*
X611642Y488958D01*
X611719Y489268D01*
X611642Y489578D01*
X611450Y489836D01*
X611105Y489991D01*
X610760Y489939D01*
X610415Y489733D01*
G01X613324Y489474D02*
X613554Y489784D01*
X613822Y489939D01*
X614129Y489991D01*
X614512Y489888D01*
X614780Y489629D01*
X614857Y489319D01*
X614819Y489009D01*
X614665Y488751D01*
X613899Y488234D01*
X613554Y487873D01*
X613324Y487356D01*
X613247Y486891D01*
X614857D01*
G01X616309Y487356D02*
X616539Y487098D01*
X616807Y486943D01*
X617152Y486891D01*
X617497Y486994D01*
X617765Y487201D01*
X617957Y487563D01*
X617995Y487976D01*
X617919Y488389D01*
X617727Y488648D01*
X617459Y488854D01*
X617190Y488906D01*
X616922Y488854D01*
X616577Y488648D01*
X616692Y489991D01*
X617727D01*
G01X604211Y485945D02*
X619565D01*
G01X609056Y750279D02*
X607500D01*
G01X609056Y756479D02*
Y750279D01*
G01X607500Y756479D02*
X609056D01*
G01X605856Y752100D02*
Y754900D01*
G01X617043Y750291D02*
X615500D01*
G01X617043Y756491D02*
Y750291D01*
G01X615500Y756491D02*
X617043D01*
G01X613843Y752000D02*
Y754900D01*
G01X609843Y756491D02*
X611600D01*
G01X609843Y750291D02*
Y756491D01*
G01X613043Y754900D02*
Y752000D01*
G01X611700Y750291D02*
X609843D01*
G01X605056Y754900D02*
Y752100D01*
G01X614103Y777635D02*
Y775413D01*
X614256Y774948D01*
X614563Y774638D01*
X614946Y774535D01*
X615329Y774638D01*
X615636Y774948D01*
X615789Y775413D01*
Y777635D01*
G01X617318Y777118D02*
X617548Y777428D01*
X617816Y777583D01*
X618123Y777635D01*
X618506Y777532D01*
X618774Y777273D01*
X618851Y776963D01*
X618813Y776653D01*
X618659Y776395D01*
X617893Y775878D01*
X617548Y775517D01*
X617318Y775000D01*
X617241Y774535D01*
X618851D01*
G01X620418Y775827D02*
X620686Y776188D01*
X620916Y776395D01*
X621223Y776498D01*
X621491Y776395D01*
X621683Y776188D01*
X621836Y775878D01*
X621874Y775517D01*
X621836Y775207D01*
X621683Y774897D01*
X621453Y774638D01*
X621184Y774535D01*
X620878Y774638D01*
X620609Y774948D01*
X620456Y775413D01*
X620418Y775930D01*
X620494Y776602D01*
X620609Y776963D01*
X620801Y777325D01*
X621069Y777583D01*
X621338Y777635D01*
X621606Y777532D01*
X621798Y777273D01*
G01X604871Y1268198D02*
Y1264998D01*
G01Y1264198D02*
Y1260998D01*
G01Y1272198D02*
Y1268998D01*
G01Y1280198D02*
Y1276998D01*
G01Y1276198D02*
Y1272998D01*
G01X617759Y1368766D02*
X623959D01*
G01X617759Y1365566D02*
Y1368766D01*
G01X623959Y1365566D02*
X617759D01*
G01X617713Y1372782D02*
X623913D01*
G01X617713Y1369582D02*
Y1372782D01*
G01X623913Y1369582D02*
X617713D01*
G01X617738Y1384464D02*
X623938D01*
G01X617738Y1381264D02*
Y1384464D01*
G01X623938Y1381264D02*
X617738D01*
G01Y1380564D02*
X623938D01*
G01X617738Y1377364D02*
Y1380564D01*
G01X623938Y1377364D02*
X617738D01*
G01X617677Y1385132D02*
Y1388332D01*
G01X623877Y1385132D02*
X617677D01*
G01X617713Y1376682D02*
X623913D01*
G01X617713Y1373482D02*
Y1376682D01*
G01X623913Y1373482D02*
X617713D01*
G01X612182Y1382337D02*
X614682D01*
X614182Y1382657D01*
G01X612182D02*
Y1382017D01*
G01Y1380137D02*
X614682D01*
X614182Y1380457D01*
G01X612182D02*
Y1379817D01*
G01X617677Y1392332D02*
X623877D01*
G01X617677Y1389132D02*
Y1392332D01*
G01X623877Y1389132D02*
X617677D01*
G01Y1388332D02*
X623877D01*
G01X612500Y1393820D02*
X624519D01*
G01X610645Y1431302D02*
X610270Y1431675D01*
X609645Y1431955D01*
X608770Y1432142D01*
X608020Y1431955D01*
X607520Y1431582D01*
X607145Y1430928D01*
Y1428408D01*
X614645D01*
Y1431488D01*
X614145Y1432142D01*
X613395Y1432515D01*
X612520Y1432702D01*
X611645Y1432515D01*
X610895Y1431955D01*
X610645Y1431302D01*
Y1428408D01*
G01X613770Y1436468D02*
X614395Y1437122D01*
X614645Y1437868D01*
X614395Y1438615D01*
X613645Y1439268D01*
X612520Y1439735D01*
X611395Y1439922D01*
X610020D01*
X608895Y1439735D01*
X607895Y1439268D01*
X607395Y1438708D01*
X607145Y1438055D01*
X607395Y1437308D01*
X607895Y1436748D01*
X608645Y1436375D01*
X609645Y1436188D01*
X610520Y1436375D01*
X611395Y1436842D01*
X611895Y1437402D01*
X612020Y1438055D01*
X611770Y1438802D01*
X611145Y1439362D01*
X610020Y1439922D01*
G01X618602Y1424759D02*
X603602D01*
G01D02*
Y1450259D01*
G01X611085Y1655935D02*
X610413Y1656012D01*
X609845Y1656127D01*
X609328Y1656280D01*
X608760Y1656472D01*
X607985Y1656779D01*
Y1655245D01*
G01X618959Y1656012D02*
X618907Y1656280D01*
X618752Y1656587D01*
X618494Y1656779D01*
X618132Y1656855D01*
X617771Y1656779D01*
X617461Y1656549D01*
X617306Y1656204D01*
Y1655820D01*
X617202Y1655590D01*
X616944Y1655399D01*
X616582Y1655322D01*
X616221Y1655437D01*
X615962Y1655705D01*
X615859Y1656012D01*
X615962Y1656319D01*
X616221Y1656587D01*
X616582Y1656702D01*
X616944Y1656625D01*
X617202Y1656434D01*
X617306Y1656204D01*
Y1655820D01*
X617461Y1655475D01*
X617771Y1655245D01*
X618132Y1655169D01*
X618494Y1655245D01*
X618752Y1655437D01*
X618907Y1655744D01*
X618959Y1656012D01*
G01X629000Y64566D02*
X625904D01*
G01X619782Y94773D02*
Y88573D01*
G01X619856Y108170D02*
Y101970D01*
G01X627627Y130088D02*
X629849D01*
X630314Y130241D01*
X630624Y130548D01*
X630727Y130931D01*
X630624Y131314D01*
X630314Y131621D01*
X629849Y131774D01*
X627627D01*
G01X630727Y134031D02*
X627627D01*
X628247Y133571D01*
G01X630727D02*
Y134491D01*
G01X630262Y136288D02*
X630520Y136518D01*
X630675Y136786D01*
X630727Y137131D01*
X630624Y137476D01*
X630417Y137744D01*
X630055Y137936D01*
X629642Y137974D01*
X629229Y137898D01*
X628970Y137706D01*
X628764Y137438D01*
X628712Y137169D01*
X628764Y136901D01*
X628970Y136556D01*
X627627Y136671D01*
Y137706D01*
G01X630727Y140154D02*
X630055Y140231D01*
X629487Y140346D01*
X628970Y140499D01*
X628402Y140691D01*
X627627Y140998D01*
Y139464D01*
G01X635154Y132771D02*
X632552Y130169D01*
G01D02*
Y125947D01*
G01D02*
X644756D01*
G01X632552Y139595D02*
Y135373D01*
G01D02*
X635154Y132771D01*
G01X644756Y139595D02*
X632552D01*
G01X622910Y180209D02*
Y174009D01*
G01D02*
X619710D01*
G01D02*
Y180209D01*
G01D02*
X622910D01*
G01X623710Y174009D02*
Y180209D01*
G01D02*
X626910D01*
G01D02*
Y174009D01*
G01D02*
X623710D01*
G01X625129Y227877D02*
Y224677D01*
G01X618929D02*
Y227877D01*
G01X625129Y224677D02*
X618929D01*
G01X625129Y223377D02*
Y220177D01*
G01X618929Y223377D02*
X625129D01*
G01X618929Y220177D02*
Y223377D01*
G01X625129Y220177D02*
X618929D01*
G01X629009Y232075D02*
X632209D01*
G01X629009Y225875D02*
Y232075D01*
G01X632209Y225875D02*
X629009D01*
G01X632209Y232075D02*
Y225875D01*
G01X618929Y227877D02*
X625129D01*
G01X633009Y232575D02*
X639209D01*
G01X633009Y229375D02*
Y232575D01*
G01X639209Y229375D02*
X633009D01*
G01Y228575D02*
X639209D01*
G01X633009Y225375D02*
Y228575D01*
G01X639209Y225375D02*
X633009D01*
G01X624400Y238501D02*
Y236279D01*
X624553Y235814D01*
X624860Y235504D01*
X625243Y235401D01*
X625626Y235504D01*
X625933Y235814D01*
X626086Y236279D01*
Y238501D01*
G01X627615Y237984D02*
X627845Y238294D01*
X628113Y238449D01*
X628420Y238501D01*
X628803Y238398D01*
X629071Y238139D01*
X629148Y237829D01*
X629110Y237519D01*
X628956Y237261D01*
X628190Y236744D01*
X627845Y236383D01*
X627615Y235866D01*
X627538Y235401D01*
X629148D01*
G01X630715Y236693D02*
X630983Y237054D01*
X631213Y237261D01*
X631520Y237364D01*
X631788Y237261D01*
X631980Y237054D01*
X632133Y236744D01*
X632171Y236383D01*
X632133Y236073D01*
X631980Y235763D01*
X631750Y235504D01*
X631481Y235401D01*
X631175Y235504D01*
X630906Y235814D01*
X630753Y236279D01*
X630715Y236796D01*
X630791Y237468D01*
X630906Y237829D01*
X631098Y238191D01*
X631366Y238449D01*
X631635Y238501D01*
X631903Y238398D01*
X632095Y238139D01*
G01X635003Y235401D02*
Y238501D01*
X633585Y236279D01*
X635501D01*
G01X628305Y304405D02*
Y298205D01*
G01D02*
X625105D01*
G01D02*
Y304405D01*
G01X633105Y291455D02*
Y285255D01*
G01D02*
X629905D01*
G01D02*
Y291455D01*
G01D02*
X633105D01*
G01X625105Y291205D02*
Y297405D01*
G01D02*
X628305D01*
G01D02*
Y291205D01*
G01D02*
X625105D01*
G01X621105D02*
Y297405D01*
G01D02*
X624305D01*
G01D02*
Y291205D01*
G01D02*
X621105D01*
G01X620305Y297405D02*
Y291205D01*
G01X625105Y304405D02*
X628305D01*
G01X619985Y372952D02*
Y379152D01*
G01X623185D02*
Y372952D01*
G01D02*
X619985D01*
G01X620560Y368427D02*
Y365227D01*
G01X619985Y385702D02*
Y391902D01*
G01X623185D02*
Y385702D01*
G01D02*
X619985D01*
G01Y379152D02*
X623185D01*
G01X619985Y391902D02*
X623185D01*
G01X620100Y419600D02*
Y416400D01*
G01X623253Y414669D02*
Y423331D01*
G01X626600Y414669D02*
X623253D01*
G01X628500Y416869D02*
X626600Y414669D01*
G01X630400D02*
X628500Y416869D01*
G01X633747Y414669D02*
X630400D01*
G01X619991Y428501D02*
Y425301D01*
G01X632600Y428600D02*
Y425400D01*
G01X626400Y428600D02*
X632600D01*
G01X626400Y425400D02*
Y428600D01*
G01X632600Y425400D02*
X626400D01*
G01X623253Y423331D02*
X633747D01*
G01X634103Y436281D02*
X627903D01*
G01D02*
Y439481D01*
G01D02*
X634103D01*
G01X621100Y443600D02*
Y437400D01*
G01X620177Y457142D02*
Y444661D01*
G01X634759Y459841D02*
X628559D01*
G01D02*
Y463041D01*
G01D02*
X634759D01*
G01X622193Y459122D02*
Y456900D01*
X622346Y456435D01*
X622653Y456125D01*
X623036Y456022D01*
X623419Y456125D01*
X623726Y456435D01*
X623879Y456900D01*
Y459122D01*
G01X625408Y458605D02*
X625638Y458915D01*
X625906Y459070D01*
X626213Y459122D01*
X626596Y459019D01*
X626864Y458760D01*
X626941Y458450D01*
X626903Y458140D01*
X626749Y457882D01*
X625983Y457365D01*
X625638Y457004D01*
X625408Y456487D01*
X625331Y456022D01*
X626941D01*
G01X629236Y459122D02*
X628929Y459019D01*
X628699Y458760D01*
X628546Y458450D01*
X628431Y458037D01*
X628393Y457572D01*
X628431Y457107D01*
X628546Y456694D01*
X628699Y456384D01*
X628929Y456125D01*
X629236Y456022D01*
X629543Y456125D01*
X629773Y456384D01*
X629926Y456694D01*
X630041Y457107D01*
X630079Y457572D01*
X630041Y458037D01*
X629926Y458450D01*
X629773Y458760D01*
X629543Y459019D01*
X629236Y459122D01*
G01X631608Y457314D02*
X631876Y457675D01*
X632106Y457882D01*
X632413Y457985D01*
X632681Y457882D01*
X632873Y457675D01*
X633026Y457365D01*
X633064Y457004D01*
X633026Y456694D01*
X632873Y456384D01*
X632643Y456125D01*
X632374Y456022D01*
X632068Y456125D01*
X631799Y456435D01*
X631646Y456900D01*
X631608Y457417D01*
X631684Y458089D01*
X631799Y458450D01*
X631991Y458812D01*
X632259Y459070D01*
X632528Y459122D01*
X632796Y459019D01*
X632988Y458760D01*
G01X620104Y459379D02*
Y470797D01*
G01X634509Y467256D02*
X628309D01*
G01D02*
Y470456D01*
G01D02*
X634509D01*
G01X628321Y475620D02*
X634521D01*
G01Y472420D02*
X628321D01*
G01D02*
Y475620D01*
G01X619565Y485945D02*
Y473267D01*
G01X632644Y505938D02*
Y512138D01*
G01X635844Y505938D02*
X632644D01*
G01Y512138D02*
X635844D01*
G01X624519Y1256025D02*
Y781812D01*
G01Y1393820D02*
Y1256025D01*
G01X632002Y1358714D02*
Y1355514D01*
G01X625802D02*
Y1358714D01*
G01X632002Y1355514D02*
X625802D01*
G01X625103Y1354784D02*
X628303D01*
G01Y1348584D02*
X625103D01*
G01X628303Y1354784D02*
Y1348584D01*
G01X625103D02*
Y1354784D01*
G01X624312Y1356557D02*
X624152Y1356307D01*
X623965Y1356182D01*
X623752Y1356140D01*
X623485Y1356223D01*
X623298Y1356432D01*
X623245Y1356682D01*
X623272Y1356932D01*
X623378Y1357140D01*
X623912Y1357557D01*
X624152Y1357848D01*
X624312Y1358265D01*
X624365Y1358640D01*
X623245D01*
G01X621605D02*
Y1356140D01*
X621925Y1356640D01*
G01Y1358640D02*
X621285D01*
G01X625802Y1358714D02*
X632002D01*
G01X623959Y1368766D02*
Y1365566D01*
G01X623913Y1372782D02*
Y1369582D01*
G01X626845Y1363764D02*
X627095Y1363604D01*
X627220Y1363417D01*
X627262Y1363204D01*
X627179Y1362937D01*
X626970Y1362750D01*
X626720Y1362697D01*
X626470Y1362724D01*
X626262Y1362830D01*
X625845Y1363364D01*
X625554Y1363604D01*
X625137Y1363764D01*
X624762Y1363817D01*
Y1362697D01*
G01X627262Y1361057D02*
X627179Y1361270D01*
X626970Y1361430D01*
X626720Y1361537D01*
X626387Y1361617D01*
X626012Y1361644D01*
X625637Y1361617D01*
X625304Y1361537D01*
X625054Y1361430D01*
X624845Y1361270D01*
X624762Y1361057D01*
X624845Y1360844D01*
X625054Y1360684D01*
X625304Y1360577D01*
X625637Y1360497D01*
X626012Y1360470D01*
X626387Y1360497D01*
X626720Y1360577D01*
X626970Y1360684D01*
X627179Y1360844D01*
X627262Y1361057D01*
G01X628852Y1362414D02*
Y1364320D01*
G01X630758Y1362414D02*
X628852D01*
G01X624395Y1365257D02*
X627395D01*
G01X623938Y1384464D02*
Y1381264D01*
G01Y1380564D02*
Y1377364D01*
G01X631795Y1391557D02*
Y1385357D01*
G01X628595D02*
Y1391557D01*
G01X631795Y1385357D02*
X628595D01*
G01X624695D02*
Y1391557D01*
G01X627895Y1385357D02*
X624695D01*
G01X627895Y1391557D02*
Y1385357D01*
G01X623877Y1388332D02*
Y1385132D01*
G01X632495Y1385357D02*
Y1391557D01*
G01X635695Y1385357D02*
X632495D01*
G01X623913Y1376682D02*
Y1373482D01*
G01X628852Y1382100D02*
X630748D01*
G01X628852Y1380194D02*
Y1382100D01*
G01X627345Y1373057D02*
X625845D01*
G01X631595Y1384400D02*
Y1383657D01*
G01X623877Y1392332D02*
Y1389132D01*
G01X631600Y1399900D02*
X628400D01*
G01X631600Y1406100D02*
Y1399900D01*
G01X628400D02*
Y1406100D01*
G01X628595Y1391557D02*
X631795D01*
G01X624695D02*
X627895D01*
G01X632495D02*
X635695D01*
G01X625545Y1397280D02*
Y1394780D01*
X625865Y1395280D01*
G01Y1397280D02*
X625225D01*
G01X623345Y1394780D02*
X623558Y1394863D01*
X623718Y1395072D01*
X623825Y1395322D01*
X623905Y1395655D01*
X623932Y1396030D01*
X623905Y1396405D01*
X623825Y1396738D01*
X623718Y1396988D01*
X623558Y1397197D01*
X623345Y1397280D01*
X623132Y1397197D01*
X622972Y1396988D01*
X622865Y1396738D01*
X622785Y1396405D01*
X622758Y1396030D01*
X622785Y1395655D01*
X622865Y1395322D01*
X622972Y1395072D01*
X623132Y1394863D01*
X623345Y1394780D01*
G01X648602Y1411259D02*
X627813D01*
G01X628400Y1406100D02*
X631600D01*
G01X625645Y1431302D02*
X625270Y1431675D01*
X624645Y1431955D01*
X623770Y1432142D01*
X623020Y1431955D01*
X622520Y1431582D01*
X622145Y1430928D01*
Y1428408D01*
X629645D01*
Y1431488D01*
X629145Y1432142D01*
X628395Y1432515D01*
X627520Y1432702D01*
X626645Y1432515D01*
X625895Y1431955D01*
X625645Y1431302D01*
Y1428408D01*
G01X629645Y1438055D02*
X622145D01*
X623645Y1436935D01*
G01X629645D02*
Y1439175D01*
G01X622145Y1445555D02*
X622395Y1444808D01*
X623020Y1444248D01*
X623770Y1443875D01*
X624770Y1443595D01*
X625895Y1443502D01*
X627020Y1443595D01*
X628020Y1443875D01*
X628770Y1444248D01*
X629395Y1444808D01*
X629645Y1445555D01*
X629395Y1446302D01*
X628770Y1446862D01*
X628020Y1447235D01*
X627020Y1447515D01*
X625895Y1447608D01*
X624770Y1447515D01*
X623770Y1447235D01*
X623020Y1446862D01*
X622395Y1446302D01*
X622145Y1445555D01*
G01X633602Y1424759D02*
X618602D01*
G01D02*
Y1450259D01*
G01X631604Y1641997D02*
X631796Y1641687D01*
X632026Y1641480D01*
X632294Y1641377D01*
X632601Y1641480D01*
X632831Y1641687D01*
X633061Y1641997D01*
X633138Y1642410D01*
Y1644477D01*
G01X635471Y1641377D02*
Y1644477D01*
X635011Y1643857D01*
G01Y1641377D02*
X635931D01*
G01X638571Y1644477D02*
X638264Y1644374D01*
X638034Y1644115D01*
X637881Y1643805D01*
X637766Y1643392D01*
X637728Y1642927D01*
X637766Y1642462D01*
X637881Y1642049D01*
X638034Y1641739D01*
X638264Y1641480D01*
X638571Y1641377D01*
X638878Y1641480D01*
X639108Y1641739D01*
X639261Y1642049D01*
X639376Y1642462D01*
X639414Y1642927D01*
X639376Y1643392D01*
X639261Y1643805D01*
X639108Y1644115D01*
X638878Y1644374D01*
X638571Y1644477D01*
G01X641019Y1641739D02*
X641288Y1641480D01*
X641594Y1641377D01*
X641901Y1641480D01*
X642169Y1641790D01*
X642361Y1642255D01*
X642438Y1642720D01*
Y1643289D01*
X642361Y1643754D01*
X642169Y1644167D01*
X641939Y1644374D01*
X641671Y1644477D01*
X641364Y1644374D01*
X641134Y1644167D01*
X640981Y1643857D01*
X640904Y1643444D01*
X640981Y1643082D01*
X641173Y1642720D01*
X641403Y1642514D01*
X641671Y1642462D01*
X641978Y1642565D01*
X642208Y1642824D01*
X642438Y1643289D01*
G01X623622Y1657834D02*
Y1736118D01*
G01X628460Y1671913D02*
X625360D01*
X628460Y1673677D01*
X625360D01*
G01X628460Y1676522D02*
X625360D01*
X627943Y1677519D01*
X625360Y1678516D01*
X628460D01*
G01X625360Y1681476D02*
X628460D01*
Y1683010D01*
G01Y1686125D02*
X625360D01*
G01Y1687581D02*
X627272Y1686125D01*
G01X628460Y1687811D02*
X626393Y1686776D01*
G01X625360Y1695957D02*
Y1696877D01*
G01Y1696417D02*
X628460D01*
G01Y1695957D02*
Y1696877D01*
G01Y1700336D02*
X625360D01*
G01Y1701946D02*
X628460D01*
G01X626910D02*
Y1700336D01*
G01X627840Y1690925D02*
X628150Y1691117D01*
X628357Y1691347D01*
X628460Y1691615D01*
X628357Y1691922D01*
X628150Y1692152D01*
X627840Y1692382D01*
X627427Y1692459D01*
X625360D01*
G01X626910Y1706096D02*
Y1706863D01*
X627840D01*
X628150Y1706633D01*
X628357Y1706364D01*
X628460Y1705981D01*
X628357Y1705598D01*
X628150Y1705329D01*
X627840Y1705099D01*
X627478Y1704946D01*
X627065Y1704869D01*
X626703D01*
X626393Y1704946D01*
X626032Y1705099D01*
X625722Y1705329D01*
X625515Y1705559D01*
X625360Y1705866D01*
Y1706134D01*
X625463Y1706441D01*
X625670Y1706671D01*
G01X628460Y1709862D02*
X625360D01*
Y1711318D01*
G01X626858Y1710782D02*
Y1709862D01*
G01X628460Y1716081D02*
Y1714547D01*
X625360D01*
Y1716081D01*
G01X626858Y1715467D02*
Y1714547D01*
G01X625618Y1725606D02*
X625463Y1725376D01*
X625360Y1725108D01*
Y1724801D01*
X625515Y1724456D01*
X625773Y1724188D01*
X626083Y1723996D01*
X626600Y1723843D01*
X627065Y1723805D01*
X627530Y1723881D01*
X627840Y1723996D01*
X628150Y1724226D01*
X628357Y1724495D01*
X628460Y1724763D01*
Y1725031D01*
X628357Y1725300D01*
X628202Y1725530D01*
X627995Y1725721D01*
G01X626807Y1729795D02*
X626652Y1729948D01*
X626393Y1730063D01*
X626032Y1730140D01*
X625722Y1730063D01*
X625515Y1729910D01*
X625360Y1729641D01*
Y1728606D01*
X628460D01*
Y1729871D01*
X628253Y1730140D01*
X627943Y1730293D01*
X627582Y1730370D01*
X627220Y1730293D01*
X626910Y1730063D01*
X626807Y1729795D01*
Y1728606D01*
G01X628460Y1719196D02*
X625360D01*
Y1719962D01*
X625515Y1720269D01*
X625722Y1720499D01*
X626032Y1720691D01*
X626393Y1720844D01*
X626910Y1720882D01*
X627427Y1720844D01*
X627788Y1720691D01*
X628098Y1720499D01*
X628305Y1720269D01*
X628460Y1719962D01*
Y1719196D01*
G01X766780Y71929D02*
X641200D01*
G01X644756Y125947D02*
Y139595D01*
G01X633460Y141543D02*
Y147743D01*
G01D02*
X636660D01*
G01D02*
Y141543D01*
G01D02*
X633460D01*
G01X644631Y148451D02*
Y154651D01*
G01X647831D02*
Y148451D01*
G01D02*
X644631D01*
G01X643901Y154651D02*
Y148451D01*
G01D02*
X640701D01*
G01D02*
Y154651D01*
G01X650914Y164453D02*
X644714D01*
G01D02*
Y167653D01*
G01Y163462D02*
X650914D01*
G01Y160262D02*
X644714D01*
G01D02*
Y163462D01*
G01X644631Y154651D02*
X647831D01*
G01X640701D02*
X643901D01*
G01X644766Y175801D02*
X650966D01*
G01Y172601D02*
X644766D01*
G01D02*
Y175801D01*
G01X644714Y167653D02*
X650914D01*
G01X644714Y171653D02*
X650914D01*
G01Y168453D02*
X644714D01*
G01D02*
Y171653D01*
G01X650821Y183262D02*
X644621D01*
G01D02*
Y186462D01*
G01D02*
X650821D01*
G01X648476Y198895D02*
X643876D01*
G01D02*
Y209095D01*
G01D02*
X648476D01*
G01X641919Y244117D02*
Y213113D01*
X656719D01*
Y244117D01*
X641919D01*
G01X639209Y232575D02*
Y229375D01*
G01Y228575D02*
Y225375D01*
G01X642383Y246000D02*
Y249100D01*
X643342D01*
X643648Y248945D01*
X643840Y248738D01*
X643917Y248325D01*
X643840Y247912D01*
X643610Y247653D01*
X643342Y247498D01*
X642383D01*
G01X643342D02*
X643917Y246000D01*
G01X645407Y246620D02*
X645637Y246258D01*
X645943Y246052D01*
X646288Y246000D01*
X646595Y246052D01*
X646902Y246310D01*
X647093Y246620D01*
X647132Y246930D01*
X647055Y247292D01*
X646787Y247550D01*
X646518Y247653D01*
X646173D01*
G01X646518D02*
X646748Y247808D01*
X646940Y248067D01*
X647017Y248377D01*
X646940Y248687D01*
X646748Y248945D01*
X646403Y249100D01*
X646058Y249048D01*
X645713Y248842D01*
G01X648622Y247292D02*
X648890Y247653D01*
X649120Y247860D01*
X649427Y247963D01*
X649695Y247860D01*
X649887Y247653D01*
X650040Y247343D01*
X650078Y246982D01*
X650040Y246672D01*
X649887Y246362D01*
X649657Y246103D01*
X649388Y246000D01*
X649082Y246103D01*
X648813Y246413D01*
X648660Y246878D01*
X648622Y247395D01*
X648698Y248067D01*
X648813Y248428D01*
X649005Y248790D01*
X649273Y249048D01*
X649542Y249100D01*
X649810Y248997D01*
X650002Y248738D01*
G01X651607Y246620D02*
X651837Y246258D01*
X652143Y246052D01*
X652488Y246000D01*
X652795Y246052D01*
X653102Y246310D01*
X653293Y246620D01*
X653332Y246930D01*
X653255Y247292D01*
X652987Y247550D01*
X652718Y247653D01*
X652373D01*
G01X652718D02*
X652948Y247808D01*
X653140Y248067D01*
X653217Y248377D01*
X653140Y248687D01*
X652948Y248945D01*
X652603Y249100D01*
X652258Y249048D01*
X651913Y248842D01*
G01X656010Y246000D02*
Y249100D01*
X654592Y246878D01*
X656508D01*
G01X645292Y304061D02*
Y295399D01*
G01D02*
X634798D01*
G01D02*
Y304061D01*
G01X653260Y305489D02*
X647060D01*
G01D02*
Y308689D01*
G01D02*
X653260D01*
G01X635595Y305297D02*
X635288Y305349D01*
X635020Y305555D01*
X634790Y305865D01*
X634637Y306227D01*
X634560Y306640D01*
Y307054D01*
X634637Y307467D01*
X634790Y307829D01*
X635020Y308139D01*
X635288Y308345D01*
X635595Y308397D01*
X635902Y308345D01*
X636170Y308139D01*
X636400Y307829D01*
X636553Y307467D01*
X636630Y307054D01*
Y306640D01*
X636553Y306227D01*
X636400Y305865D01*
X636170Y305555D01*
X635902Y305349D01*
X635595Y305297D01*
G01X635902Y306124D02*
X636362Y305297D01*
G01X639155D02*
Y308397D01*
X637737Y306175D01*
X639653D01*
G01X634798Y304061D02*
X638145D01*
G01D02*
X640045Y301861D01*
G01D02*
X641945Y304061D01*
G01D02*
X645292D01*
G01X646877Y361853D02*
X649099D01*
X649564Y362006D01*
X649874Y362313D01*
X649977Y362696D01*
X649874Y363079D01*
X649564Y363386D01*
X649099Y363539D01*
X646877D01*
G01X649357Y364953D02*
X649719Y365183D01*
X649925Y365489D01*
X649977Y365834D01*
X649925Y366141D01*
X649667Y366448D01*
X649357Y366639D01*
X649047Y366678D01*
X648685Y366601D01*
X648427Y366333D01*
X648324Y366064D01*
Y365719D01*
G01Y366064D02*
X648169Y366294D01*
X647910Y366486D01*
X647600Y366563D01*
X647290Y366486D01*
X647032Y366294D01*
X646877Y365949D01*
X646929Y365604D01*
X647135Y365259D01*
G01X646877Y368896D02*
X646980Y368589D01*
X647239Y368359D01*
X647549Y368206D01*
X647962Y368091D01*
X648427Y368053D01*
X648892Y368091D01*
X649305Y368206D01*
X649615Y368359D01*
X649874Y368589D01*
X649977Y368896D01*
X649874Y369203D01*
X649615Y369433D01*
X649305Y369586D01*
X648892Y369701D01*
X648427Y369739D01*
X647962Y369701D01*
X647549Y369586D01*
X647239Y369433D01*
X646980Y369203D01*
X646877Y368896D01*
G01X651100Y374900D02*
X647900D01*
G01Y381100D02*
X651100D01*
G01X647900Y374900D02*
Y381100D01*
G01X647180Y399980D02*
X640980D01*
G01D02*
Y403180D01*
G01D02*
X647180D01*
G01D02*
Y399980D01*
G01X647124Y403849D02*
X640924D01*
G01D02*
Y407049D01*
G01X647124D02*
Y403849D01*
G01X640924Y407049D02*
X647124D01*
G01X644100Y417400D02*
X640900D01*
G01X644100Y423600D02*
Y417400D01*
G01X640900D02*
Y423600D01*
G01X645400Y416900D02*
Y420100D01*
G01X651600Y416900D02*
X645400D01*
G01X636400Y413900D02*
Y420100D01*
G01X639600Y413900D02*
X636400D01*
G01X639600Y420100D02*
Y413900D01*
G01X633747Y423331D02*
Y414669D01*
G01X639600Y420900D02*
X636400D01*
G01X639600Y427100D02*
Y420900D01*
G01X636400Y427100D02*
X639600D01*
G01X636400Y420900D02*
Y427100D01*
G01X647600Y432262D02*
X641400D01*
G01D02*
Y435462D01*
G01X647600D02*
Y432262D01*
G01X640900Y423600D02*
X644100D01*
G01X645400Y424100D02*
X651600D01*
G01X645400Y420900D02*
Y424100D01*
G01X651600Y420900D02*
X645400D01*
G01Y420100D02*
X651600D01*
G01X636400D02*
X639600D01*
G01X647600Y448262D02*
X641400D01*
G01D02*
Y451462D01*
G01X647600D02*
Y448262D01*
G01X641400Y435462D02*
X647600D01*
G01Y436262D02*
X641400D01*
G01D02*
Y439462D01*
G01D02*
X647600D01*
G01D02*
Y436262D01*
G01Y440762D02*
X641400D01*
G01D02*
Y443962D01*
G01D02*
X647600D01*
G01D02*
Y440762D01*
G01X634103Y439481D02*
Y436281D01*
G01X634759Y463041D02*
Y459841D01*
G01X647600Y452262D02*
X641400D01*
G01D02*
Y455462D01*
G01D02*
X647600D01*
G01D02*
Y452262D01*
G01X641400Y451462D02*
X647600D01*
G01X647724Y460253D02*
X641524D01*
G01D02*
Y463453D01*
G01D02*
X647724D01*
G01D02*
Y460253D01*
G01X647611Y456146D02*
X641411D01*
G01D02*
Y459346D01*
G01D02*
X647611D01*
G01D02*
Y456146D01*
G01X634509Y470456D02*
Y467256D01*
G01X634521Y475620D02*
Y472420D01*
G01X641561Y475505D02*
X647761D01*
G01D02*
Y472305D01*
G01D02*
X641561D01*
G01D02*
Y475505D01*
G01X647741Y468263D02*
X641541D01*
G01D02*
Y471463D01*
G01D02*
X647741D01*
G01D02*
Y468263D01*
G01X647600Y489600D02*
Y486400D01*
G01X641400Y489600D02*
X647600D01*
G01X641400Y486400D02*
Y489600D01*
G01X647600Y486400D02*
X641400D01*
G01X635844Y512138D02*
Y505938D01*
G01X637997Y505707D02*
Y514369D01*
G01X648491Y505707D02*
X637997D01*
G01X645400Y521100D02*
X651600D01*
G01X645400Y517900D02*
Y521100D01*
G01X651600Y517900D02*
X645400D01*
G01X635350Y516972D02*
X635043Y517024D01*
X634775Y517230D01*
X634545Y517540D01*
X634392Y517902D01*
X634315Y518315D01*
Y518729D01*
X634392Y519142D01*
X634545Y519504D01*
X634775Y519814D01*
X635043Y520020D01*
X635350Y520072D01*
X635657Y520020D01*
X635925Y519814D01*
X636155Y519504D01*
X636308Y519142D01*
X636385Y518729D01*
Y518315D01*
X636308Y517902D01*
X636155Y517540D01*
X635925Y517230D01*
X635657Y517024D01*
X635350Y516972D01*
G01X635657Y517799D02*
X636117Y516972D01*
G01X638450D02*
Y520072D01*
X637990Y519452D01*
G01Y516972D02*
X638910D01*
G01X645144Y514369D02*
X648491D01*
G01X643244Y512169D02*
X645144Y514369D01*
G01X641344D02*
X643244Y512169D01*
G01X637997Y514369D02*
X641344D01*
G01X641573Y655962D02*
Y659062D01*
G01X643183D02*
Y655962D01*
G01Y657512D02*
X641573D01*
G01X645478Y655962D02*
X645746Y656014D01*
X646053Y656169D01*
X646245Y656427D01*
X646321Y656789D01*
X646245Y657150D01*
X646015Y657460D01*
X645670Y657615D01*
X645286D01*
X645056Y657719D01*
X644865Y657977D01*
X644788Y658339D01*
X644903Y658700D01*
X645171Y658959D01*
X645478Y659062D01*
X645785Y658959D01*
X646053Y658700D01*
X646168Y658339D01*
X646091Y657977D01*
X645900Y657719D01*
X645670Y657615D01*
X645286D01*
X644941Y657460D01*
X644711Y657150D01*
X644635Y656789D01*
X644711Y656427D01*
X644903Y656169D01*
X645210Y656014D01*
X645478Y655962D01*
G01X647926Y656324D02*
X648195Y656065D01*
X648501Y655962D01*
X648808Y656065D01*
X649076Y656375D01*
X649268Y656840D01*
X649345Y657305D01*
Y657874D01*
X649268Y658339D01*
X649076Y658752D01*
X648846Y658959D01*
X648578Y659062D01*
X648271Y658959D01*
X648041Y658752D01*
X647888Y658442D01*
X647811Y658029D01*
X647888Y657667D01*
X648080Y657305D01*
X648310Y657099D01*
X648578Y657047D01*
X648885Y657150D01*
X649115Y657409D01*
X649345Y657874D01*
G01X642630Y687245D02*
Y777500D01*
G01X668220Y687245D02*
X642630D01*
G01X668220Y720710D02*
X642630D01*
G01Y1002500D02*
Y1025000D01*
G01Y1252000D02*
Y1325041D01*
G01X668220Y1291576D02*
X642630D01*
G01Y1325041D02*
X668220D01*
G01X647836Y1358037D02*
Y1351837D01*
G01X644636Y1358037D02*
X647836D01*
G01X644636Y1351837D02*
Y1358037D01*
G01X647836Y1351837D02*
X644636D01*
G01X636836Y1358037D02*
X640036D01*
G01X636836Y1351837D02*
Y1358037D01*
G01X640036Y1351837D02*
X636836D01*
G01X640036Y1358037D02*
Y1351837D01*
G01X640836Y1358037D02*
X644036D01*
G01X640836Y1351837D02*
Y1358037D01*
G01X644036Y1351837D02*
X640836D01*
G01X644036Y1358037D02*
Y1351837D01*
G01X645695Y1360957D02*
Y1357957D01*
G01X650172Y1360910D02*
X650012Y1361202D01*
X649798Y1361368D01*
X649558Y1361410D01*
X649345Y1361368D01*
X649132Y1361160D01*
X648998Y1360910D01*
X648972Y1360660D01*
X649025Y1360368D01*
X649212Y1360160D01*
X649398Y1360077D01*
X649638D01*
G01X649398D02*
X649238Y1359952D01*
X649105Y1359743D01*
X649052Y1359493D01*
X649105Y1359243D01*
X649238Y1359035D01*
X649478Y1358910D01*
X649718Y1358952D01*
X649958Y1359118D01*
G01X647385Y1358910D02*
X647598Y1358993D01*
X647758Y1359202D01*
X647865Y1359452D01*
X647945Y1359785D01*
X647972Y1360160D01*
X647945Y1360535D01*
X647865Y1360868D01*
X647758Y1361118D01*
X647598Y1361327D01*
X647385Y1361410D01*
X647172Y1361327D01*
X647012Y1361118D01*
X646905Y1360868D01*
X646825Y1360535D01*
X646798Y1360160D01*
X646825Y1359785D01*
X646905Y1359452D01*
X647012Y1359202D01*
X647172Y1358993D01*
X647385Y1358910D01*
G01X648538Y1362414D02*
X646632D01*
G01X637895Y1360907D02*
Y1359407D01*
G01X645163Y1385297D02*
X641963D01*
G01X645163Y1391497D02*
Y1385297D01*
G01X641963D02*
Y1391497D01*
G01X649045Y1385321D02*
X645845D01*
G01D02*
Y1391521D01*
G01X635695Y1391557D02*
Y1385357D01*
G01X646632Y1382100D02*
X648538D01*
G01X639395Y1385107D02*
Y1383607D01*
G01X641963Y1391497D02*
X645163D01*
G01X645845Y1391521D02*
X649045D01*
G01X636600Y1399900D02*
X633400D01*
G01X636600Y1406100D02*
Y1399900D01*
G01X633400D02*
Y1406100D01*
G01D02*
X636600D01*
G01X640645Y1431302D02*
X640270Y1431675D01*
X639645Y1431955D01*
X638770Y1432142D01*
X638020Y1431955D01*
X637520Y1431582D01*
X637145Y1430928D01*
Y1428408D01*
X644645D01*
Y1431488D01*
X644145Y1432142D01*
X643395Y1432515D01*
X642520Y1432702D01*
X641645Y1432515D01*
X640895Y1431955D01*
X640645Y1431302D01*
Y1428408D01*
G01X644645Y1438055D02*
X637145D01*
X638645Y1436935D01*
G01X644645D02*
Y1439175D01*
G01Y1445555D02*
X637145D01*
X638645Y1444435D01*
G01X644645D02*
Y1446675D01*
G01X633602Y1424759D02*
Y1450259D01*
G01Y1424759D02*
X636242D01*
G01X635433Y1736118D02*
Y1646023D01*
G01X636941Y1661369D02*
X656627D01*
G01X636941Y1675769D02*
Y1661369D01*
G01X656627Y1675769D02*
X636941D01*
G01X636717Y1695545D02*
Y1698945D01*
G01D02*
X638717Y1700945D01*
G01D02*
X636717Y1702945D01*
G01X648717Y1695545D02*
X636717D01*
G01X647300Y1715538D02*
Y1718738D01*
G01X653500Y1715538D02*
X647300D01*
G01X646500D02*
X640300D01*
G01D02*
Y1718738D01*
G01X646500D02*
Y1715538D01*
G01X636717Y1702945D02*
Y1706345D01*
G01D02*
X648717D01*
G01X647300Y1726400D02*
Y1729600D01*
G01X653500Y1726400D02*
X647300D01*
G01Y1729600D02*
X653500D01*
G01X647300Y1718738D02*
X653500D01*
G01X639394Y1716870D02*
X636194D01*
G01D02*
Y1723070D01*
G01D02*
X639394D01*
G01D02*
Y1716870D01*
G01X646500Y1726400D02*
X640300D01*
G01D02*
Y1729600D01*
G01X646500D02*
Y1726400D01*
G01X640300Y1729600D02*
X646500D01*
G01X640300Y1723738D02*
X646500D01*
G01X640300Y1720538D02*
Y1723738D01*
G01X646500Y1720538D02*
X640300D01*
G01X646500Y1723738D02*
Y1720538D01*
G01X640300Y1718738D02*
X646500D01*
G01X647300Y1720538D02*
Y1723738D01*
G01X653500Y1720538D02*
X647300D01*
G01Y1723738D02*
X653500D01*
G01X640300Y1734600D02*
X646500D01*
G01X640300Y1731400D02*
Y1734600D01*
G01X646500Y1731400D02*
X640300D01*
G01X646500Y1734600D02*
Y1731400D01*
G01X647300D02*
Y1734600D01*
G01X653500Y1731400D02*
X647300D01*
G01Y1734600D02*
X653500D01*
G01X652221Y82662D02*
Y88862D01*
G01D02*
X655421D01*
G01D02*
Y82662D01*
G01D02*
X652221D01*
G01X658074Y149554D02*
X658746Y149477D01*
X659314Y149362D01*
X659831Y149209D01*
X660399Y149017D01*
X661174Y148710D01*
Y150244D01*
G01X658074Y145917D02*
X661174D01*
X658952Y147335D01*
Y145419D01*
G01X650914Y167653D02*
Y164453D01*
G01Y163462D02*
Y160262D01*
G01X661372Y159914D02*
X661733Y159646D01*
X661940Y159416D01*
X662043Y159109D01*
X661940Y158841D01*
X661733Y158649D01*
X661423Y158496D01*
X661062Y158458D01*
X660752Y158496D01*
X660442Y158649D01*
X660183Y158879D01*
X660080Y159148D01*
X660183Y159454D01*
X660493Y159723D01*
X660958Y159876D01*
X661475Y159914D01*
X662147Y159838D01*
X662508Y159723D01*
X662870Y159531D01*
X663128Y159263D01*
X663180Y158994D01*
X663077Y158726D01*
X662818Y158534D01*
G01X660080Y156086D02*
X660132Y155818D01*
X660287Y155511D01*
X660545Y155319D01*
X660907Y155243D01*
X661268Y155319D01*
X661578Y155549D01*
X661733Y155894D01*
Y156278D01*
X661837Y156508D01*
X662095Y156699D01*
X662457Y156776D01*
X662818Y156661D01*
X663077Y156393D01*
X663180Y156086D01*
X663077Y155779D01*
X662818Y155511D01*
X662457Y155396D01*
X662095Y155473D01*
X661837Y155664D01*
X661733Y155894D01*
Y156278D01*
X661578Y156623D01*
X661268Y156853D01*
X660907Y156929D01*
X660545Y156853D01*
X660287Y156661D01*
X660132Y156354D01*
X660080Y156086D01*
G01X660517Y168944D02*
X660259Y168714D01*
X660104Y168446D01*
X660052Y168101D01*
X660155Y167756D01*
X660362Y167488D01*
X660724Y167296D01*
X661137Y167258D01*
X661550Y167334D01*
X661809Y167526D01*
X662015Y167794D01*
X662067Y168063D01*
X662015Y168331D01*
X661809Y168676D01*
X663152Y168561D01*
Y167526D01*
G01X660052Y165001D02*
X660104Y164733D01*
X660259Y164426D01*
X660517Y164234D01*
X660879Y164158D01*
X661240Y164234D01*
X661550Y164464D01*
X661705Y164809D01*
Y165193D01*
X661809Y165423D01*
X662067Y165614D01*
X662429Y165691D01*
X662790Y165576D01*
X663049Y165308D01*
X663152Y165001D01*
X663049Y164694D01*
X662790Y164426D01*
X662429Y164311D01*
X662067Y164388D01*
X661809Y164579D01*
X661705Y164809D01*
Y165193D01*
X661550Y165538D01*
X661240Y165768D01*
X660879Y165844D01*
X660517Y165768D01*
X660259Y165576D01*
X660104Y165269D01*
X660052Y165001D01*
G01X650966Y175801D02*
Y172601D01*
G01X650914Y171653D02*
Y168453D01*
G01X650821Y186462D02*
Y183262D01*
G01X653912Y209090D02*
Y198890D01*
G01D02*
X649312D01*
G01D02*
Y209090D01*
G01D02*
X653912D01*
G01X648476Y209095D02*
Y198895D01*
G01X662635Y221397D02*
X662945Y221167D01*
X663100Y220899D01*
X663152Y220592D01*
X663049Y220209D01*
X662790Y219941D01*
X662480Y219864D01*
X662170Y219902D01*
X661912Y220056D01*
X661395Y220822D01*
X661034Y221167D01*
X660517Y221397D01*
X660052Y221474D01*
Y219864D01*
G01X653260Y308689D02*
Y305489D01*
G01X663123Y361661D02*
Y364861D01*
G01X669323Y361661D02*
X663123D01*
G01Y364861D02*
X669323D01*
G01X652500Y374000D02*
X655000Y375500D01*
G01X652500Y367400D02*
Y374000D01*
G01X665500Y367400D02*
X652500D01*
G01X651100Y381100D02*
Y374900D01*
G01X657900Y388400D02*
Y391600D01*
G01X664100Y388400D02*
X657900D01*
G01X650900D02*
Y391600D01*
G01X657100Y388400D02*
X650900D01*
G01X657100Y391600D02*
Y388400D01*
G01X652500Y377000D02*
Y383600D01*
G01X655000Y375500D02*
X652500Y377000D01*
G01Y383600D02*
X665500D01*
G01X657900Y391600D02*
X664100D01*
G01X650900D02*
X657100D01*
G01X651600Y420100D02*
Y416900D01*
G01X661100Y428262D02*
X654900D01*
G01D02*
Y431462D01*
G01D02*
X661100D01*
G01D02*
Y428262D01*
G01Y424262D02*
X654900D01*
G01D02*
Y427462D01*
G01D02*
X661100D01*
G01D02*
Y424262D01*
G01Y432262D02*
X654900D01*
G01D02*
Y435462D01*
G01X661100D02*
Y432262D01*
G01X651600Y424100D02*
Y420900D01*
G01X654900Y435462D02*
X661100D01*
G01Y452262D02*
X654900D01*
G01D02*
Y455462D01*
G01D02*
X661100D01*
G01D02*
Y452262D01*
G01X654840Y463418D02*
X661040D01*
G01D02*
Y460218D01*
G01D02*
X654840D01*
G01D02*
Y463418D01*
G01X654823Y459355D02*
X661023D01*
G01D02*
Y456155D01*
G01D02*
X654823D01*
G01D02*
Y459355D01*
G01X661100Y468262D02*
X654900D01*
G01D02*
Y471462D01*
G01D02*
X661100D01*
G01D02*
Y468262D01*
G01Y472262D02*
X654900D01*
G01D02*
Y475462D01*
G01D02*
X661100D01*
G01D02*
Y472262D01*
G01X659855Y488541D02*
X666055D01*
G01Y485341D02*
X659855D01*
G01D02*
Y488541D01*
G01X648965Y485341D02*
Y488541D01*
G01X655165Y485341D02*
X648965D01*
G01X655165Y488541D02*
Y485341D01*
G01X648965Y488541D02*
X655165D01*
G01X659717Y496726D02*
X665917D01*
G01Y493526D02*
X659717D01*
G01D02*
Y496726D01*
G01X648491Y514369D02*
Y505707D01*
G01X654400Y522600D02*
X657600D01*
G01X654400Y516400D02*
Y522600D01*
G01X657600Y516400D02*
X654400D01*
G01X657600Y522600D02*
Y516400D01*
G01X651600Y521100D02*
Y517900D01*
G01X654400Y514600D02*
X657600D01*
G01X654400Y508400D02*
Y514600D01*
G01X657600Y508400D02*
X654400D01*
G01X657600Y514600D02*
Y508400D01*
G01X676118Y513900D02*
X660882D01*
G01D02*
Y526100D01*
G01X648923Y528471D02*
Y526249D01*
X649076Y525784D01*
X649383Y525474D01*
X649766Y525371D01*
X650149Y525474D01*
X650456Y525784D01*
X650609Y526249D01*
Y528471D01*
G01X652866Y525371D02*
Y528471D01*
X652406Y527851D01*
G01Y525371D02*
X653326D01*
G01X655966Y528471D02*
X655659Y528368D01*
X655429Y528109D01*
X655276Y527799D01*
X655161Y527386D01*
X655123Y526921D01*
X655161Y526456D01*
X655276Y526043D01*
X655429Y525733D01*
X655659Y525474D01*
X655966Y525371D01*
X656273Y525474D01*
X656503Y525733D01*
X656656Y526043D01*
X656771Y526456D01*
X656809Y526921D01*
X656771Y527386D01*
X656656Y527799D01*
X656503Y528109D01*
X656273Y528368D01*
X655966Y528471D01*
G01X659066D02*
X658759Y528368D01*
X658529Y528109D01*
X658376Y527799D01*
X658261Y527386D01*
X658223Y526921D01*
X658261Y526456D01*
X658376Y526043D01*
X658529Y525733D01*
X658759Y525474D01*
X659066Y525371D01*
X659373Y525474D01*
X659603Y525733D01*
X659756Y526043D01*
X659871Y526456D01*
X659909Y526921D01*
X659871Y527386D01*
X659756Y527799D01*
X659603Y528109D01*
X659373Y528368D01*
X659066Y528471D01*
G01X660882Y526100D02*
X676118D01*
G01X660708Y683096D02*
X660900Y682786D01*
X661130Y682579D01*
X661398Y682476D01*
X661705Y682579D01*
X661935Y682786D01*
X662165Y683096D01*
X662242Y683509D01*
Y685576D01*
G01X664575Y682476D02*
Y685576D01*
X664115Y684956D01*
G01Y682476D02*
X665035D01*
G01X667675Y685576D02*
X667368Y685473D01*
X667138Y685214D01*
X666985Y684904D01*
X666870Y684491D01*
X666832Y684026D01*
X666870Y683561D01*
X666985Y683148D01*
X667138Y682838D01*
X667368Y682579D01*
X667675Y682476D01*
X667982Y682579D01*
X668212Y682838D01*
X668365Y683148D01*
X668480Y683561D01*
X668518Y684026D01*
X668480Y684491D01*
X668365Y684904D01*
X668212Y685214D01*
X667982Y685473D01*
X667675Y685576D01*
G01X670047Y685059D02*
X670277Y685369D01*
X670545Y685524D01*
X670852Y685576D01*
X671235Y685473D01*
X671503Y685214D01*
X671580Y684904D01*
X671542Y684594D01*
X671388Y684336D01*
X670622Y683819D01*
X670277Y683458D01*
X670047Y682941D01*
X669970Y682476D01*
X671580D01*
G01X657972Y1330402D02*
Y1327302D01*
G01X657090Y1330402D02*
X658854D01*
G01X660305Y1327302D02*
Y1330402D01*
X661225D01*
X661532Y1330247D01*
X661762Y1329885D01*
X661839Y1329472D01*
X661762Y1329059D01*
X661570Y1328749D01*
X661225Y1328594D01*
X660305D01*
G01X664172Y1327302D02*
Y1330402D01*
X663712Y1329782D01*
G01Y1327302D02*
X664632D01*
G01X666429Y1327922D02*
X666659Y1327560D01*
X666965Y1327354D01*
X667310Y1327302D01*
X667617Y1327354D01*
X667924Y1327612D01*
X668115Y1327922D01*
X668154Y1328232D01*
X668077Y1328594D01*
X667809Y1328852D01*
X667540Y1328955D01*
X667195D01*
G01X667540D02*
X667770Y1329110D01*
X667962Y1329369D01*
X668039Y1329679D01*
X667962Y1329989D01*
X667770Y1330247D01*
X667425Y1330402D01*
X667080Y1330350D01*
X666735Y1330144D01*
G01X658172Y1334952D02*
Y1331852D01*
G01X657290Y1334952D02*
X659054D01*
G01X660505Y1331852D02*
Y1334952D01*
X661425D01*
X661732Y1334797D01*
X661962Y1334435D01*
X662039Y1334022D01*
X661962Y1333609D01*
X661770Y1333299D01*
X661425Y1333144D01*
X660505D01*
G01X664372Y1331852D02*
Y1334952D01*
X663912Y1334332D01*
G01Y1331852D02*
X664832D01*
G01X667472D02*
X667740Y1331904D01*
X668047Y1332059D01*
X668239Y1332317D01*
X668315Y1332679D01*
X668239Y1333040D01*
X668009Y1333350D01*
X667664Y1333505D01*
X667280D01*
X667050Y1333609D01*
X666859Y1333867D01*
X666782Y1334229D01*
X666897Y1334590D01*
X667165Y1334849D01*
X667472Y1334952D01*
X667779Y1334849D01*
X668047Y1334590D01*
X668162Y1334229D01*
X668085Y1333867D01*
X667894Y1333609D01*
X667664Y1333505D01*
X667280D01*
X666935Y1333350D01*
X666705Y1333040D01*
X666629Y1332679D01*
X666705Y1332317D01*
X666897Y1332059D01*
X667204Y1331904D01*
X667472Y1331852D01*
G01X648436Y1358037D02*
X651636D01*
G01X648436Y1351837D02*
Y1358037D01*
G01X651636Y1351837D02*
X648436D01*
G01X651636Y1358037D02*
Y1351837D01*
G01X652236Y1358037D02*
X655436D01*
G01X652236Y1351837D02*
Y1358037D01*
G01X655436Y1351837D02*
X652236D01*
G01X655436Y1358037D02*
Y1351837D01*
G01X656236Y1358037D02*
X659436D01*
G01X656236Y1351837D02*
Y1358037D01*
G01X659436Y1351837D02*
X656236D01*
G01X659436Y1358037D02*
Y1351837D01*
G01X654136Y1369599D02*
Y1372799D01*
G01X660336Y1369599D02*
X654136D01*
G01X660336Y1372799D02*
Y1369599D01*
G01X654136Y1372799D02*
X660336D01*
G01X660322Y1364994D02*
Y1361794D01*
G01X654122Y1364994D02*
X660322D01*
G01X654122Y1361794D02*
Y1364994D01*
G01X660322Y1361794D02*
X654122D01*
G01X654154Y1368883D02*
X660354D01*
G01D02*
Y1365683D01*
G01X654154D02*
Y1368883D01*
G01X660354Y1365683D02*
X654154D01*
G01X650352Y1365714D02*
X650060Y1365554D01*
X649894Y1365340D01*
X649852Y1365100D01*
X649894Y1364887D01*
X650102Y1364674D01*
X650352Y1364540D01*
X650602Y1364514D01*
X650894Y1364567D01*
X651102Y1364754D01*
X651185Y1364940D01*
Y1365180D01*
G01Y1364940D02*
X651310Y1364780D01*
X651519Y1364647D01*
X651769Y1364594D01*
X652019Y1364647D01*
X652227Y1364780D01*
X652352Y1365020D01*
X652310Y1365260D01*
X652144Y1365500D01*
G01X649852Y1362927D02*
X652352D01*
X651852Y1363247D01*
G01X649852D02*
Y1362607D01*
G01X651445Y1371557D02*
X649945D01*
G01X648538Y1364320D02*
Y1362414D01*
G01X649045Y1391521D02*
Y1385321D01*
G01X654068Y1377331D02*
Y1380531D01*
G01X660268Y1377331D02*
X654068D01*
G01X660268Y1380531D02*
Y1377331D01*
G01X654068Y1380531D02*
X660268D01*
G01X654102Y1373461D02*
Y1376661D01*
G01X660302Y1373461D02*
X654102D01*
G01X660302Y1376661D02*
Y1373461D01*
G01X654102Y1376661D02*
X660302D01*
G01X657302Y1383823D02*
X654102D01*
G01X657302Y1390023D02*
Y1383823D01*
G01X654102D02*
Y1390023D01*
G01X661159Y1389965D02*
Y1383765D01*
G01D02*
X657959D01*
G01D02*
Y1389965D01*
G01X653477Y1383790D02*
X650277D01*
G01X653477Y1389990D02*
Y1383790D01*
G01X650277D02*
Y1389990D01*
G01X652583Y1380835D02*
Y1383335D01*
X651596Y1381543D01*
X652930D01*
G01X654463Y1383335D02*
X654250Y1383252D01*
X654090Y1383043D01*
X653983Y1382793D01*
X653903Y1382460D01*
X653876Y1382085D01*
X653903Y1381710D01*
X653983Y1381377D01*
X654090Y1381127D01*
X654250Y1380918D01*
X654463Y1380835D01*
X654676Y1380918D01*
X654836Y1381127D01*
X654943Y1381377D01*
X655023Y1381710D01*
X655050Y1382085D01*
X655023Y1382460D01*
X654943Y1382793D01*
X654836Y1383043D01*
X654676Y1383252D01*
X654463Y1383335D01*
G01X649995Y1379357D02*
X652995D01*
G01X648538Y1382100D02*
Y1380194D01*
G01X654102Y1390023D02*
X657302D01*
G01X657959Y1389965D02*
X661159D01*
G01X650277Y1389990D02*
X653477D01*
G01X648602Y1411259D02*
Y1423837D01*
G01Y1450259D02*
Y1427459D01*
G01X659432Y1507451D02*
X652200D01*
G01X659432Y1542491D02*
Y1507451D01*
G01X652300Y1542491D02*
X659432D01*
G01X657098Y1670385D02*
X659320D01*
X659785Y1670538D01*
X660095Y1670845D01*
X660198Y1671228D01*
X660095Y1671611D01*
X659785Y1671918D01*
X659320Y1672071D01*
X657098D01*
G01X657615Y1673600D02*
X657305Y1673830D01*
X657150Y1674098D01*
X657098Y1674405D01*
X657201Y1674788D01*
X657460Y1675056D01*
X657770Y1675133D01*
X658080Y1675095D01*
X658338Y1674941D01*
X658855Y1674175D01*
X659216Y1673830D01*
X659733Y1673600D01*
X660198Y1673523D01*
Y1675133D01*
G01X657098Y1677428D02*
X657201Y1677121D01*
X657460Y1676891D01*
X657770Y1676738D01*
X658183Y1676623D01*
X658648Y1676585D01*
X659113Y1676623D01*
X659526Y1676738D01*
X659836Y1676891D01*
X660095Y1677121D01*
X660198Y1677428D01*
X660095Y1677735D01*
X659836Y1677965D01*
X659526Y1678118D01*
X659113Y1678233D01*
X658648Y1678271D01*
X658183Y1678233D01*
X657770Y1678118D01*
X657460Y1677965D01*
X657201Y1677735D01*
X657098Y1677428D01*
G01X656627Y1664326D02*
X652384Y1668569D01*
G01X656627Y1661369D02*
Y1664326D01*
G01X652384Y1668569D02*
X656627Y1672812D01*
G01X660628Y1661583D02*
X680314D01*
G01X660628Y1675983D02*
Y1661583D01*
G01X657300Y1689000D02*
Y1685800D01*
G01D02*
X651100D01*
G01D02*
Y1689000D01*
G01X656627Y1672812D02*
Y1675769D01*
G01X680314Y1675983D02*
X660628D01*
G01X651200Y1689700D02*
Y1695900D01*
G01D02*
X654400D01*
G01D02*
Y1689700D01*
G01D02*
X651200D01*
G01X657900Y1700000D02*
Y1696800D01*
G01X651700Y1700000D02*
X657900D01*
G01Y1696800D02*
X651700D01*
G01D02*
Y1700000D01*
G01X657900Y1700800D02*
X651700D01*
G01D02*
Y1704000D01*
G01X657900D02*
Y1700800D01*
G01X658400Y1689700D02*
X655200D01*
G01Y1695900D02*
X658400D01*
G01D02*
Y1689700D01*
G01X655200D02*
Y1695900D01*
G01X651100Y1689000D02*
X657300D01*
G01X663000Y1692207D02*
X665222D01*
X665687Y1692360D01*
X665997Y1692667D01*
X666100Y1693050D01*
X665997Y1693433D01*
X665687Y1693740D01*
X665222Y1693893D01*
X663000D01*
G01X666100Y1696150D02*
X663000D01*
X663620Y1695690D01*
G01X666100D02*
Y1696610D01*
G01Y1699173D02*
X665428Y1699250D01*
X664860Y1699365D01*
X664343Y1699518D01*
X663775Y1699710D01*
X663000Y1700017D01*
Y1698483D01*
G01X665635Y1701507D02*
X665893Y1701737D01*
X666048Y1702005D01*
X666100Y1702350D01*
X665997Y1702695D01*
X665790Y1702963D01*
X665428Y1703155D01*
X665015Y1703193D01*
X664602Y1703117D01*
X664343Y1702925D01*
X664137Y1702657D01*
X664085Y1702388D01*
X664137Y1702120D01*
X664343Y1701775D01*
X663000Y1701890D01*
Y1702925D01*
G01X648717Y1706345D02*
Y1695545D01*
G01X653500Y1718738D02*
Y1715538D01*
G01X660900Y1709784D02*
X667100D01*
G01Y1706584D02*
X660900D01*
G01D02*
Y1709784D01*
G01X657900Y1713684D02*
Y1710484D01*
G01X651700Y1713684D02*
X657900D01*
G01Y1710484D02*
X651700D01*
G01D02*
Y1713684D01*
G01X657900Y1706584D02*
X651700D01*
G01Y1709784D02*
X657900D01*
G01D02*
Y1706584D01*
G01X651700D02*
Y1709784D01*
G01X660900Y1713684D02*
X667100D01*
G01Y1710484D02*
X660900D01*
G01D02*
Y1713684D01*
G01X651700Y1704000D02*
X657900D01*
G01X655666Y1715284D02*
Y1723946D01*
G01X666160Y1715284D02*
X655666D01*
G01X653500Y1729600D02*
Y1726400D01*
G01Y1723738D02*
Y1720538D01*
G01X655666Y1725946D02*
Y1734608D01*
G01X666160Y1725946D02*
X655666D01*
G01X662813Y1723946D02*
X666160D01*
G01X660913Y1721746D02*
X662813Y1723946D01*
G01X659013D02*
X660913Y1721746D01*
G01X655666Y1723946D02*
X659013D01*
G01X653500Y1734600D02*
Y1731400D01*
G01X662813Y1734608D02*
X666160D01*
G01X655666D02*
X659013D01*
G01X660913Y1732408D02*
X662813Y1734608D01*
G01X659013D02*
X660913Y1732408D01*
G01X674243Y102585D02*
Y108785D01*
G01X677443D02*
Y102585D01*
G01D02*
X674243D01*
G01Y108785D02*
X677443D01*
G01X669350Y110328D02*
X671850D01*
X671350Y110648D01*
G01X669350D02*
Y110008D01*
G01Y108128D02*
X671850D01*
X671350Y108448D01*
G01X669350D02*
Y107808D01*
G01X674213Y141929D02*
X665485D01*
G01X668438Y148753D02*
Y142224D01*
G01D02*
X673713D01*
G01X665485Y141929D02*
Y148753D01*
G01Y156758D02*
Y164501D01*
G01X668438D02*
Y156758D01*
G01X665963Y160266D02*
X670063D01*
G01D02*
X670163Y160166D01*
G01D02*
Y162666D01*
G01D02*
X665963Y160266D01*
G01D02*
X670063Y157666D01*
G01D02*
Y160266D01*
G01D02*
X678463D01*
G01X675072Y212849D02*
X675197Y213009D01*
X675280Y213196D01*
Y213409D01*
X675155Y213649D01*
X674947Y213836D01*
X674697Y213969D01*
X674280Y214076D01*
X673905Y214103D01*
X673530Y214049D01*
X673280Y213969D01*
X673030Y213809D01*
X672863Y213623D01*
X672780Y213436D01*
Y213249D01*
X672863Y213063D01*
X672988Y212903D01*
X673155Y212769D01*
G01X672780Y211236D02*
X672822Y211449D01*
X672988Y211636D01*
X673238Y211796D01*
X673530Y211903D01*
X673863Y211956D01*
X674197D01*
X674530Y211903D01*
X674822Y211796D01*
X675072Y211636D01*
X675238Y211449D01*
X675280Y211236D01*
X675238Y211023D01*
X675072Y210836D01*
X674822Y210676D01*
X674530Y210569D01*
X674197Y210516D01*
X673863D01*
X673530Y210569D01*
X673238Y210676D01*
X672988Y210836D01*
X672822Y211023D01*
X672780Y211236D01*
G01Y209649D02*
X675280D01*
X672780Y208423D01*
X675280D01*
G01X672780Y207449D02*
X675280D01*
X672780Y206223D01*
X675280D01*
G01X672780Y204103D02*
Y205169D01*
X675280D01*
Y204103D01*
G01X674072Y204529D02*
Y205169D01*
G01X675072Y201849D02*
X675197Y202009D01*
X675280Y202196D01*
Y202409D01*
X675155Y202649D01*
X674947Y202836D01*
X674697Y202969D01*
X674280Y203076D01*
X673905Y203103D01*
X673530Y203049D01*
X673280Y202969D01*
X673030Y202809D01*
X672863Y202623D01*
X672780Y202436D01*
Y202249D01*
X672863Y202063D01*
X672988Y201903D01*
X673155Y201769D01*
G01X675280Y200236D02*
X672780D01*
G01X675280Y200849D02*
Y199623D01*
G01X672780Y198036D02*
X672822Y198249D01*
X672988Y198436D01*
X673238Y198596D01*
X673530Y198703D01*
X673863Y198756D01*
X674197D01*
X674530Y198703D01*
X674822Y198596D01*
X675072Y198436D01*
X675238Y198249D01*
X675280Y198036D01*
X675238Y197823D01*
X675072Y197636D01*
X674822Y197476D01*
X674530Y197369D01*
X674197Y197316D01*
X673863D01*
X673530Y197369D01*
X673238Y197476D01*
X672988Y197636D01*
X672822Y197823D01*
X672780Y198036D01*
G01Y196369D02*
X675280D01*
Y195703D01*
X675155Y195489D01*
X674988Y195356D01*
X674655Y195303D01*
X674322Y195356D01*
X674113Y195516D01*
X673988Y195703D01*
Y196369D01*
G01Y195703D02*
X672780Y195303D01*
G01Y192023D02*
X675280D01*
G01Y191009D02*
X673738Y192023D01*
G01X672780Y190849D02*
X674447Y191569D01*
G01X672780Y188703D02*
Y189769D01*
X675280D01*
Y188703D01*
G01X674072Y189129D02*
Y189769D01*
G01X672780Y186503D02*
Y187569D01*
X675280D01*
Y186503D01*
G01X674072Y186929D02*
Y187569D01*
G01X672780Y185369D02*
X675280D01*
Y184729D01*
X675155Y184516D01*
X674863Y184356D01*
X674530Y184303D01*
X674197Y184356D01*
X673947Y184489D01*
X673822Y184729D01*
Y185369D01*
G01X672780Y182636D02*
X672822Y182849D01*
X672988Y183036D01*
X673238Y183196D01*
X673530Y183303D01*
X673863Y183356D01*
X674197D01*
X674530Y183303D01*
X674822Y183196D01*
X675072Y183036D01*
X675238Y182849D01*
X675280Y182636D01*
X675238Y182423D01*
X675072Y182236D01*
X674822Y182076D01*
X674530Y181969D01*
X674197Y181916D01*
X673863D01*
X673530Y181969D01*
X673238Y182076D01*
X672988Y182236D01*
X672822Y182423D01*
X672780Y182636D01*
G01X675280Y181023D02*
X673488D01*
X673113Y180916D01*
X672863Y180703D01*
X672780Y180436D01*
X672863Y180169D01*
X673113Y179956D01*
X673488Y179849D01*
X675280D01*
G01Y178236D02*
X672780D01*
G01X675280Y178849D02*
Y177623D01*
G01Y174343D02*
Y173329D01*
X672780Y174343D01*
Y173329D01*
G01Y171636D02*
X672822Y171849D01*
X672988Y172036D01*
X673238Y172196D01*
X673530Y172303D01*
X673863Y172356D01*
X674197D01*
X674530Y172303D01*
X674822Y172196D01*
X675072Y172036D01*
X675238Y171849D01*
X675280Y171636D01*
X675238Y171423D01*
X675072Y171236D01*
X674822Y171076D01*
X674530Y170969D01*
X674197Y170916D01*
X673863D01*
X673530Y170969D01*
X673238Y171076D01*
X672988Y171236D01*
X672822Y171423D01*
X672780Y171636D01*
G01Y170049D02*
X675280D01*
X672780Y168823D01*
X675280D01*
G01X672780Y166703D02*
Y167769D01*
X675280D01*
Y166703D01*
G01X674072Y167129D02*
Y167769D01*
G01X678463Y168772D02*
X676213Y170836D01*
G01X665485Y221719D02*
Y228543D01*
G01X668438Y228248D02*
Y221719D01*
G01X680043Y231249D02*
X675043D01*
X679210Y232896D01*
X675043Y234543D01*
X680043D01*
G01X680210Y237996D02*
X680126Y237869D01*
X679960D01*
X679876Y237996D01*
X679960Y238123D01*
X680126D01*
X680210Y237996D01*
G01X675876Y241893D02*
X675376Y242273D01*
X675126Y242716D01*
X675043Y243223D01*
X675210Y243856D01*
X675626Y244299D01*
X676126Y244426D01*
X676626Y244363D01*
X677043Y244109D01*
X677876Y242843D01*
X678460Y242273D01*
X679293Y241893D01*
X680043Y241766D01*
Y244426D01*
G01X679376Y251966D02*
X679793Y252473D01*
X680043Y253043D01*
Y253549D01*
X679793Y254056D01*
X679376Y254436D01*
X678793Y254626D01*
X678210Y254499D01*
X677710Y254183D01*
X677376Y253613D01*
X677210Y252853D01*
X676876Y252409D01*
X676293Y252219D01*
X675710Y252346D01*
X675293Y252663D01*
X675043Y253106D01*
Y253549D01*
X675210Y253993D01*
X675626Y254373D01*
G01X675043Y257129D02*
X680043D01*
Y259663D01*
G01Y263496D02*
X679960Y262989D01*
X679626Y262546D01*
X679126Y262166D01*
X678543Y261913D01*
X677876Y261786D01*
X677210D01*
X676543Y261913D01*
X675960Y262166D01*
X675460Y262546D01*
X675126Y262989D01*
X675043Y263496D01*
X675126Y264003D01*
X675460Y264446D01*
X675960Y264826D01*
X676543Y265079D01*
X677210Y265206D01*
X677876D01*
X678543Y265079D01*
X679126Y264826D01*
X679626Y264446D01*
X679960Y264003D01*
X680043Y263496D01*
G01X675043Y268596D02*
X680043D01*
G01X675043Y267139D02*
Y270053D01*
G01Y278796D02*
X675210Y278289D01*
X675626Y277909D01*
X676126Y277656D01*
X676793Y277466D01*
X677543Y277403D01*
X678293Y277466D01*
X678960Y277656D01*
X679460Y277909D01*
X679876Y278289D01*
X680043Y278796D01*
X679876Y279303D01*
X679460Y279683D01*
X678960Y279936D01*
X678293Y280126D01*
X677543Y280189D01*
X676793Y280126D01*
X676126Y279936D01*
X675626Y279683D01*
X675210Y279303D01*
X675043Y278796D01*
G01X681710Y288679D02*
X680876Y288046D01*
X680043Y287729D01*
X676710D01*
X675876Y288046D01*
X675043Y288679D01*
G01X679376Y292766D02*
X679793Y293273D01*
X680043Y293843D01*
Y294349D01*
X679793Y294856D01*
X679376Y295236D01*
X678793Y295426D01*
X678210Y295299D01*
X677710Y294983D01*
X677376Y294413D01*
X677210Y293653D01*
X676876Y293209D01*
X676293Y293019D01*
X675710Y293146D01*
X675293Y293463D01*
X675043Y293906D01*
Y294349D01*
X675210Y294793D01*
X675626Y295173D01*
G01X680043Y297613D02*
X675043Y299196D01*
X680043Y300779D01*
G01X678293Y300209D02*
Y298183D01*
G01X675043Y304296D02*
X680043D01*
G01X675043Y302839D02*
Y305753D01*
G01X680043Y307813D02*
X675043Y309396D01*
X680043Y310979D01*
G01X678293Y310409D02*
Y308383D01*
G01X680210Y313356D02*
X675043Y315636D01*
G01X680043Y318329D02*
X675043D01*
Y319849D01*
X675293Y320356D01*
X675876Y320736D01*
X676543Y320863D01*
X677210Y320736D01*
X677710Y320419D01*
X677960Y319849D01*
Y318329D01*
G01X675460Y326089D02*
X675210Y325709D01*
X675043Y325266D01*
Y324759D01*
X675293Y324189D01*
X675710Y323746D01*
X676210Y323429D01*
X677043Y323176D01*
X677793Y323113D01*
X678543Y323239D01*
X679043Y323429D01*
X679543Y323809D01*
X679876Y324253D01*
X680043Y324696D01*
Y325139D01*
X679876Y325583D01*
X679626Y325963D01*
X679293Y326279D01*
G01X675043Y329036D02*
Y330556D01*
G01Y329796D02*
X680043D01*
G01Y329036D02*
Y330556D01*
G01X677793Y333946D02*
Y335973D01*
X677210Y335783D01*
X676876Y335466D01*
X676710Y335023D01*
X676793Y334579D01*
X677043Y334199D01*
X677626Y333946D01*
X678126Y333819D01*
X678626D01*
X679126Y333946D01*
X679626Y334263D01*
X679960Y334643D01*
X680043Y335086D01*
X679876Y335529D01*
X679376Y335973D01*
G01X676710Y344146D02*
X680043Y346046D01*
G01X676710D02*
X680043Y344146D01*
G01Y350956D02*
X675043D01*
X678626Y348613D01*
Y351779D01*
G01X681710Y355613D02*
X680876Y356246D01*
X680043Y356563D01*
X676710D01*
X675876Y356246D01*
X675043Y355613D01*
G01X665196Y231123D02*
X665388Y230813D01*
X665618Y230606D01*
X665886Y230503D01*
X666193Y230606D01*
X666423Y230813D01*
X666653Y231123D01*
X666730Y231536D01*
Y233603D01*
G01X668220Y230968D02*
X668450Y230710D01*
X668718Y230555D01*
X669063Y230503D01*
X669408Y230606D01*
X669676Y230813D01*
X669868Y231175D01*
X669906Y231588D01*
X669830Y232001D01*
X669638Y232260D01*
X669370Y232466D01*
X669101Y232518D01*
X668833Y232466D01*
X668488Y232260D01*
X668603Y233603D01*
X669638D01*
G01X671511Y230865D02*
X671780Y230606D01*
X672086Y230503D01*
X672393Y230606D01*
X672661Y230916D01*
X672853Y231381D01*
X672930Y231846D01*
Y232415D01*
X672853Y232880D01*
X672661Y233293D01*
X672431Y233500D01*
X672163Y233603D01*
X671856Y233500D01*
X671626Y233293D01*
X671473Y232983D01*
X671396Y232570D01*
X671473Y232208D01*
X671665Y231846D01*
X671895Y231640D01*
X672163Y231588D01*
X672470Y231691D01*
X672700Y231950D01*
X672930Y232415D01*
G01X665485Y228543D02*
X688226D01*
G01Y228248D02*
X668438D01*
G01X674400Y376462D02*
Y370262D01*
G01D02*
X671200D01*
G01D02*
Y376462D01*
G01X678400Y370262D02*
X675200D01*
G01D02*
Y376462D01*
G01X669323Y364861D02*
Y361661D01*
G01X665500Y383600D02*
Y367400D01*
G01X671200Y376462D02*
X674400D01*
G01X675200D02*
X678400D01*
G01X664100Y391600D02*
Y388400D01*
G01X677100Y397962D02*
Y391762D01*
G01D02*
X673900D01*
G01D02*
Y397962D01*
G01D02*
X677100D01*
G01X681100Y391762D02*
X677900D01*
G01D02*
Y397962D01*
G01D02*
X681100D01*
G01X668548Y402787D02*
Y396587D01*
G01D02*
X665348D01*
G01D02*
Y402787D01*
G01D02*
X668548D01*
G01X665285Y403655D02*
Y409855D01*
G01X668485D02*
Y403655D01*
G01D02*
X665285D01*
G01X670945Y403167D02*
X677145D01*
G01D02*
Y399967D01*
G01D02*
X670945D01*
G01D02*
Y403167D01*
G01X677145Y407088D02*
Y403888D01*
G01D02*
X670945D01*
G01D02*
Y407088D01*
G01Y410920D02*
X677145D01*
G01D02*
Y407720D01*
G01D02*
X670945D01*
G01D02*
Y410920D01*
G01X677100Y416262D02*
X670900D01*
G01D02*
Y419462D01*
G01X677100D02*
Y416262D01*
G01Y411762D02*
X670900D01*
G01D02*
Y414962D01*
G01D02*
X677100D01*
G01D02*
Y411762D01*
G01X665285Y409855D02*
X668485D01*
G01X670945Y407088D02*
X677145D01*
G01X670900Y419462D02*
X677100D01*
G01Y432262D02*
X670900D01*
G01D02*
Y435462D01*
G01X677100D02*
Y432262D01*
G01Y428262D02*
X670900D01*
G01D02*
Y431462D01*
G01D02*
X677100D01*
G01D02*
Y428262D01*
G01Y424262D02*
X670900D01*
G01D02*
Y427462D01*
G01D02*
X677100D01*
G01D02*
Y424262D01*
G01Y420262D02*
X670900D01*
G01D02*
Y423462D01*
G01D02*
X677100D01*
G01D02*
Y420262D01*
G01Y440762D02*
X670900D01*
G01D02*
Y443962D01*
G01D02*
X677100D01*
G01D02*
Y440762D01*
G01Y448262D02*
X670900D01*
G01D02*
Y451462D01*
G01X677100D02*
Y448262D01*
G01X670900Y435462D02*
X677100D01*
G01X670900Y451462D02*
X677100D01*
G01X670900Y459462D02*
X677100D01*
G01D02*
Y456262D01*
G01D02*
X670900D01*
G01D02*
Y459462D01*
G01Y455462D02*
X677100D01*
G01D02*
Y452262D01*
G01D02*
X670900D01*
G01D02*
Y455462D01*
G01Y463462D02*
X677100D01*
G01D02*
Y460262D01*
G01D02*
X670900D01*
G01D02*
Y463462D01*
G01X677100Y479462D02*
Y476262D01*
G01D02*
X670900D01*
G01D02*
Y479462D01*
G01Y467462D02*
X677100D01*
G01D02*
Y464262D01*
G01D02*
X670900D01*
G01D02*
Y467462D01*
G01X670816Y472668D02*
Y475868D01*
G01X677016Y472668D02*
X670816D01*
G01X677016Y475868D02*
Y472668D01*
G01X670816Y475868D02*
X677016D01*
G01X670900Y479462D02*
X677100D01*
G01X670900Y484462D02*
X677100D01*
G01D02*
Y481262D01*
G01D02*
X670900D01*
G01D02*
Y484462D01*
G01X666055Y488541D02*
Y485341D01*
G01X677132Y485342D02*
X670932D01*
G01D02*
Y488542D01*
G01D02*
X677132D01*
G01D02*
Y485342D01*
G01X665917Y496726D02*
Y493526D01*
G01X677389Y493484D02*
X671189D01*
G01D02*
Y496684D01*
G01D02*
X677389D01*
G01D02*
Y493484D01*
G01X665186Y503295D02*
Y506495D01*
G01X671386Y503295D02*
X665186D01*
G01X671386Y506495D02*
Y503295D01*
G01X665186Y506495D02*
X671386D01*
G01X673186Y503295D02*
Y506495D01*
G01X679386Y503295D02*
X673186D01*
G01Y506495D02*
X679386D01*
G01X681100Y519400D02*
X677900D01*
G01D02*
Y525600D01*
G01X676118Y526100D02*
Y513900D01*
G01X677900Y525600D02*
X681100D01*
G01X663900Y527900D02*
Y531100D01*
G01X670100Y527900D02*
X663900D01*
G01X670100Y531100D02*
Y527900D01*
G01X663900Y531100D02*
X670100D01*
G01Y535100D02*
Y531900D01*
G01X663900Y535100D02*
X670100D01*
G01X663900Y531900D02*
Y535100D01*
G01X670100Y531900D02*
X663900D01*
G01X672331Y687245D02*
Y1303870D01*
G01X697921Y687245D02*
X672331D01*
G01X668220Y1325041D02*
Y687245D01*
G01X697921Y720710D02*
X672331D01*
G01X697921Y1291576D02*
X672331D01*
G01X676471Y1313289D02*
X679671D01*
G01X676471Y1307089D02*
Y1313289D01*
G01X679671Y1307089D02*
X676471D01*
G01X675700Y1314102D02*
Y1310902D01*
G01X669500D02*
Y1314102D01*
G01X675700Y1310902D02*
X669500D01*
G01Y1306402D02*
Y1309602D01*
G01X675700Y1306402D02*
X669500D01*
G01X675700Y1309602D02*
Y1306402D01*
G01X669500Y1309602D02*
X675700D01*
G01X669500Y1314102D02*
X675700D01*
G01X672331Y1325041D02*
X697921D01*
G01X672331Y1317230D02*
Y1325041D01*
G01X680446Y1326681D02*
X677346D01*
Y1327601D01*
X677501Y1327908D01*
X677863Y1328138D01*
X678276Y1328215D01*
X678689Y1328138D01*
X678999Y1327946D01*
X679154Y1327601D01*
Y1326681D01*
G01X677604Y1331391D02*
X677449Y1331161D01*
X677346Y1330893D01*
Y1330586D01*
X677501Y1330241D01*
X677759Y1329973D01*
X678069Y1329781D01*
X678586Y1329628D01*
X679051Y1329590D01*
X679516Y1329666D01*
X679826Y1329781D01*
X680136Y1330011D01*
X680343Y1330280D01*
X680446Y1330548D01*
Y1330816D01*
X680343Y1331085D01*
X680188Y1331315D01*
X679981Y1331506D01*
G01Y1332805D02*
X680239Y1333035D01*
X680394Y1333303D01*
X680446Y1333648D01*
X680343Y1333993D01*
X680136Y1334261D01*
X679774Y1334453D01*
X679361Y1334491D01*
X678948Y1334415D01*
X678689Y1334223D01*
X678483Y1333955D01*
X678431Y1333686D01*
X678483Y1333418D01*
X678689Y1333073D01*
X677346Y1333188D01*
Y1334223D01*
G01X679826Y1335905D02*
X680188Y1336135D01*
X680394Y1336441D01*
X680446Y1336786D01*
X680394Y1337093D01*
X680136Y1337400D01*
X679826Y1337591D01*
X679516Y1337630D01*
X679154Y1337553D01*
X678896Y1337285D01*
X678793Y1337016D01*
Y1336671D01*
G01Y1337016D02*
X678638Y1337246D01*
X678379Y1337438D01*
X678069Y1337515D01*
X677759Y1337438D01*
X677501Y1337246D01*
X677346Y1336901D01*
X677398Y1336556D01*
X677604Y1336211D01*
G01X680446Y1339848D02*
X677346D01*
X677966Y1339388D01*
G01X680446D02*
Y1340308D01*
G01X675568Y1326641D02*
X672468D01*
Y1327561D01*
X672623Y1327868D01*
X672985Y1328098D01*
X673398Y1328175D01*
X673811Y1328098D01*
X674121Y1327906D01*
X674276Y1327561D01*
Y1326641D01*
G01X672726Y1331351D02*
X672571Y1331121D01*
X672468Y1330853D01*
Y1330546D01*
X672623Y1330201D01*
X672881Y1329933D01*
X673191Y1329741D01*
X673708Y1329588D01*
X674173Y1329550D01*
X674638Y1329626D01*
X674948Y1329741D01*
X675258Y1329971D01*
X675465Y1330240D01*
X675568Y1330508D01*
Y1330776D01*
X675465Y1331045D01*
X675310Y1331275D01*
X675103Y1331466D01*
G01X675568Y1333608D02*
X675516Y1333876D01*
X675361Y1334183D01*
X675103Y1334375D01*
X674741Y1334451D01*
X674380Y1334375D01*
X674070Y1334145D01*
X673915Y1333800D01*
Y1333416D01*
X673811Y1333186D01*
X673553Y1332995D01*
X673191Y1332918D01*
X672830Y1333033D01*
X672571Y1333301D01*
X672468Y1333608D01*
X672571Y1333915D01*
X672830Y1334183D01*
X673191Y1334298D01*
X673553Y1334221D01*
X673811Y1334030D01*
X673915Y1333800D01*
Y1333416D01*
X674070Y1333071D01*
X674380Y1332841D01*
X674741Y1332765D01*
X675103Y1332841D01*
X675361Y1333033D01*
X675516Y1333340D01*
X675568Y1333608D01*
G01X672468Y1336708D02*
X672571Y1336401D01*
X672830Y1336171D01*
X673140Y1336018D01*
X673553Y1335903D01*
X674018Y1335865D01*
X674483Y1335903D01*
X674896Y1336018D01*
X675206Y1336171D01*
X675465Y1336401D01*
X675568Y1336708D01*
X675465Y1337015D01*
X675206Y1337245D01*
X674896Y1337398D01*
X674483Y1337513D01*
X674018Y1337551D01*
X673553Y1337513D01*
X673140Y1337398D01*
X672830Y1337245D01*
X672571Y1337015D01*
X672468Y1336708D01*
G01X674948Y1338965D02*
X675310Y1339195D01*
X675516Y1339501D01*
X675568Y1339846D01*
X675516Y1340153D01*
X675258Y1340460D01*
X674948Y1340651D01*
X674638Y1340690D01*
X674276Y1340613D01*
X674018Y1340345D01*
X673915Y1340076D01*
Y1339731D01*
G01Y1340076D02*
X673760Y1340306D01*
X673501Y1340498D01*
X673191Y1340575D01*
X672881Y1340498D01*
X672623Y1340306D01*
X672468Y1339961D01*
X672520Y1339616D01*
X672726Y1339271D01*
G01X669102Y1366471D02*
X666002D01*
Y1367391D01*
X666157Y1367698D01*
X666519Y1367928D01*
X666932Y1368005D01*
X667345Y1367928D01*
X667655Y1367736D01*
X667810Y1367391D01*
Y1366471D01*
G01X666002Y1369495D02*
X668224D01*
X668689Y1369648D01*
X668999Y1369955D01*
X669102Y1370338D01*
X668999Y1370721D01*
X668689Y1371028D01*
X668224Y1371181D01*
X666002D01*
G01X668637Y1372595D02*
X668895Y1372825D01*
X669050Y1373093D01*
X669102Y1373438D01*
X668999Y1373783D01*
X668792Y1374051D01*
X668430Y1374243D01*
X668017Y1374281D01*
X667604Y1374205D01*
X667345Y1374013D01*
X667139Y1373745D01*
X667087Y1373476D01*
X667139Y1373208D01*
X667345Y1372863D01*
X666002Y1372978D01*
Y1374013D01*
G01X669102Y1376998D02*
X666002D01*
X668224Y1375580D01*
Y1377496D01*
G01X666385Y1399338D02*
Y1402438D01*
G01X667995D02*
Y1399338D01*
G01Y1400888D02*
X666385D01*
G01X669562Y1401921D02*
X669792Y1402231D01*
X670060Y1402386D01*
X670367Y1402438D01*
X670750Y1402335D01*
X671018Y1402076D01*
X671095Y1401766D01*
X671057Y1401456D01*
X670903Y1401198D01*
X670137Y1400681D01*
X669792Y1400320D01*
X669562Y1399803D01*
X669485Y1399338D01*
X671095D01*
G01X672662Y1401921D02*
X672892Y1402231D01*
X673160Y1402386D01*
X673467Y1402438D01*
X673850Y1402335D01*
X674118Y1402076D01*
X674195Y1401766D01*
X674157Y1401456D01*
X674003Y1401198D01*
X673237Y1400681D01*
X672892Y1400320D01*
X672662Y1399803D01*
X672585Y1399338D01*
X674195D01*
G01X664200Y1518200D02*
Y1524200D01*
G01X676200Y1518200D02*
X664200D01*
G01X676200Y1524200D02*
Y1518200D01*
G01X677040Y1511000D02*
Y1517400D01*
G01X664160Y1511000D02*
Y1517400D01*
G01D02*
X677040D01*
G01Y1511000D02*
X664160D01*
G01X664133Y1533745D02*
Y1539745D01*
G01X676133Y1533745D02*
X664133D01*
G01X676133Y1539745D02*
Y1533745D01*
G01X664200Y1524200D02*
X676200D01*
G01X671290Y1532026D02*
X677290D01*
Y1529026D01*
X671290D01*
Y1532026D01*
G01X664232Y1525900D02*
Y1532100D01*
X667432D01*
Y1525900D01*
X664232D01*
G01X677390Y1525026D02*
X671190D01*
Y1528226D01*
X677390D01*
Y1525026D01*
G01X674240Y1528926D02*
X668040D01*
Y1532126D01*
X674240D01*
Y1528926D01*
G01Y1525026D02*
X668040D01*
Y1528226D01*
X674240D01*
Y1525026D01*
G01X664133Y1546599D02*
X676133D01*
G01X664133Y1540599D02*
Y1546599D01*
G01X676133Y1540599D02*
X664133D01*
G01X676133Y1546599D02*
Y1540599D01*
G01X664133Y1539745D02*
X676133D01*
G01X676205Y1637442D02*
X682405D01*
G01X676205Y1634242D02*
Y1637442D01*
G01X682405Y1634242D02*
X676205D01*
G01X676193Y1638104D02*
Y1641304D01*
G01X682393Y1638104D02*
X676193D01*
G01Y1641304D02*
X682393D01*
G01X676205Y1649442D02*
X682405D01*
G01X676205Y1646242D02*
Y1649442D01*
G01X682405Y1646242D02*
X676205D01*
G01X676193Y1642304D02*
Y1645504D01*
G01X682393Y1642304D02*
X676193D01*
G01Y1645504D02*
X682393D01*
G01X680314Y1664540D02*
X676071Y1668783D01*
G01D02*
X680314Y1673026D01*
G01X667100Y1709784D02*
Y1706584D01*
G01Y1713684D02*
Y1710484D01*
G01X671802Y1712179D02*
X671495Y1712231D01*
X671227Y1712437D01*
X670997Y1712747D01*
X670844Y1713109D01*
X670767Y1713522D01*
Y1713936D01*
X670844Y1714349D01*
X670997Y1714711D01*
X671227Y1715021D01*
X671495Y1715227D01*
X671802Y1715279D01*
X672109Y1715227D01*
X672377Y1715021D01*
X672607Y1714711D01*
X672760Y1714349D01*
X672837Y1713936D01*
Y1713522D01*
X672760Y1713109D01*
X672607Y1712747D01*
X672377Y1712437D01*
X672109Y1712231D01*
X671802Y1712179D01*
G01X672109Y1713006D02*
X672569Y1712179D01*
G01X674902D02*
Y1715279D01*
X674442Y1714659D01*
G01Y1712179D02*
X675362D01*
G01X678002Y1715279D02*
X677695Y1715176D01*
X677465Y1714917D01*
X677312Y1714607D01*
X677197Y1714194D01*
X677159Y1713729D01*
X677197Y1713264D01*
X677312Y1712851D01*
X677465Y1712541D01*
X677695Y1712282D01*
X678002Y1712179D01*
X678309Y1712282D01*
X678539Y1712541D01*
X678692Y1712851D01*
X678807Y1713264D01*
X678845Y1713729D01*
X678807Y1714194D01*
X678692Y1714607D01*
X678539Y1714917D01*
X678309Y1715176D01*
X678002Y1715279D01*
G01X680374Y1714762D02*
X680604Y1715072D01*
X680872Y1715227D01*
X681179Y1715279D01*
X681562Y1715176D01*
X681830Y1714917D01*
X681907Y1714607D01*
X681869Y1714297D01*
X681715Y1714039D01*
X680949Y1713522D01*
X680604Y1713161D01*
X680374Y1712644D01*
X680297Y1712179D01*
X681907D01*
G01X666160Y1723946D02*
Y1715284D01*
G01X674713Y1728161D02*
X671513D01*
G01X674713Y1734361D02*
Y1728161D01*
G01X671513D02*
Y1734361D01*
G01X674713Y1717499D02*
X671513D01*
G01X674713Y1723699D02*
Y1717499D01*
G01X671513Y1723699D02*
X674713D01*
G01X671513Y1717499D02*
Y1723699D01*
G01X675359Y1724214D02*
X675052Y1724266D01*
X674784Y1724472D01*
X674554Y1724782D01*
X674401Y1725144D01*
X674324Y1725557D01*
Y1725971D01*
X674401Y1726384D01*
X674554Y1726746D01*
X674784Y1727056D01*
X675052Y1727262D01*
X675359Y1727314D01*
X675666Y1727262D01*
X675934Y1727056D01*
X676164Y1726746D01*
X676317Y1726384D01*
X676394Y1725971D01*
Y1725557D01*
X676317Y1725144D01*
X676164Y1724782D01*
X675934Y1724472D01*
X675666Y1724266D01*
X675359Y1724214D01*
G01X675666Y1725041D02*
X676126Y1724214D01*
G01X677731Y1725506D02*
X677999Y1725867D01*
X678229Y1726074D01*
X678536Y1726177D01*
X678804Y1726074D01*
X678996Y1725867D01*
X679149Y1725557D01*
X679187Y1725196D01*
X679149Y1724886D01*
X678996Y1724576D01*
X678766Y1724317D01*
X678497Y1724214D01*
X678191Y1724317D01*
X677922Y1724627D01*
X677769Y1725092D01*
X677731Y1725609D01*
X677807Y1726281D01*
X677922Y1726642D01*
X678114Y1727004D01*
X678382Y1727262D01*
X678651Y1727314D01*
X678919Y1727211D01*
X679111Y1726952D01*
G01X681482Y1724214D02*
X681559Y1724886D01*
X681674Y1725454D01*
X681827Y1725971D01*
X682019Y1726539D01*
X682326Y1727314D01*
X680792D01*
G01X666160Y1734608D02*
Y1725946D01*
G01X671513Y1734361D02*
X674713D01*
G01X695320Y75362D02*
X689120D01*
G01D02*
Y78562D01*
G01D02*
X695320D01*
G01X695553Y90068D02*
X689353D01*
G01D02*
Y93268D01*
G01X683220Y80362D02*
Y86362D01*
G01D02*
X695220D01*
G01Y80362D02*
X683220D01*
G01X689353Y93268D02*
X695553D01*
G01X682443Y99158D02*
X692643D01*
G01D02*
Y94558D01*
G01D02*
X682443D01*
G01D02*
Y99158D01*
G01X692643Y99458D02*
X682443D01*
G01D02*
Y104058D01*
G01D02*
X692643D01*
G01D02*
Y99458D01*
G01X689853Y107019D02*
Y104519D01*
X690173Y105019D01*
G01Y107019D02*
X689533D01*
G01X688160Y104936D02*
X688000Y104686D01*
X687813Y104561D01*
X687600Y104519D01*
X687333Y104602D01*
X687146Y104811D01*
X687093Y105061D01*
X687120Y105311D01*
X687226Y105519D01*
X687760Y105936D01*
X688000Y106227D01*
X688160Y106644D01*
X688213Y107019D01*
X687093D01*
G01X679023Y107285D02*
Y113485D01*
G01D02*
X682223D01*
G01D02*
Y107285D01*
G01D02*
X679023D01*
G01X678853Y117468D02*
X685053D01*
G01D02*
Y114268D01*
G01D02*
X678853D01*
G01D02*
Y117468D01*
G01X685053Y118268D02*
X678853D01*
G01D02*
Y121468D01*
G01X685053D02*
Y118268D01*
G01X686243Y113485D02*
Y107285D01*
G01D02*
X683043D01*
G01D02*
Y113485D01*
G01D02*
X686243D01*
G01X685900Y120628D02*
X688400D01*
X687900Y120948D01*
G01X685900D02*
Y120308D01*
G01X688400Y118428D02*
X688317Y118641D01*
X688108Y118801D01*
X687858Y118908D01*
X687525Y118988D01*
X687150Y119015D01*
X686775Y118988D01*
X686442Y118908D01*
X686192Y118801D01*
X685983Y118641D01*
X685900Y118428D01*
X685983Y118215D01*
X686192Y118055D01*
X686442Y117948D01*
X686775Y117868D01*
X687150Y117841D01*
X687525Y117868D01*
X687858Y117948D01*
X688108Y118055D01*
X688317Y118215D01*
X688400Y118428D01*
G01X690709Y120030D02*
X689544D01*
G01D02*
Y116896D01*
G01Y114896D02*
Y112960D01*
G01Y110960D02*
Y107826D01*
G01D02*
X690709D01*
G01X692853Y126568D02*
Y132768D01*
G01D02*
X696053D01*
G01Y126568D02*
X692853D01*
G01X685853D02*
Y132768D01*
G01D02*
X689053D01*
G01D02*
Y126568D01*
G01D02*
X685853D01*
G01X681853D02*
Y132768D01*
G01D02*
X685053D01*
G01D02*
Y126568D01*
G01D02*
X681853D01*
G01X678853Y121468D02*
X685053D01*
G01X691836Y124969D02*
X691650Y125178D01*
X691436Y125261D01*
X691223Y125178D01*
X691036Y124928D01*
X690903Y124553D01*
X690850Y124178D01*
Y123719D01*
X690903Y123344D01*
X691036Y123011D01*
X691196Y122844D01*
X691383Y122761D01*
X691596Y122844D01*
X691756Y123011D01*
X691863Y123261D01*
X691916Y123594D01*
X691863Y123886D01*
X691730Y124178D01*
X691570Y124344D01*
X691383Y124386D01*
X691170Y124303D01*
X691010Y124094D01*
X690850Y123719D01*
G01X679313Y142224D02*
X688226D01*
G01X688213Y141929D02*
X678813D01*
G01X678463Y160266D02*
Y168772D01*
G01X682400Y376462D02*
Y370262D01*
G01D02*
X679200D01*
G01D02*
Y376462D01*
G01X686400D02*
Y370262D01*
G01D02*
X683200D01*
G01D02*
Y376462D01*
G01X678400D02*
Y370262D01*
G01X691040Y361804D02*
X687840D01*
G01X691040Y368004D02*
Y361804D01*
G01X687840Y368004D02*
X691040D01*
G01X687840Y361804D02*
Y368004D01*
G01X691767D02*
X694967D01*
G01X691767Y361804D02*
Y368004D01*
G01X694967Y361804D02*
X691767D01*
G01X679200Y376462D02*
X682400D01*
G01X683200D02*
X686400D01*
G01X689200Y375262D02*
Y381462D01*
G01D02*
X692400D01*
G01D02*
Y375262D01*
G01D02*
X689200D01*
G01X685100Y397962D02*
Y391762D01*
G01D02*
X681900D01*
G01D02*
Y397962D01*
G01D02*
X685100D01*
G01X681100D02*
Y391762D01*
G01X685900D02*
Y397962D01*
G01D02*
X689100D01*
G01D02*
Y391762D01*
G01D02*
X685900D01*
G01X693100D02*
X689900D01*
G01D02*
Y397962D01*
G01D02*
X693100D01*
G01X679720Y412604D02*
Y410382D01*
X679873Y409917D01*
X680180Y409607D01*
X680563Y409504D01*
X680946Y409607D01*
X681253Y409917D01*
X681406Y410382D01*
Y412604D01*
G01X683663Y409504D02*
Y412604D01*
X683203Y411984D01*
G01Y409504D02*
X684123D01*
G01X686763D02*
X687031Y409556D01*
X687338Y409711D01*
X687530Y409969D01*
X687606Y410331D01*
X687530Y410692D01*
X687300Y411002D01*
X686955Y411157D01*
X686571D01*
X686341Y411261D01*
X686150Y411519D01*
X686073Y411881D01*
X686188Y412242D01*
X686456Y412501D01*
X686763Y412604D01*
X687070Y412501D01*
X687338Y412242D01*
X687453Y411881D01*
X687376Y411519D01*
X687185Y411261D01*
X686955Y411157D01*
X686571D01*
X686226Y411002D01*
X685996Y410692D01*
X685920Y410331D01*
X685996Y409969D01*
X686188Y409711D01*
X686495Y409556D01*
X686763Y409504D01*
G01X685710Y506262D02*
Y512462D01*
G01X688910D02*
Y506262D01*
G01D02*
X685710D01*
G01X690900D02*
Y512462D01*
G01X694100Y506262D02*
X690900D01*
G01X679386Y506495D02*
Y503295D01*
G01X681100Y525600D02*
Y519400D01*
G01X685710Y512462D02*
X688910D01*
G01X690900D02*
X694100D01*
G01X686900Y538762D02*
Y544962D01*
G01D02*
X690100D01*
G01D02*
Y538762D01*
G01D02*
X686900D01*
G01X691959Y683096D02*
X692151Y682786D01*
X692381Y682579D01*
X692649Y682476D01*
X692956Y682579D01*
X693186Y682786D01*
X693416Y683096D01*
X693493Y683509D01*
Y685576D01*
G01X695098Y685059D02*
X695328Y685369D01*
X695596Y685524D01*
X695903Y685576D01*
X696286Y685473D01*
X696554Y685214D01*
X696631Y684904D01*
X696593Y684594D01*
X696439Y684336D01*
X695673Y683819D01*
X695328Y683458D01*
X695098Y682941D01*
X695021Y682476D01*
X696631D01*
G01X698849D02*
X698926Y683148D01*
X699041Y683716D01*
X699194Y684233D01*
X699386Y684801D01*
X699693Y685576D01*
X698159D01*
G01X679671Y1313289D02*
Y1307089D01*
G01X681934Y1299151D02*
X689061D01*
G01X681934Y1317805D02*
Y1299151D01*
G01X692736Y1327111D02*
X689636D01*
Y1328031D01*
X689791Y1328338D01*
X690153Y1328568D01*
X690566Y1328645D01*
X690979Y1328568D01*
X691289Y1328376D01*
X691444Y1328031D01*
Y1327111D01*
G01X689894Y1331821D02*
X689739Y1331591D01*
X689636Y1331323D01*
Y1331016D01*
X689791Y1330671D01*
X690049Y1330403D01*
X690359Y1330211D01*
X690876Y1330058D01*
X691341Y1330020D01*
X691806Y1330096D01*
X692116Y1330211D01*
X692426Y1330441D01*
X692633Y1330710D01*
X692736Y1330978D01*
Y1331246D01*
X692633Y1331515D01*
X692478Y1331745D01*
X692271Y1331936D01*
G01Y1333235D02*
X692529Y1333465D01*
X692684Y1333733D01*
X692736Y1334078D01*
X692633Y1334423D01*
X692426Y1334691D01*
X692064Y1334883D01*
X691651Y1334921D01*
X691238Y1334845D01*
X690979Y1334653D01*
X690773Y1334385D01*
X690721Y1334116D01*
X690773Y1333848D01*
X690979Y1333503D01*
X689636Y1333618D01*
Y1334653D01*
G01X692116Y1336335D02*
X692478Y1336565D01*
X692684Y1336871D01*
X692736Y1337216D01*
X692684Y1337523D01*
X692426Y1337830D01*
X692116Y1338021D01*
X691806Y1338060D01*
X691444Y1337983D01*
X691186Y1337715D01*
X691083Y1337446D01*
Y1337101D01*
G01Y1337446D02*
X690928Y1337676D01*
X690669Y1337868D01*
X690359Y1337945D01*
X690049Y1337868D01*
X689791Y1337676D01*
X689636Y1337331D01*
X689688Y1336986D01*
X689894Y1336641D01*
G01X690153Y1339550D02*
X689843Y1339780D01*
X689688Y1340048D01*
X689636Y1340355D01*
X689739Y1340738D01*
X689998Y1341006D01*
X690308Y1341083D01*
X690618Y1341045D01*
X690876Y1340891D01*
X691393Y1340125D01*
X691754Y1339780D01*
X692271Y1339550D01*
X692736Y1339473D01*
Y1341083D01*
G01X684934Y1320805D02*
X681934Y1317805D01*
G01X689061Y1320805D02*
X684934D01*
G01X679200Y1511800D02*
Y1523800D01*
G01X685200Y1511800D02*
X679200D01*
G01X685200Y1523800D02*
Y1511800D01*
G01X686520Y1514926D02*
Y1521126D01*
X689720D01*
Y1514926D01*
X686520D01*
G01X678677Y1528926D02*
Y1532126D01*
G01X684877Y1528926D02*
X678677D01*
G01X684877Y1532126D02*
Y1528926D01*
G01X678677Y1532126D02*
X684877D01*
G01X678677Y1524926D02*
Y1528126D01*
G01X684877Y1524926D02*
X678677D01*
G01X684877Y1528126D02*
Y1524926D01*
G01X678677Y1528126D02*
X684877D01*
G01X679200Y1523800D02*
X685200D01*
G01X682405Y1637442D02*
Y1634242D01*
G01X682393Y1641304D02*
Y1638104D01*
G01X688274Y1639001D02*
Y1647663D01*
G01X698768Y1639001D02*
X688274D01*
G01X682405Y1649442D02*
Y1646242D01*
G01X682393Y1645504D02*
Y1642304D01*
G01X683678Y1649127D02*
X683371Y1649179D01*
X683103Y1649385D01*
X682873Y1649695D01*
X682720Y1650057D01*
X682643Y1650470D01*
Y1650884D01*
X682720Y1651297D01*
X682873Y1651659D01*
X683103Y1651969D01*
X683371Y1652175D01*
X683678Y1652227D01*
X683985Y1652175D01*
X684253Y1651969D01*
X684483Y1651659D01*
X684636Y1651297D01*
X684713Y1650884D01*
Y1650470D01*
X684636Y1650057D01*
X684483Y1649695D01*
X684253Y1649385D01*
X683985Y1649179D01*
X683678Y1649127D01*
G01X683985Y1649954D02*
X684445Y1649127D01*
G01X686126Y1649489D02*
X686395Y1649230D01*
X686701Y1649127D01*
X687008Y1649230D01*
X687276Y1649540D01*
X687468Y1650005D01*
X687545Y1650470D01*
Y1651039D01*
X687468Y1651504D01*
X687276Y1651917D01*
X687046Y1652124D01*
X686778Y1652227D01*
X686471Y1652124D01*
X686241Y1651917D01*
X686088Y1651607D01*
X686011Y1651194D01*
X686088Y1650832D01*
X686280Y1650470D01*
X686510Y1650264D01*
X686778Y1650212D01*
X687085Y1650315D01*
X687315Y1650574D01*
X687545Y1651039D01*
G01X689878Y1652227D02*
X689571Y1652124D01*
X689341Y1651865D01*
X689188Y1651555D01*
X689073Y1651142D01*
X689035Y1650677D01*
X689073Y1650212D01*
X689188Y1649799D01*
X689341Y1649489D01*
X689571Y1649230D01*
X689878Y1649127D01*
X690185Y1649230D01*
X690415Y1649489D01*
X690568Y1649799D01*
X690683Y1650212D01*
X690721Y1650677D01*
X690683Y1651142D01*
X690568Y1651555D01*
X690415Y1651865D01*
X690185Y1652124D01*
X689878Y1652227D01*
G01X692978D02*
X692671Y1652124D01*
X692441Y1651865D01*
X692288Y1651555D01*
X692173Y1651142D01*
X692135Y1650677D01*
X692173Y1650212D01*
X692288Y1649799D01*
X692441Y1649489D01*
X692671Y1649230D01*
X692978Y1649127D01*
X693285Y1649230D01*
X693515Y1649489D01*
X693668Y1649799D01*
X693783Y1650212D01*
X693821Y1650677D01*
X693783Y1651142D01*
X693668Y1651555D01*
X693515Y1651865D01*
X693285Y1652124D01*
X692978Y1652227D01*
G01X696078Y1649127D02*
Y1652227D01*
X695618Y1651607D01*
G01Y1649127D02*
X696538D01*
G01X691621Y1647663D02*
X693521Y1645463D01*
G01X688274Y1647663D02*
X691621D01*
G01X681296Y1670637D02*
X683518D01*
X683983Y1670790D01*
X684293Y1671097D01*
X684396Y1671480D01*
X684293Y1671863D01*
X683983Y1672170D01*
X683518Y1672323D01*
X681296D01*
G01X681813Y1673852D02*
X681503Y1674082D01*
X681348Y1674350D01*
X681296Y1674657D01*
X681399Y1675040D01*
X681658Y1675308D01*
X681968Y1675385D01*
X682278Y1675347D01*
X682536Y1675193D01*
X683053Y1674427D01*
X683414Y1674082D01*
X683931Y1673852D01*
X684396Y1673775D01*
Y1675385D01*
G01Y1677680D02*
X681296D01*
X681916Y1677220D01*
G01X684396D02*
Y1678140D01*
G01X680314Y1661583D02*
Y1664540D01*
G01Y1673026D02*
Y1675983D01*
G01X682162Y1730543D02*
Y1733643D01*
G01X683772D02*
Y1730543D01*
G01Y1732093D02*
X682162D01*
G01X686067Y1730543D02*
Y1733643D01*
X685607Y1733023D01*
G01Y1730543D02*
X686527D01*
G01X689167Y1733643D02*
X688860Y1733540D01*
X688630Y1733281D01*
X688477Y1732971D01*
X688362Y1732558D01*
X688324Y1732093D01*
X688362Y1731628D01*
X688477Y1731215D01*
X688630Y1730905D01*
X688860Y1730646D01*
X689167Y1730543D01*
X689474Y1730646D01*
X689704Y1730905D01*
X689857Y1731215D01*
X689972Y1731628D01*
X690010Y1732093D01*
X689972Y1732558D01*
X689857Y1732971D01*
X689704Y1733281D01*
X689474Y1733540D01*
X689167Y1733643D01*
G01X691539Y1731835D02*
X691807Y1732196D01*
X692037Y1732403D01*
X692344Y1732506D01*
X692612Y1732403D01*
X692804Y1732196D01*
X692957Y1731886D01*
X692995Y1731525D01*
X692957Y1731215D01*
X692804Y1730905D01*
X692574Y1730646D01*
X692305Y1730543D01*
X691999Y1730646D01*
X691730Y1730956D01*
X691577Y1731421D01*
X691539Y1731938D01*
X691615Y1732610D01*
X691730Y1732971D01*
X691922Y1733333D01*
X692190Y1733591D01*
X692459Y1733643D01*
X692727Y1733540D01*
X692919Y1733281D01*
G01X695320Y78562D02*
Y75362D01*
G01X720254Y64566D02*
X705454D01*
G01X695553Y93268D02*
Y90068D01*
G01X695220Y86362D02*
Y80362D01*
G01X705323Y104908D02*
X711523D01*
G01Y101708D02*
X705323D01*
G01D02*
Y104908D01*
G01X710590Y97878D02*
X710430Y97628D01*
X710243Y97503D01*
X710030Y97461D01*
X709763Y97544D01*
X709576Y97753D01*
X709523Y98003D01*
X709550Y98253D01*
X709656Y98461D01*
X710190Y98878D01*
X710430Y99169D01*
X710590Y99586D01*
X710643Y99961D01*
X709523D01*
G01X707883Y97461D02*
X708096Y97544D01*
X708256Y97753D01*
X708363Y98003D01*
X708443Y98336D01*
X708470Y98711D01*
X708443Y99086D01*
X708363Y99419D01*
X708256Y99669D01*
X708096Y99878D01*
X707883Y99961D01*
X707670Y99878D01*
X707510Y99669D01*
X707403Y99419D01*
X707323Y99086D01*
X707296Y98711D01*
X707323Y98336D01*
X707403Y98003D01*
X707510Y97753D01*
X707670Y97544D01*
X707883Y97461D01*
G01X703353Y126568D02*
Y132768D01*
G01D02*
X706553D01*
G01D02*
Y126568D01*
G01D02*
X703353D01*
G01X696053Y132768D02*
Y126568D01*
G01X710553D02*
X707353D01*
G01D02*
Y132768D01*
G01D02*
X710553D01*
G01X699363Y126628D02*
Y132828D01*
G01D02*
X702563D01*
G01D02*
Y126628D01*
G01D02*
X699363D01*
G01X701780Y150063D02*
X702452Y149986D01*
X703020Y149871D01*
X703537Y149718D01*
X704105Y149526D01*
X704880Y149219D01*
Y150753D01*
G01X702245Y147729D02*
X701987Y147499D01*
X701832Y147231D01*
X701780Y146886D01*
X701883Y146541D01*
X702090Y146273D01*
X702452Y146081D01*
X702865Y146043D01*
X703278Y146119D01*
X703537Y146311D01*
X703743Y146579D01*
X703795Y146848D01*
X703743Y147116D01*
X703537Y147461D01*
X704880Y147346D01*
Y146311D01*
G01X703172Y159814D02*
X703533Y159546D01*
X703740Y159316D01*
X703843Y159009D01*
X703740Y158741D01*
X703533Y158549D01*
X703223Y158396D01*
X702862Y158358D01*
X702552Y158396D01*
X702242Y158549D01*
X701983Y158779D01*
X701880Y159048D01*
X701983Y159354D01*
X702293Y159623D01*
X702758Y159776D01*
X703275Y159814D01*
X703947Y159738D01*
X704308Y159623D01*
X704670Y159431D01*
X704928Y159163D01*
X704980Y158894D01*
X704877Y158626D01*
X704618Y158434D01*
G01X701880Y156063D02*
X702552Y155986D01*
X703120Y155871D01*
X703637Y155718D01*
X704205Y155526D01*
X704980Y155219D01*
Y156753D01*
G01X702242Y170028D02*
X701984Y169798D01*
X701829Y169530D01*
X701777Y169185D01*
X701880Y168840D01*
X702087Y168572D01*
X702449Y168380D01*
X702862Y168342D01*
X703275Y168418D01*
X703534Y168610D01*
X703740Y168878D01*
X703792Y169147D01*
X703740Y169415D01*
X703534Y169760D01*
X704877Y169645D01*
Y168610D01*
G01X701777Y166162D02*
X702449Y166085D01*
X703017Y165970D01*
X703534Y165817D01*
X704102Y165625D01*
X704877Y165318D01*
Y166852D01*
G01X697769Y165485D02*
Y157743D01*
G01X696588D02*
Y165485D01*
G01X705945Y361721D02*
Y367921D01*
G01D02*
X709145D01*
G01Y361721D02*
X705945D01*
G01X705120Y361804D02*
X701920D01*
G01X705120Y368004D02*
Y361804D01*
G01X701920Y368004D02*
X705120D01*
G01X701920Y361804D02*
Y368004D01*
G01X694967D02*
Y361804D01*
G01X697920Y368004D02*
X701120D01*
G01X697920Y361804D02*
Y368004D01*
G01X701120Y361804D02*
X697920D01*
G01X701120Y368004D02*
Y361804D01*
G01X706700Y375262D02*
Y381462D01*
G01D02*
X709900D01*
G01Y375262D02*
X706700D01*
G01X702700D02*
Y381462D01*
G01D02*
X705900D01*
G01D02*
Y375262D01*
G01D02*
X702700D01*
G01X698700D02*
Y381462D01*
G01D02*
X701900D01*
G01D02*
Y375262D01*
G01D02*
X698700D01*
G01X693100Y397962D02*
Y391762D01*
G01X705900D02*
Y397962D01*
G01D02*
X709100D01*
G01Y391762D02*
X705900D01*
G01X697900D02*
Y397962D01*
G01D02*
X701100D01*
G01D02*
Y391762D01*
G01D02*
X697900D01*
G01X693900D02*
Y397962D01*
G01D02*
X697100D01*
G01D02*
Y391762D01*
G01D02*
X693900D01*
G01X701900D02*
Y397962D01*
G01D02*
X705100D01*
G01D02*
Y391762D01*
G01D02*
X701900D01*
G01X693000Y490366D02*
Y415562D01*
G01D02*
X767804D01*
G01Y490366D02*
X693000D01*
G01X710100Y506262D02*
X706900D01*
G01D02*
Y512462D01*
G01X698900Y506262D02*
Y512462D01*
G01X702100D02*
Y506262D01*
G01D02*
X698900D01*
G01X694900D02*
Y512462D01*
G01X698100D02*
Y506262D01*
G01D02*
X694900D01*
G01X694100Y512462D02*
Y506262D01*
G01X703066Y506217D02*
Y512417D01*
G01X706266Y506217D02*
X703066D01*
G01X706266Y512417D02*
Y506217D01*
G01X706900Y512462D02*
X710100D01*
G01X698900D02*
X702100D01*
G01X694900D02*
X698100D01*
G01X706100Y528962D02*
Y522762D01*
G01D02*
X702900D01*
G01D02*
Y528962D01*
G01X694900Y522762D02*
Y528962D01*
G01X698100D02*
Y522762D01*
G01D02*
X694900D01*
G01X702100Y528962D02*
Y522762D01*
G01D02*
X698900D01*
G01D02*
Y528962D01*
G01X706909Y522245D02*
Y528445D01*
G01X710109Y522245D02*
X706909D01*
G01X703066Y512417D02*
X706266D01*
G01X702900Y528962D02*
X706100D01*
G01X694900D02*
X698100D01*
G01X698900D02*
X702100D01*
G01X706909Y528445D02*
X710109D01*
G01X710100Y538762D02*
X706900D01*
G01D02*
Y544962D01*
G01D02*
X710100D01*
G01X706100D02*
Y538762D01*
G01D02*
X702900D01*
G01D02*
Y544962D01*
G01D02*
X706100D01*
G01X698900Y538762D02*
Y544962D01*
G01D02*
X702100D01*
G01D02*
Y538762D01*
G01D02*
X698900D01*
G01X702900Y548762D02*
Y554962D01*
G01X706100D02*
Y548762D01*
G01D02*
X702900D01*
G01X694683Y545387D02*
X697883D01*
G01X694683Y539187D02*
Y545387D01*
G01X697883Y539187D02*
X694683D01*
G01X697883Y545387D02*
Y539187D01*
G01X702900Y554962D02*
X706100D01*
G01X702456Y575981D02*
Y582181D01*
G01D02*
X705656D01*
G01D02*
Y575981D01*
G01D02*
X702456D01*
G01X697396D02*
Y582181D01*
G01D02*
X700596D01*
G01D02*
Y575981D01*
G01D02*
X697396D01*
G01X706456D02*
Y582181D01*
G01D02*
X709656D01*
G01Y575981D02*
X706456D01*
G01X693396D02*
Y582181D01*
G01D02*
X696596D01*
G01D02*
Y575981D01*
G01D02*
X693396D01*
G01X707628Y600599D02*
X704526Y597497D01*
G01D02*
X707628Y594497D01*
G01D02*
Y591735D01*
G01D02*
X695424D01*
G01D02*
Y603259D01*
G01X707628D02*
Y600599D01*
G01X695424Y603259D02*
X707628D01*
G01X704245Y623211D02*
Y617011D01*
G01D02*
X701045D01*
G01D02*
Y623211D01*
G01D02*
X704245D01*
G01X700245D02*
Y617011D01*
G01D02*
X697045D01*
G01D02*
Y623211D01*
G01D02*
X700245D01*
G01X697921Y1297200D02*
Y687245D01*
G01X702032D02*
Y1297200D01*
G01X727622Y687245D02*
X702032D01*
G01X727622Y720710D02*
X702032D01*
G01X727622Y1291576D02*
X702032D01*
G01X705812Y1299191D02*
X712939D01*
G01X705812Y1317845D02*
Y1299191D01*
G01X703588Y1299151D02*
Y1317805D01*
G01X696461Y1299151D02*
X703588D01*
G01X697921Y1325041D02*
Y1323600D01*
G01X702032Y1325041D02*
X727622D01*
G01X702032Y1323600D02*
Y1325041D01*
G01X697736Y1327111D02*
X694636D01*
Y1328031D01*
X694791Y1328338D01*
X695153Y1328568D01*
X695566Y1328645D01*
X695979Y1328568D01*
X696289Y1328376D01*
X696444Y1328031D01*
Y1327111D01*
G01X694894Y1331821D02*
X694739Y1331591D01*
X694636Y1331323D01*
Y1331016D01*
X694791Y1330671D01*
X695049Y1330403D01*
X695359Y1330211D01*
X695876Y1330058D01*
X696341Y1330020D01*
X696806Y1330096D01*
X697116Y1330211D01*
X697426Y1330441D01*
X697633Y1330710D01*
X697736Y1330978D01*
Y1331246D01*
X697633Y1331515D01*
X697478Y1331745D01*
X697271Y1331936D01*
G01Y1333235D02*
X697529Y1333465D01*
X697684Y1333733D01*
X697736Y1334078D01*
X697633Y1334423D01*
X697426Y1334691D01*
X697064Y1334883D01*
X696651Y1334921D01*
X696238Y1334845D01*
X695979Y1334653D01*
X695773Y1334385D01*
X695721Y1334116D01*
X695773Y1333848D01*
X695979Y1333503D01*
X694636Y1333618D01*
Y1334653D01*
G01X697116Y1336335D02*
X697478Y1336565D01*
X697684Y1336871D01*
X697736Y1337216D01*
X697684Y1337523D01*
X697426Y1337830D01*
X697116Y1338021D01*
X696806Y1338060D01*
X696444Y1337983D01*
X696186Y1337715D01*
X696083Y1337446D01*
Y1337101D01*
G01Y1337446D02*
X695928Y1337676D01*
X695669Y1337868D01*
X695359Y1337945D01*
X695049Y1337868D01*
X694791Y1337676D01*
X694636Y1337331D01*
X694688Y1336986D01*
X694894Y1336641D01*
G01X694636Y1340278D02*
X694739Y1339971D01*
X694998Y1339741D01*
X695308Y1339588D01*
X695721Y1339473D01*
X696186Y1339435D01*
X696651Y1339473D01*
X697064Y1339588D01*
X697374Y1339741D01*
X697633Y1339971D01*
X697736Y1340278D01*
X697633Y1340585D01*
X697374Y1340815D01*
X697064Y1340968D01*
X696651Y1341083D01*
X696186Y1341121D01*
X695721Y1341083D01*
X695308Y1340968D01*
X694998Y1340815D01*
X694739Y1340585D01*
X694636Y1340278D01*
G01X708812Y1320845D02*
X705812Y1317845D01*
G01X700588Y1320805D02*
X696461D01*
G01X703588Y1317805D02*
X700588Y1320805D01*
G01X705000Y1328592D02*
Y1367962D01*
G01X711342Y1328592D02*
X705000D01*
G01X700299Y1344270D02*
X697099D01*
G01X700299Y1350470D02*
Y1344270D01*
G01X697099Y1350470D02*
X700299D01*
G01X697099Y1344270D02*
Y1350470D01*
G01X702514Y1372825D02*
X708714D01*
G01X702514Y1369625D02*
Y1372825D01*
G01X708714Y1369625D02*
X702514D01*
G01X705000Y1367962D02*
X711342D01*
G01X704057Y1386146D02*
X707257D01*
G01X704057Y1379946D02*
Y1386146D01*
G01X707257Y1379946D02*
X704057D01*
G01X707257Y1386146D02*
Y1379946D01*
G01X707280Y1373125D02*
X704080D01*
G01X707280Y1379325D02*
Y1373125D01*
G01X704080Y1379325D02*
X707280D01*
G01X704080Y1373125D02*
Y1379325D01*
G01X707257Y1390446D02*
X704057D01*
G01X707257Y1396646D02*
Y1395200D01*
G01X704057Y1396646D02*
X707257D01*
G01X704057Y1390446D02*
Y1396646D01*
G01X707257Y1392500D02*
Y1390446D01*
G01X703261Y1390468D02*
X700061D01*
G01X703261Y1396668D02*
Y1390468D01*
G01X700061Y1396668D02*
X703261D01*
G01X700061Y1390468D02*
Y1396668D01*
G01X699331Y1390438D02*
X696131D01*
G01X699331Y1396638D02*
Y1390438D01*
G01X696131Y1396638D02*
X699331D01*
G01X696131Y1390438D02*
Y1396638D01*
G01X696981Y1406394D02*
Y1409494D01*
X697901D01*
X698208Y1409339D01*
X698438Y1408977D01*
X698515Y1408564D01*
X698438Y1408151D01*
X698246Y1407841D01*
X697901Y1407686D01*
X696981D01*
G01X700081Y1409494D02*
Y1406394D01*
X701615D01*
G01X703105Y1406859D02*
X703335Y1406601D01*
X703603Y1406446D01*
X703948Y1406394D01*
X704293Y1406497D01*
X704561Y1406704D01*
X704753Y1407066D01*
X704791Y1407479D01*
X704715Y1407892D01*
X704523Y1408151D01*
X704255Y1408357D01*
X703986Y1408409D01*
X703718Y1408357D01*
X703373Y1408151D01*
X703488Y1409494D01*
X704523D01*
G01X707508Y1406394D02*
Y1409494D01*
X706090Y1407272D01*
X708006D01*
G01X697140Y1411073D02*
Y1414173D01*
X698060D01*
X698367Y1414018D01*
X698597Y1413656D01*
X698674Y1413243D01*
X698597Y1412830D01*
X698405Y1412520D01*
X698060Y1412365D01*
X697140D01*
G01X700164Y1414173D02*
Y1411951D01*
X700317Y1411486D01*
X700624Y1411176D01*
X701007Y1411073D01*
X701390Y1411176D01*
X701697Y1411486D01*
X701850Y1411951D01*
Y1414173D01*
G01X704567Y1411073D02*
Y1414173D01*
X703149Y1411951D01*
X705065D01*
G01X707667Y1411073D02*
Y1414173D01*
X706249Y1411951D01*
X708165D01*
G01X706710Y1566123D02*
Y1562923D01*
G01X700510Y1566123D02*
X706710D01*
G01X700510Y1562923D02*
Y1566123D01*
G01X706710Y1562923D02*
X700510D01*
G01X700540Y1558973D02*
Y1562173D01*
G01X706740Y1558973D02*
X700540D01*
G01X706740Y1562173D02*
Y1558973D01*
G01X700540Y1562173D02*
X706740D01*
G01X706600Y1558100D02*
Y1554900D01*
G01X700400Y1558100D02*
X706600D01*
G01X700400Y1554900D02*
Y1558100D01*
G01X706600Y1554900D02*
X700400D01*
G01X706710Y1578123D02*
Y1574923D01*
G01X700510Y1578123D02*
X706710D01*
G01X700510Y1574923D02*
Y1578123D01*
G01X706710Y1574923D02*
X700510D01*
G01Y1574123D02*
X706710D01*
G01D02*
Y1570923D01*
G01X700510D02*
Y1574123D01*
G01X706710Y1570923D02*
X700510D01*
G01X706710Y1570123D02*
Y1566923D01*
G01X700510Y1570123D02*
X706710D01*
G01X700510Y1566923D02*
Y1570123D01*
G01X706710Y1566923D02*
X700510D01*
G01Y1578923D02*
Y1582123D01*
G01X706710Y1578923D02*
X700510D01*
G01X706710Y1582123D02*
Y1578923D01*
G01X700100Y1589400D02*
X696900D01*
G01X700100Y1595600D02*
Y1589400D01*
G01X696900Y1595600D02*
X700100D01*
G01X696900Y1589400D02*
Y1595600D01*
G01X706710Y1586123D02*
Y1582923D01*
G01X700510Y1586123D02*
X706710D01*
G01X700510Y1582923D02*
Y1586123D01*
G01X706710Y1582923D02*
X700510D01*
G01X706600Y1598100D02*
Y1594900D01*
G01X700400D02*
Y1598100D01*
G01X706600Y1594900D02*
X700400D01*
G01X706710Y1586923D02*
X700510D01*
G01X706710Y1590123D02*
Y1586923D01*
G01X700510Y1590123D02*
X706710D01*
G01X700510Y1586923D02*
Y1590123D01*
G01Y1582123D02*
X706710D01*
G01X700510Y1594123D02*
X706710D01*
G01D02*
Y1590923D01*
G01X700510D02*
Y1594123D01*
G01X706710Y1590923D02*
X700510D01*
G01X700400Y1598100D02*
X706600D01*
G01Y1606100D02*
Y1602900D01*
G01X700400Y1606100D02*
X706600D01*
G01X700400Y1602900D02*
Y1606100D01*
G01X706600Y1602900D02*
X700400D01*
G01Y1606900D02*
Y1610100D01*
G01X706600Y1606900D02*
X700400D01*
G01X706600Y1610100D02*
Y1606900D01*
G01X700400Y1610100D02*
X706600D01*
G01X700400Y1598900D02*
Y1602100D01*
G01X706600Y1598900D02*
X700400D01*
G01X706600Y1602100D02*
Y1598900D01*
G01X700400Y1602100D02*
X706600D01*
G01X703828Y1624662D02*
Y1621462D01*
G01X697628Y1624662D02*
X703828D01*
G01X697628Y1621462D02*
Y1624662D01*
G01X703828Y1621462D02*
X697628D01*
G01X707241Y1615056D02*
X701041D01*
G01D02*
Y1618256D01*
G01X707241D02*
Y1615056D01*
G01X701041Y1618256D02*
X707241D01*
G01X694430Y1626177D02*
Y1632377D01*
G01X697630D02*
Y1626177D01*
G01D02*
X694430D01*
G01X705399Y1632293D02*
Y1626093D01*
G01D02*
X702199D01*
G01D02*
Y1632293D01*
G01X698199Y1626093D02*
Y1632293D01*
G01X701399D02*
Y1626093D01*
G01D02*
X698199D01*
G01X694430Y1632377D02*
X697630D01*
G01X702199Y1632293D02*
X705399D01*
G01X698199D02*
X701399D01*
G01X698768Y1647663D02*
Y1639001D01*
G01X704088Y1652042D02*
X707288D01*
G01X704088Y1645842D02*
Y1652042D01*
G01X707288Y1645842D02*
X704088D01*
G01X707288Y1652042D02*
Y1645842D01*
G01X695421Y1647663D02*
X698768D01*
G01X693521Y1645463D02*
X695421Y1647663D01*
G01X693058Y1653813D02*
X695280D01*
X695745Y1653966D01*
X696055Y1654273D01*
X696158Y1654656D01*
X696055Y1655039D01*
X695745Y1655346D01*
X695280Y1655499D01*
X693058D01*
G01X696158Y1657756D02*
X693058D01*
X693678Y1657296D01*
G01X696158D02*
Y1658216D01*
G01Y1660856D02*
X696106Y1661124D01*
X695951Y1661431D01*
X695693Y1661623D01*
X695331Y1661699D01*
X694970Y1661623D01*
X694660Y1661393D01*
X694505Y1661048D01*
Y1660664D01*
X694401Y1660434D01*
X694143Y1660243D01*
X693781Y1660166D01*
X693420Y1660281D01*
X693161Y1660549D01*
X693058Y1660856D01*
X693161Y1661163D01*
X693420Y1661431D01*
X693781Y1661546D01*
X694143Y1661469D01*
X694401Y1661278D01*
X694505Y1661048D01*
Y1660664D01*
X694660Y1660319D01*
X694970Y1660089D01*
X695331Y1660013D01*
X695693Y1660089D01*
X695951Y1660281D01*
X696106Y1660588D01*
X696158Y1660856D01*
G01Y1663956D02*
X693058D01*
X693678Y1663496D01*
G01X696158D02*
Y1664416D01*
G01X705023Y1661476D02*
Y1667676D01*
G01X708223Y1661476D02*
X705023D01*
G01Y1667676D02*
X708223D01*
G01X695317Y1668808D02*
Y1672008D01*
G01X701517D02*
Y1668808D01*
G01D02*
X695317D01*
G01Y1672008D02*
X701517D01*
G01X695355Y1672829D02*
Y1676029D01*
G01D02*
X701555D01*
G01D02*
Y1672829D01*
G01D02*
X695355D01*
G01X695239Y1676874D02*
Y1680074D01*
G01D02*
X701439D01*
G01D02*
Y1676874D01*
G01D02*
X695239D01*
G01X701439Y1680396D02*
X695239D01*
G01D02*
Y1683596D01*
G01D02*
X701439D01*
G01D02*
Y1680396D01*
G01X717657Y76031D02*
X717849Y75721D01*
X718079Y75514D01*
X718347Y75411D01*
X718654Y75514D01*
X718884Y75721D01*
X719114Y76031D01*
X719191Y76444D01*
Y78511D01*
G01X721984Y75411D02*
Y78511D01*
X720566Y76289D01*
X722482D01*
G01X724624Y75411D02*
Y78511D01*
X724164Y77891D01*
G01Y75411D02*
X725084D01*
G01X711523Y104908D02*
Y101708D01*
G01X714933Y119135D02*
X715183Y118975D01*
X715308Y118788D01*
X715350Y118575D01*
X715267Y118308D01*
X715058Y118121D01*
X714808Y118068D01*
X714558Y118095D01*
X714350Y118201D01*
X713933Y118735D01*
X713642Y118975D01*
X713225Y119135D01*
X712850Y119188D01*
Y118068D01*
G01Y116428D02*
X715350D01*
X714850Y116748D01*
G01X712850D02*
Y116108D01*
G01X712017Y115028D02*
Y113428D01*
G01X714933Y112535D02*
X715183Y112375D01*
X715308Y112188D01*
X715350Y111975D01*
X715267Y111708D01*
X715058Y111521D01*
X714808Y111468D01*
X714558Y111495D01*
X714350Y111601D01*
X713933Y112135D01*
X713642Y112375D01*
X713225Y112535D01*
X712850Y112588D01*
Y111468D01*
G01X714933Y110335D02*
X715183Y110175D01*
X715308Y109988D01*
X715350Y109775D01*
X715267Y109508D01*
X715058Y109321D01*
X714808Y109268D01*
X714558Y109295D01*
X714350Y109401D01*
X713933Y109935D01*
X713642Y110175D01*
X713225Y110335D01*
X712850Y110388D01*
Y109268D01*
G01X709622Y107826D02*
Y110967D01*
G01Y116889D02*
Y120030D01*
G01D02*
X708449D01*
G01X708457Y107826D02*
X709622D01*
G01Y112978D02*
Y114878D01*
G01X722333Y133888D02*
Y140088D01*
G01X725533Y133888D02*
X722333D01*
G01X710553Y132768D02*
Y126568D01*
G01X713260Y129437D02*
Y132537D01*
X714180D01*
X714487Y132382D01*
X714717Y132020D01*
X714794Y131607D01*
X714717Y131194D01*
X714525Y130884D01*
X714180Y130729D01*
X713260D01*
G01X716284Y132537D02*
Y130315D01*
X716437Y129850D01*
X716744Y129540D01*
X717127Y129437D01*
X717510Y129540D01*
X717817Y129850D01*
X717970Y130315D01*
Y132537D01*
G01X719499Y132020D02*
X719729Y132330D01*
X719997Y132485D01*
X720304Y132537D01*
X720687Y132434D01*
X720955Y132175D01*
X721032Y131865D01*
X720994Y131555D01*
X720840Y131297D01*
X720074Y130780D01*
X719729Y130419D01*
X719499Y129902D01*
X719422Y129437D01*
X721032D01*
G01X722675Y129799D02*
X722944Y129540D01*
X723250Y129437D01*
X723557Y129540D01*
X723825Y129850D01*
X724017Y130315D01*
X724094Y130780D01*
Y131349D01*
X724017Y131814D01*
X723825Y132227D01*
X723595Y132434D01*
X723327Y132537D01*
X723020Y132434D01*
X722790Y132227D01*
X722637Y131917D01*
X722560Y131504D01*
X722637Y131142D01*
X722829Y130780D01*
X723059Y130574D01*
X723327Y130522D01*
X723634Y130625D01*
X723864Y130884D01*
X724094Y131349D01*
G01X725775Y129799D02*
X726044Y129540D01*
X726350Y129437D01*
X726657Y129540D01*
X726925Y129850D01*
X727117Y130315D01*
X727194Y130780D01*
Y131349D01*
X727117Y131814D01*
X726925Y132227D01*
X726695Y132434D01*
X726427Y132537D01*
X726120Y132434D01*
X725890Y132227D01*
X725737Y131917D01*
X725660Y131504D01*
X725737Y131142D01*
X725929Y130780D01*
X726159Y130574D01*
X726427Y130522D01*
X726734Y130625D01*
X726964Y130884D01*
X727194Y131349D01*
G01X722333Y140088D02*
X725533D01*
G01X708600Y159362D02*
X714800D01*
G01D02*
Y156162D01*
G01D02*
X708600D01*
G01D02*
Y159362D01*
G01X722629Y185144D02*
X721234D01*
X719529Y184377D01*
G01Y185911D02*
X721234Y185144D01*
G01Y187669D02*
Y188896D01*
X720872Y188781D01*
X720666Y188589D01*
X720562Y188321D01*
X720614Y188052D01*
X720769Y187822D01*
X721131Y187669D01*
X721441Y187592D01*
X721751D01*
X722061Y187669D01*
X722371Y187861D01*
X722577Y188091D01*
X722629Y188359D01*
X722526Y188627D01*
X722216Y188896D01*
G01X722629Y191344D02*
X719529D01*
G01X722629Y194444D02*
X719529D01*
G01X722629Y197544D02*
X722577Y197314D01*
X722371Y197084D01*
X722009Y196931D01*
X721596Y196854D01*
X721182Y196931D01*
X720821Y197084D01*
X720614Y197314D01*
X720562Y197544D01*
X720614Y197774D01*
X720821Y198004D01*
X721182Y198157D01*
X721596Y198196D01*
X722009Y198157D01*
X722371Y198004D01*
X722577Y197774D01*
X722629Y197544D01*
G01X720562Y199686D02*
X722629Y200146D01*
X720562Y200644D01*
X722629Y201142D01*
X720562Y201602D01*
G01X719529Y206077D02*
X722629D01*
Y207611D01*
G01X720562Y209944D02*
X722629D01*
G01X719736D02*
X719684Y209867D01*
X719581D01*
X719529Y209944D01*
X719581Y210021D01*
X719684D01*
X719736Y209944D01*
G01X723404Y212507D02*
X723611Y212776D01*
X723662Y213082D01*
X723611Y213351D01*
X723352Y213581D01*
X722991Y213734D01*
X720562D01*
G01X720976D02*
X720769Y213581D01*
X720614Y213351D01*
X720562Y213082D01*
X720666Y212776D01*
X720872Y212584D01*
X721234Y212431D01*
X721596Y212354D01*
X721906Y212392D01*
X722267Y212546D01*
X722526Y212776D01*
X722629Y213082D01*
X722577Y213312D01*
X722371Y213581D01*
X722164Y213734D01*
G01X722629Y215492D02*
X719529D01*
G01X721027D02*
X720769Y215684D01*
X720614Y215876D01*
X720562Y216182D01*
X720614Y216412D01*
X720821Y216681D01*
X721131Y216796D01*
X722629D01*
G01X719529Y219244D02*
X722629D01*
G01X720562Y218707D02*
Y219781D01*
G01X719529Y224677D02*
X722629D01*
Y226211D01*
G01Y229311D02*
Y227777D01*
X719529D01*
Y229311D01*
G01X721027Y228697D02*
Y227777D01*
G01X722629Y230801D02*
X719529D01*
Y231567D01*
X719684Y231874D01*
X719891Y232104D01*
X720201Y232296D01*
X720562Y232449D01*
X721079Y232487D01*
X721596Y232449D01*
X721957Y232296D01*
X722267Y232104D01*
X722474Y231874D01*
X722629Y231567D01*
Y230801D01*
G01X714821Y220262D02*
X708621D01*
G01D02*
Y223462D01*
G01D02*
X714821D01*
G01D02*
Y220262D01*
G01X721900Y361762D02*
Y367962D01*
G01D02*
X725100D01*
G01Y361762D02*
X721900D01*
G01X713795Y361752D02*
Y367952D01*
G01D02*
X716995D01*
G01D02*
Y361752D01*
G01D02*
X713795D01*
G01X709145Y367921D02*
Y361721D01*
G01X720934Y367962D02*
Y361762D01*
G01D02*
X717734D01*
G01D02*
Y367962D01*
G01D02*
X720934D01*
G01X713058Y367960D02*
Y361760D01*
G01D02*
X709858D01*
G01D02*
Y367960D01*
G01D02*
X713058D01*
G01X709900Y381462D02*
Y375262D01*
G01X710700D02*
Y381462D01*
G01D02*
X713900D01*
G01D02*
Y375262D01*
G01D02*
X710700D01*
G01X717900Y381462D02*
Y375262D01*
G01D02*
X714700D01*
G01D02*
Y381462D01*
G01D02*
X717900D01*
G01X718700Y375262D02*
Y381462D01*
G01D02*
X721900D01*
G01D02*
Y375262D01*
G01D02*
X718700D01*
G01X713900Y391762D02*
Y397962D01*
G01D02*
X717100D01*
G01D02*
Y391762D01*
G01D02*
X713900D01*
G01X709100Y397962D02*
Y391762D01*
G01X709900D02*
Y397962D01*
G01D02*
X713100D01*
G01D02*
Y391762D01*
G01D02*
X709900D01*
G01X721100Y397962D02*
Y391762D01*
G01D02*
X717900D01*
G01D02*
Y397962D01*
G01D02*
X721100D01*
G01X725100Y391762D02*
X721900D01*
G01D02*
Y397962D01*
G01D02*
X725100D01*
G01X718100Y512462D02*
Y506262D01*
G01D02*
X714900D01*
G01D02*
Y512462D01*
G01X722100D02*
Y506262D01*
G01D02*
X718900D01*
G01D02*
Y512462D01*
G01X714100D02*
Y506262D01*
G01D02*
X710900D01*
G01D02*
Y512462D01*
G01X710100D02*
Y506262D01*
G01X724632Y522715D02*
X721432D01*
G01D02*
Y528915D01*
G01X714900Y512462D02*
X718100D01*
G01X718900D02*
X722100D01*
G01X710900D02*
X714100D01*
G01X721118Y528931D02*
Y522731D01*
G01D02*
X717918D01*
G01D02*
Y528931D01*
G01X714084Y527651D02*
Y521451D01*
G01D02*
X710884D01*
G01D02*
Y527651D01*
G01X717616Y529025D02*
Y522825D01*
G01D02*
X714416D01*
G01D02*
Y529025D01*
G01X710109Y528445D02*
Y522245D01*
G01X721432Y528915D02*
X724632D01*
G01X717918Y528931D02*
X721118D01*
G01X710884Y527651D02*
X714084D01*
G01X714416Y529025D02*
X717616D01*
G01X718900Y548762D02*
Y554962D01*
G01X722100D02*
Y548762D01*
G01D02*
X718900D01*
G01Y538762D02*
Y544962D01*
G01D02*
X722100D01*
G01D02*
Y538762D01*
G01D02*
X718900D01*
G01X710100Y544962D02*
Y538762D01*
G01X708864Y547873D02*
Y554073D01*
G01X712064Y547873D02*
X708864D01*
G01X712064Y554073D02*
Y547873D01*
G01X718900Y554962D02*
X722100D01*
G01X708864Y554073D02*
X712064D01*
G01X709656Y582181D02*
Y575981D01*
G01X712550Y598300D02*
Y596078D01*
X712703Y595613D01*
X713010Y595303D01*
X713393Y595200D01*
X713776Y595303D01*
X714083Y595613D01*
X714236Y596078D01*
Y598300D01*
G01X715765Y597783D02*
X715995Y598093D01*
X716263Y598248D01*
X716570Y598300D01*
X716953Y598197D01*
X717221Y597938D01*
X717298Y597628D01*
X717260Y597318D01*
X717106Y597060D01*
X716340Y596543D01*
X715995Y596182D01*
X715765Y595665D01*
X715688Y595200D01*
X717298D01*
G01X719516D02*
X719593Y595872D01*
X719708Y596440D01*
X719861Y596957D01*
X720053Y597525D01*
X720360Y598300D01*
X718826D01*
G01X713445Y592317D02*
Y586117D01*
G01D02*
X710245D01*
G01D02*
Y592317D01*
G01D02*
X713445D01*
G01X713507Y607953D02*
Y601753D01*
G01D02*
X710307D01*
G01D02*
Y607953D01*
G01D02*
X713507D01*
G01X719187Y629231D02*
Y635431D01*
G01D02*
X722387D01*
G01D02*
Y629231D01*
G01D02*
X719187D01*
G01X715121Y629167D02*
Y635367D01*
G01D02*
X718321D01*
G01D02*
Y629167D01*
G01D02*
X715121D01*
G01X715072Y644597D02*
Y652737D01*
G01D02*
X725186D01*
G01Y644597D02*
X715072D01*
G01X710102Y647656D02*
Y653856D01*
G01D02*
X713302D01*
G01D02*
Y647656D01*
G01D02*
X710102D01*
G01X723729Y659567D02*
X720529D01*
G01D02*
Y665767D01*
G01D02*
X723729D01*
G01X719729D02*
Y659567D01*
G01D02*
X716529D01*
G01D02*
Y665767D01*
G01D02*
X719729D01*
G01X715729Y668917D02*
Y662717D01*
X712529D01*
Y668917D01*
X715729D01*
G01Y665767D02*
Y659567D01*
X712529D01*
Y665767D01*
X715729D01*
G01X720110Y683096D02*
X720302Y682786D01*
X720532Y682579D01*
X720800Y682476D01*
X721107Y682579D01*
X721337Y682786D01*
X721567Y683096D01*
X721644Y683509D01*
Y685576D01*
G01X723977Y682476D02*
Y685576D01*
X723517Y684956D01*
G01Y682476D02*
X724437D01*
G01X727077Y685576D02*
X726770Y685473D01*
X726540Y685214D01*
X726387Y684904D01*
X726272Y684491D01*
X726234Y684026D01*
X726272Y683561D01*
X726387Y683148D01*
X726540Y682838D01*
X726770Y682579D01*
X727077Y682476D01*
X727384Y682579D01*
X727614Y682838D01*
X727767Y683148D01*
X727882Y683561D01*
X727920Y684026D01*
X727882Y684491D01*
X727767Y684904D01*
X727614Y685214D01*
X727384Y685473D01*
X727077Y685576D01*
G01X730177D02*
X729870Y685473D01*
X729640Y685214D01*
X729487Y684904D01*
X729372Y684491D01*
X729334Y684026D01*
X729372Y683561D01*
X729487Y683148D01*
X729640Y682838D01*
X729870Y682579D01*
X730177Y682476D01*
X730484Y682579D01*
X730714Y682838D01*
X730867Y683148D01*
X730982Y683561D01*
X731020Y684026D01*
X730982Y684491D01*
X730867Y684904D01*
X730714Y685214D01*
X730484Y685473D01*
X730177Y685576D01*
G01X720339Y1299191D02*
X727466D01*
G01X724466Y1320845D02*
X720339D01*
G01X712939D02*
X708812D01*
G01X708714Y1372825D02*
Y1369625D01*
G01X710314Y1371242D02*
Y1373842D01*
G01X711107Y1371242D02*
X710314D01*
G01Y1380453D02*
Y1382151D01*
G01X711151Y1399077D02*
X707951D01*
G01X711151Y1405277D02*
Y1399077D01*
G01X707951D02*
Y1405277D01*
G01X718121Y1405171D02*
Y1401971D01*
G01X711921D02*
Y1405171D01*
G01X718121Y1401971D02*
X711921D01*
G01X724746Y1398077D02*
X721546D01*
G01D02*
Y1404277D01*
G01X710314Y1394864D02*
X711322D01*
G01X710314Y1393010D02*
Y1394864D01*
G01X707951Y1405277D02*
X711151D01*
G01X711921Y1405171D02*
X718121D01*
G01X721546Y1404277D02*
X724746D01*
G01X730392Y1414765D02*
X712676D01*
G01D02*
Y1418173D01*
G01X719383Y1433500D02*
Y1436600D01*
X720303D01*
X720610Y1436445D01*
X720840Y1436083D01*
X720917Y1435670D01*
X720840Y1435257D01*
X720648Y1434947D01*
X720303Y1434792D01*
X719383D01*
G01X722483Y1436600D02*
Y1433500D01*
X724017D01*
G01X725507Y1433965D02*
X725737Y1433707D01*
X726005Y1433552D01*
X726350Y1433500D01*
X726695Y1433603D01*
X726963Y1433810D01*
X727155Y1434172D01*
X727193Y1434585D01*
X727117Y1434998D01*
X726925Y1435257D01*
X726657Y1435463D01*
X726388Y1435515D01*
X726120Y1435463D01*
X725775Y1435257D01*
X725890Y1436600D01*
X726925D01*
G01X728722Y1434792D02*
X728990Y1435153D01*
X729220Y1435360D01*
X729527Y1435463D01*
X729795Y1435360D01*
X729987Y1435153D01*
X730140Y1434843D01*
X730178Y1434482D01*
X730140Y1434172D01*
X729987Y1433862D01*
X729757Y1433603D01*
X729488Y1433500D01*
X729182Y1433603D01*
X728913Y1433913D01*
X728760Y1434378D01*
X728722Y1434895D01*
X728798Y1435567D01*
X728913Y1435928D01*
X729105Y1436290D01*
X729373Y1436548D01*
X729642Y1436600D01*
X729910Y1436497D01*
X730102Y1436238D01*
G01X712676Y1432481D02*
X730392D01*
G01X712676Y1429073D02*
Y1432481D01*
G01X711817Y1434138D02*
X708617D01*
G01X711817Y1440338D02*
Y1434138D01*
G01X708617Y1440338D02*
X711817D01*
G01X708617Y1434138D02*
Y1440338D01*
G01X721850Y1567933D02*
Y1564733D01*
G01X715650D02*
Y1567933D01*
G01X721850Y1564733D02*
X715650D01*
G01X722650D02*
Y1567933D01*
G01X728850Y1564733D02*
X722650D01*
G01X715650Y1567933D02*
X721850D01*
G01X722650D02*
X728850D01*
G01X715397Y1592470D02*
Y1572252D01*
G01D02*
X743489D01*
G01Y1592470D02*
X715397D01*
G01X721450Y1604033D02*
X724650D01*
G01Y1597833D02*
X721450D01*
G01D02*
Y1604033D01*
G01X715510Y1604123D02*
X718710D01*
G01Y1597923D02*
X715510D01*
G01X718710Y1604123D02*
Y1597923D01*
G01X715510D02*
Y1604123D01*
G01X720752Y1625981D02*
X717552D01*
G01X720752Y1632181D02*
Y1625981D01*
G01X717552D02*
Y1632181D01*
G01X713552Y1625981D02*
Y1632181D01*
G01X716752D02*
Y1625981D01*
G01D02*
X713552D01*
G01X717552Y1632181D02*
X720752D01*
G01X713552D02*
X716752D01*
G01X710186Y1660393D02*
X715737Y1654842D01*
G01D02*
X710186Y1649291D01*
G01D02*
Y1646584D01*
G01D02*
X741288D01*
G01X708223Y1667676D02*
Y1661476D01*
G01X710186Y1663100D02*
Y1660393D01*
G01X741288Y1663100D02*
X710186D01*
G01X713709Y1681643D02*
X716909D01*
G01X713709Y1675443D02*
Y1681643D01*
G01X716909Y1675443D02*
X713709D01*
G01X716909Y1681643D02*
Y1675443D01*
G01X720309Y1685971D02*
X723509D01*
G01X720309Y1679771D02*
Y1685971D01*
G01X723509Y1679771D02*
X720309D01*
G01X726943Y-32011D02*
Y-15731D01*
X736543D01*
Y-32011D01*
X726943D01*
G01X727780Y73418D02*
Y79618D01*
G01X730980D02*
Y73418D01*
G01D02*
X727780D01*
G01X732780D02*
Y79618D01*
G01X735980D02*
Y73418D01*
G01D02*
X732780D01*
G01X738693Y86377D02*
X735493D01*
G01D02*
Y92577D01*
G01X734593Y92598D02*
Y89398D01*
G01D02*
X728393D01*
G01D02*
Y92598D01*
G01X734593Y85398D02*
X728393D01*
G01D02*
Y88598D01*
G01D02*
X734593D01*
G01D02*
Y85398D01*
G01X727780Y79618D02*
X730980D01*
G01X732780D02*
X735980D01*
G01X735060Y82308D02*
X737486D01*
G01X728423Y96758D02*
X734623D01*
G01D02*
Y93558D01*
G01D02*
X728423D01*
G01D02*
Y96758D01*
G01X735103Y103868D02*
X728903D01*
G01D02*
Y107068D01*
G01X735103D02*
Y103868D01*
G01Y100368D02*
X728903D01*
G01D02*
Y103568D01*
G01D02*
X735103D01*
G01D02*
Y100368D01*
G01X735493Y92577D02*
X738693D01*
G01X728393Y92598D02*
X734593D01*
G01X738940Y114135D02*
X735740D01*
G01D02*
Y120335D01*
G01D02*
X738940D01*
G01X742833Y109652D02*
X736633D01*
G01D02*
Y112852D01*
G01D02*
X742833D01*
G01X728903Y107068D02*
X735103D01*
G01X725533Y140088D02*
Y133888D01*
G01X741039Y126419D02*
X738613D01*
G01X727583Y188063D02*
X724483D01*
Y188983D01*
X724638Y189290D01*
X725000Y189520D01*
X725413Y189597D01*
X725826Y189520D01*
X726136Y189328D01*
X726291Y188983D01*
Y188063D01*
G01X727583Y191930D02*
X724483D01*
X725103Y191470D01*
G01X727583D02*
Y192390D01*
G01X725000Y194302D02*
X724690Y194532D01*
X724535Y194800D01*
X724483Y195107D01*
X724586Y195490D01*
X724845Y195758D01*
X725155Y195835D01*
X725465Y195797D01*
X725723Y195643D01*
X726240Y194877D01*
X726601Y194532D01*
X727118Y194302D01*
X727583Y194225D01*
Y195835D01*
G01X724483Y197172D02*
X727583Y198130D01*
X724483Y199088D01*
G01X728616Y200080D02*
Y202380D01*
G01X727170Y203525D02*
X727428Y203832D01*
X727583Y204177D01*
Y204483D01*
X727428Y204790D01*
X727170Y205020D01*
X726808Y205135D01*
X726446Y205058D01*
X726136Y204867D01*
X725930Y204522D01*
X725826Y204062D01*
X725620Y203793D01*
X725258Y203678D01*
X724896Y203755D01*
X724638Y203947D01*
X724483Y204215D01*
Y204483D01*
X724586Y204752D01*
X724845Y204982D01*
G01X724741Y208273D02*
X724586Y208043D01*
X724483Y207775D01*
Y207468D01*
X724638Y207123D01*
X724896Y206855D01*
X725206Y206663D01*
X725723Y206510D01*
X726188Y206472D01*
X726653Y206548D01*
X726963Y206663D01*
X727273Y206893D01*
X727480Y207162D01*
X727583Y207430D01*
Y207698D01*
X727480Y207967D01*
X727325Y208197D01*
X727118Y208388D01*
G01X727583Y209533D02*
X724483D01*
X727066Y210530D01*
X724483Y211527D01*
X727583D01*
G01X728616Y212480D02*
Y214780D01*
G01X727583Y216002D02*
X724483D01*
Y217458D01*
G01X725981Y216922D02*
Y216002D01*
G01X727583Y218872D02*
X724483Y219830D01*
X727583Y220788D01*
G01X726498Y220443D02*
Y219217D01*
G01X724483Y222087D02*
X726705D01*
X727170Y222240D01*
X727480Y222547D01*
X727583Y222930D01*
X727480Y223313D01*
X727170Y223620D01*
X726705Y223773D01*
X724483D01*
G01Y225263D02*
X727583D01*
Y226797D01*
G01X724483Y229130D02*
X727583D01*
G01X724483Y228248D02*
Y230012D01*
G01X728616Y231080D02*
Y233380D01*
G01X727583Y234563D02*
X724483D01*
Y235522D01*
X724638Y235828D01*
X724845Y236020D01*
X725258Y236097D01*
X725671Y236020D01*
X725930Y235790D01*
X726085Y235522D01*
Y234563D01*
G01Y235522D02*
X727583Y236097D01*
G01X728616Y237280D02*
Y239580D01*
G01X727583Y240648D02*
X724483D01*
X727583Y242412D01*
X724483D01*
G01X737049Y376628D02*
Y370428D01*
G01D02*
X733849D01*
G01D02*
Y376628D01*
G01X729900Y361762D02*
Y367962D01*
G01D02*
X733100D01*
G01D02*
Y361762D01*
G01D02*
X729900D01*
G01X725100Y367962D02*
Y361762D01*
G01X733849Y376628D02*
X737049D01*
G01X733006Y381431D02*
Y375231D01*
G01D02*
X729806D01*
G01D02*
Y381431D01*
G01D02*
X733006D01*
G01X725964Y375262D02*
Y381462D01*
G01D02*
X729164D01*
G01D02*
Y375262D01*
G01D02*
X725964D01*
G01X733900Y391762D02*
Y397962D01*
G01D02*
X737100D01*
G01D02*
Y391762D01*
G01D02*
X733900D01*
G01X733100Y397962D02*
Y391762D01*
G01D02*
X729900D01*
G01D02*
Y397962D01*
G01D02*
X733100D01*
G01X729100D02*
Y391762D01*
G01D02*
X725900D01*
G01D02*
Y397962D01*
G01D02*
X729100D01*
G01X725100D02*
Y391762D01*
G01X730900Y506262D02*
Y512462D01*
G01X734100D02*
Y506262D01*
G01D02*
X730900D01*
G01X726900D02*
Y512462D01*
G01X730100D02*
Y506262D01*
G01D02*
X726900D01*
G01X734900D02*
Y512462D01*
G01X738100Y506262D02*
X734900D01*
G01X726100Y512462D02*
Y506262D01*
G01D02*
X722900D01*
G01D02*
Y512462D01*
G01X730900D02*
X734100D01*
G01X726900D02*
X730100D01*
G01X734900D02*
X738100D01*
G01X731910Y528883D02*
Y522683D01*
G01D02*
X728710D01*
G01D02*
Y528883D01*
G01X724632Y528915D02*
Y522715D01*
G01X735411Y528837D02*
Y522637D01*
G01D02*
X732211D01*
G01D02*
Y528837D01*
G01X722900Y512462D02*
X726100D01*
G01X725193Y522749D02*
Y528949D01*
G01X728393Y522749D02*
X725193D01*
G01X728393Y528949D02*
Y522749D01*
G01X735724Y522403D02*
Y528603D01*
G01X738924Y522403D02*
X735724D01*
G01X728710Y528883D02*
X731910D01*
G01X732211Y528837D02*
X735411D01*
G01X725193Y528949D02*
X728393D01*
G01X735724Y528603D02*
X738924D01*
G01X726900Y538762D02*
Y544962D01*
G01D02*
X730100D01*
G01D02*
Y538762D01*
G01D02*
X726900D01*
G01X734900D02*
Y544962D01*
G01D02*
X738100D01*
G01Y538762D02*
X734900D01*
G01X726100Y544962D02*
Y538762D01*
G01D02*
X722900D01*
G01D02*
Y544962D01*
G01D02*
X726100D01*
G01X734100Y538900D02*
X730900D01*
G01X734100Y545100D02*
Y538900D01*
G01X730900Y545100D02*
X734100D01*
G01X730900Y538900D02*
Y545100D01*
G01X730326Y645096D02*
X732548D01*
X733013Y645249D01*
X733323Y645556D01*
X733426Y645939D01*
X733323Y646322D01*
X733013Y646629D01*
X732548Y646782D01*
X730326D01*
G01X733426Y649039D02*
X730326D01*
X730946Y648579D01*
G01X733426D02*
Y649499D01*
G01X730326Y652139D02*
X730429Y651832D01*
X730688Y651602D01*
X730998Y651449D01*
X731411Y651334D01*
X731876Y651296D01*
X732341Y651334D01*
X732754Y651449D01*
X733064Y651602D01*
X733323Y651832D01*
X733426Y652139D01*
X733323Y652446D01*
X733064Y652676D01*
X732754Y652829D01*
X732341Y652944D01*
X731876Y652982D01*
X731411Y652944D01*
X730998Y652829D01*
X730688Y652676D01*
X730429Y652446D01*
X730326Y652139D01*
G01X733426Y655239D02*
X733374Y655507D01*
X733219Y655814D01*
X732961Y656006D01*
X732599Y656082D01*
X732238Y656006D01*
X731928Y655776D01*
X731773Y655431D01*
Y655047D01*
X731669Y654817D01*
X731411Y654626D01*
X731049Y654549D01*
X730688Y654664D01*
X730429Y654932D01*
X730326Y655239D01*
X730429Y655546D01*
X730688Y655814D01*
X731049Y655929D01*
X731411Y655852D01*
X731669Y655661D01*
X731773Y655431D01*
Y655047D01*
X731928Y654702D01*
X732238Y654472D01*
X732599Y654396D01*
X732961Y654472D01*
X733219Y654664D01*
X733374Y654971D01*
X733426Y655239D01*
G01X725186Y652737D02*
Y644597D01*
G01X723729Y665767D02*
Y659567D01*
G01X727801Y668919D02*
Y662719D01*
X724601D01*
Y668919D01*
X727801D01*
G01Y665769D02*
Y659569D01*
X724601D01*
Y665769D01*
X727801D01*
G01X731733Y687245D02*
Y1297200D01*
G01X757323Y687245D02*
X731733D01*
G01X727622Y1297200D02*
Y687245D01*
G01X757323Y720710D02*
X731733D01*
G01X757323Y1291576D02*
X731733D01*
G01X727466Y1299191D02*
Y1317845D01*
G01X729812Y1299191D02*
X736939D01*
G01X729812Y1317845D02*
Y1299191D01*
G01X731733Y1325041D02*
X757323D01*
G01X731733Y1323400D02*
Y1325041D01*
G01X727622D02*
Y1323400D01*
G01X727466Y1317845D02*
X724466Y1320845D01*
G01X732812D02*
X729812Y1317845D01*
G01X736939Y1320845D02*
X732812D01*
G01X735314Y1328592D02*
X728972D01*
G01X735314Y1367962D02*
Y1328592D01*
G01X735296Y1372925D02*
X741496D01*
G01X735296Y1369725D02*
Y1372925D01*
G01X741496Y1369725D02*
X735296D01*
G01X728972Y1367962D02*
X735314D01*
G01X730000Y1371242D02*
X729207D01*
G01X730000Y1373842D02*
Y1371242D01*
G01X732957Y1386501D02*
X736157D01*
G01X732957Y1380301D02*
Y1386501D01*
G01X736157Y1380301D02*
X732957D01*
G01X736157Y1386501D02*
Y1380301D01*
G01X736839Y1386246D02*
X740039D01*
G01X736839Y1380046D02*
Y1386246D01*
G01X740039Y1380046D02*
X736839D01*
G01X740062Y1373225D02*
X736862D01*
G01Y1379425D02*
X740062D01*
G01X736862Y1373225D02*
Y1379425D01*
G01X725588Y1398077D02*
Y1404277D01*
G01X728788Y1398077D02*
X725588D01*
G01X728788Y1404277D02*
Y1398077D01*
G01X733555Y1398814D02*
Y1402014D01*
G01X739755Y1398814D02*
X733555D01*
G01Y1402014D02*
X739755D01*
G01X740039Y1390546D02*
X736839D01*
G01Y1396746D02*
X740039D01*
G01X736839Y1390546D02*
Y1396746D01*
G01X724746Y1404277D02*
Y1398077D01*
G01X730000Y1394864D02*
Y1392673D01*
G01X729267Y1394864D02*
X730000D01*
G01X725588Y1404277D02*
X728788D01*
G01X730392Y1418173D02*
Y1414765D01*
G01Y1432481D02*
Y1429073D01*
G01X728850Y1567933D02*
Y1564733D01*
G01X724650Y1604033D02*
Y1597833D01*
G01X729961Y1612343D02*
Y1609143D01*
G01X723761D02*
Y1612343D01*
G01X729961Y1609143D02*
X723761D01*
G01X729850Y1608333D02*
Y1605133D01*
G01X723650Y1608333D02*
X729850D01*
G01X723650Y1605133D02*
Y1608333D01*
G01X729850Y1605133D02*
X723650D01*
G01X723761Y1612343D02*
X729961D01*
G01X726323Y1631620D02*
Y1625420D01*
G01D02*
X723123D01*
G01D02*
Y1631620D01*
G01X734323Y1625420D02*
X731123D01*
G01X734323Y1631620D02*
Y1625420D01*
G01X731123D02*
Y1631620D01*
G01X738323Y1625420D02*
X735123D01*
G01D02*
Y1631620D01*
G01X730323Y1625420D02*
X727123D01*
G01X730323Y1631620D02*
Y1625420D01*
G01X727123D02*
Y1631620D01*
G01X723761Y1616343D02*
X729961D01*
Y1613143D01*
X723761D01*
Y1616343D01*
G01X723123Y1631620D02*
X726323D01*
G01X731123D02*
X734323D01*
G01X735123D02*
X738323D01*
G01X727123D02*
X730323D01*
G01X728016Y1681861D02*
X731216D01*
G01D02*
Y1675661D01*
G01D02*
X728016D01*
G01D02*
Y1681861D01*
G01X724032Y1681860D02*
X727232D01*
G01D02*
Y1675660D01*
G01D02*
X724032D01*
G01D02*
Y1681860D01*
G01X739068Y1685603D02*
X735868D01*
G01D02*
Y1691803D01*
G01X734034Y1683573D02*
X730834D01*
G01X734034Y1689773D02*
Y1683573D01*
G01X730834D02*
Y1689773D01*
G01X730054Y1683404D02*
X726854D01*
G01X730054Y1689604D02*
Y1683404D01*
G01X726854D02*
Y1689604D01*
G01X735867Y1685207D02*
X739067D01*
G01Y1679007D02*
X735867D01*
G01D02*
Y1685207D01*
G01X723509Y1685971D02*
Y1679771D01*
G01X733493Y1694566D02*
X728493D01*
G01Y1697226D02*
X733493D01*
G01X730993D02*
Y1694566D01*
G01X732826Y1699666D02*
X733243Y1700173D01*
X733493Y1700743D01*
Y1701249D01*
X733243Y1701756D01*
X732826Y1702136D01*
X732243Y1702326D01*
X731660Y1702199D01*
X731160Y1701883D01*
X730826Y1701313D01*
X730660Y1700553D01*
X730326Y1700109D01*
X729743Y1699919D01*
X729160Y1700046D01*
X728743Y1700363D01*
X728493Y1700806D01*
Y1701249D01*
X728660Y1701693D01*
X729076Y1702073D01*
G01X728910Y1707489D02*
X728660Y1707109D01*
X728493Y1706666D01*
Y1706159D01*
X728743Y1705589D01*
X729160Y1705146D01*
X729660Y1704829D01*
X730493Y1704576D01*
X731243Y1704513D01*
X731993Y1704639D01*
X732493Y1704829D01*
X732993Y1705209D01*
X733326Y1705653D01*
X733493Y1706096D01*
Y1706539D01*
X733326Y1706983D01*
X733076Y1707363D01*
X732743Y1707679D01*
G01X733493Y1715029D02*
X728493D01*
Y1716549D01*
X728743Y1717056D01*
X729326Y1717436D01*
X729993Y1717563D01*
X730660Y1717436D01*
X731160Y1717119D01*
X731410Y1716549D01*
Y1715029D01*
G01X733493Y1719749D02*
X728493D01*
X732660Y1721396D01*
X728493Y1723043D01*
X733493D01*
G01X730826Y1727003D02*
X730576Y1727256D01*
X730160Y1727446D01*
X729576Y1727573D01*
X729076Y1727446D01*
X728743Y1727193D01*
X728493Y1726749D01*
Y1725039D01*
X733493D01*
Y1727129D01*
X733160Y1727573D01*
X732660Y1727826D01*
X732076Y1727953D01*
X731493Y1727826D01*
X730993Y1727446D01*
X730826Y1727003D01*
Y1725039D01*
G01X728493Y1730203D02*
X732076D01*
X732826Y1730456D01*
X733326Y1730963D01*
X733493Y1731596D01*
X733326Y1732229D01*
X732826Y1732736D01*
X732076Y1732989D01*
X728493D01*
G01X732826Y1735366D02*
X733243Y1735873D01*
X733493Y1736443D01*
Y1736949D01*
X733243Y1737456D01*
X732826Y1737836D01*
X732243Y1738026D01*
X731660Y1737899D01*
X731160Y1737583D01*
X730826Y1737013D01*
X730660Y1736253D01*
X730326Y1735809D01*
X729743Y1735619D01*
X729160Y1735746D01*
X728743Y1736063D01*
X728493Y1736506D01*
Y1736949D01*
X728660Y1737393D01*
X729076Y1737773D01*
G01X735868Y1691803D02*
X739068D01*
G01X730834Y1689773D02*
X734034D01*
G01X726854Y1689604D02*
X730054D01*
G01X750127Y-27825D02*
X750437Y-27633D01*
X750644Y-27403D01*
X750747Y-27135D01*
X750644Y-26828D01*
X750437Y-26598D01*
X750127Y-26368D01*
X749714Y-26291D01*
X747647D01*
G01X750747Y-23958D02*
X750695Y-23690D01*
X750540Y-23383D01*
X750282Y-23191D01*
X749920Y-23115D01*
X749559Y-23191D01*
X749249Y-23421D01*
X749094Y-23766D01*
Y-24150D01*
X748990Y-24380D01*
X748732Y-24571D01*
X748370Y-24648D01*
X748009Y-24533D01*
X747750Y-24265D01*
X747647Y-23958D01*
X747750Y-23651D01*
X748009Y-23383D01*
X748370Y-23268D01*
X748732Y-23345D01*
X748990Y-23536D01*
X749094Y-23766D01*
Y-24150D01*
X749249Y-24495D01*
X749559Y-24725D01*
X749920Y-24801D01*
X750282Y-24725D01*
X750540Y-24533D01*
X750695Y-24226D01*
X750747Y-23958D01*
G01X750127Y-21701D02*
X750489Y-21471D01*
X750695Y-21165D01*
X750747Y-20820D01*
X750695Y-20513D01*
X750437Y-20206D01*
X750127Y-20015D01*
X749817Y-19976D01*
X749455Y-20053D01*
X749197Y-20321D01*
X749094Y-20590D01*
Y-20935D01*
G01Y-20590D02*
X748939Y-20360D01*
X748680Y-20168D01*
X748370Y-20091D01*
X748060Y-20168D01*
X747802Y-20360D01*
X747647Y-20705D01*
X747699Y-21050D01*
X747905Y-21395D01*
G01X768529Y73490D02*
X738970D01*
G01D02*
Y84986D01*
G01X738693Y92577D02*
Y86377D01*
G01X738970Y84986D02*
X768529D01*
G01X753991Y105052D02*
X740015D01*
G01D02*
Y96864D01*
G01D02*
X753991D01*
G01X756233Y113688D02*
X750033D01*
G01D02*
Y116888D01*
G01D02*
X756233D01*
G01X750033Y112888D02*
X756233D01*
G01Y109688D02*
X750033D01*
G01D02*
Y112888D01*
G01X738940Y120335D02*
Y114135D01*
G01X742833Y112852D02*
Y109652D01*
G01X756235Y117572D02*
X750035D01*
G01D02*
Y120772D01*
G01X742870Y120259D02*
Y114059D01*
G01D02*
X739670D01*
G01D02*
Y120259D01*
G01D02*
X742870D01*
G01X750035Y120772D02*
X756235D01*
G01X744147Y131608D02*
Y134708D01*
X745067D01*
X745374Y134553D01*
X745604Y134191D01*
X745681Y133778D01*
X745604Y133365D01*
X745412Y133055D01*
X745067Y132900D01*
X744147D01*
G01X747171Y131608D02*
Y134708D01*
X747937D01*
X748244Y134553D01*
X748474Y134346D01*
X748666Y134036D01*
X748819Y133675D01*
X748857Y133158D01*
X748819Y132641D01*
X748666Y132280D01*
X748474Y131970D01*
X748244Y131763D01*
X747937Y131608D01*
X747171D01*
G01X751114D02*
Y134708D01*
X750654Y134088D01*
G01Y131608D02*
X751574D01*
G01X754214D02*
Y134708D01*
X753754Y134088D01*
G01Y131608D02*
X754674D01*
G01X756471Y132073D02*
X756701Y131815D01*
X756969Y131660D01*
X757314Y131608D01*
X757659Y131711D01*
X757927Y131918D01*
X758119Y132280D01*
X758157Y132693D01*
X758081Y133106D01*
X757889Y133365D01*
X757621Y133571D01*
X757352Y133623D01*
X757084Y133571D01*
X756739Y133365D01*
X756854Y134708D01*
X757889D01*
G01X761085Y130356D02*
X741867D01*
G01D02*
Y122482D01*
G01D02*
X761085D01*
G01X750726Y126219D02*
X753726Y127719D01*
G01Y124719D02*
X750726Y126219D01*
G01D02*
X749726D01*
G01X750726Y124719D02*
Y127719D01*
G01X744135Y143650D02*
X750335D01*
G01D02*
Y140450D01*
G01D02*
X744135D01*
G01D02*
Y143650D01*
G01X750345Y136264D02*
X744145D01*
G01D02*
Y139464D01*
G01D02*
X750345D01*
G01D02*
Y136264D01*
G01X752835Y159863D02*
X746635D01*
G01D02*
Y163063D01*
G01D02*
X752835D01*
G01X746600Y169137D02*
X752800D01*
G01Y165937D02*
X746600D01*
G01D02*
Y169137D01*
G01X746900Y177100D02*
X753100D01*
G01X746900Y173900D02*
Y177100D01*
G01X753100Y173900D02*
X746900D01*
G01X742523Y191181D02*
X739423D01*
Y191947D01*
X739578Y192254D01*
X739785Y192484D01*
X740095Y192676D01*
X740456Y192829D01*
X740973Y192867D01*
X741490Y192829D01*
X741851Y192676D01*
X742161Y192484D01*
X742368Y192254D01*
X742523Y191947D01*
Y191181D01*
G01Y195124D02*
X742471Y195392D01*
X742316Y195699D01*
X742058Y195891D01*
X741696Y195967D01*
X741335Y195891D01*
X741025Y195661D01*
X740870Y195316D01*
Y194932D01*
X740766Y194702D01*
X740508Y194511D01*
X740146Y194434D01*
X739785Y194549D01*
X739526Y194817D01*
X739423Y195124D01*
X739526Y195431D01*
X739785Y195699D01*
X740146Y195814D01*
X740508Y195737D01*
X740766Y195546D01*
X740870Y195316D01*
Y194932D01*
X741025Y194587D01*
X741335Y194357D01*
X741696Y194281D01*
X742058Y194357D01*
X742316Y194549D01*
X742471Y194856D01*
X742523Y195124D01*
G01X739423Y198224D02*
X739526Y197917D01*
X739785Y197687D01*
X740095Y197534D01*
X740508Y197419D01*
X740973Y197381D01*
X741438Y197419D01*
X741851Y197534D01*
X742161Y197687D01*
X742420Y197917D01*
X742523Y198224D01*
X742420Y198531D01*
X742161Y198761D01*
X741851Y198914D01*
X741438Y199029D01*
X740973Y199067D01*
X740508Y199029D01*
X740095Y198914D01*
X739785Y198761D01*
X739526Y198531D01*
X739423Y198224D01*
G01Y201324D02*
X739526Y201017D01*
X739785Y200787D01*
X740095Y200634D01*
X740508Y200519D01*
X740973Y200481D01*
X741438Y200519D01*
X741851Y200634D01*
X742161Y200787D01*
X742420Y201017D01*
X742523Y201324D01*
X742420Y201631D01*
X742161Y201861D01*
X741851Y202014D01*
X741438Y202129D01*
X740973Y202167D01*
X740508Y202129D01*
X740095Y202014D01*
X739785Y201861D01*
X739526Y201631D01*
X739423Y201324D01*
G01X739940Y203696D02*
X739630Y203926D01*
X739475Y204194D01*
X739423Y204501D01*
X739526Y204884D01*
X739785Y205152D01*
X740095Y205229D01*
X740405Y205191D01*
X740663Y205037D01*
X741180Y204271D01*
X741541Y203926D01*
X742058Y203696D01*
X742523Y203619D01*
Y205229D01*
G01X753500Y190973D02*
Y193213D01*
G01X751875Y192000D02*
X755125D01*
G01X755700Y194300D02*
X751300D01*
G01D02*
Y204700D01*
G01X747100Y197900D02*
X743900D01*
G01X747100Y204100D02*
Y197900D01*
G01X743900Y204100D02*
X747100D01*
G01X743900Y197900D02*
Y204100D01*
G01X756715Y207902D02*
Y210328D01*
G01X751300Y206500D02*
Y204700D01*
G01Y206500D02*
X755700D01*
G01Y205900D02*
X751300D01*
G01Y205300D02*
X755700D01*
G01X751300Y204700D02*
X755700D01*
G01X755331Y211253D02*
X746669D01*
G01Y221747D02*
X755331D01*
G01X746669Y218400D02*
Y221747D01*
G01X748869Y216500D02*
X746669Y218400D01*
G01Y214600D02*
X748869Y216500D01*
G01X746669Y211253D02*
Y214600D01*
G01X741100Y381462D02*
Y375262D01*
G01D02*
X737900D01*
G01D02*
Y381462D01*
G01D02*
X741100D01*
G01X745100D02*
Y375262D01*
G01D02*
X741900D01*
G01D02*
Y381462D01*
G01D02*
X745100D01*
G01X745900Y375262D02*
Y381462D01*
G01D02*
X749100D01*
G01D02*
Y375262D01*
G01D02*
X745900D01*
G01X741900Y391762D02*
Y397962D01*
G01D02*
X745100D01*
G01D02*
Y391762D01*
G01D02*
X741900D01*
G01X745900D02*
Y397962D01*
G01D02*
X749100D01*
G01D02*
Y391762D01*
G01D02*
X745900D01*
G01X749900D02*
Y397962D01*
G01D02*
X753100D01*
G01Y391762D02*
X749900D01*
G01X738052Y391744D02*
Y397944D01*
X741252D01*
Y391744D01*
X738052D01*
G01X742900Y506262D02*
Y512462D01*
G01X746100D02*
Y506262D01*
G01D02*
X742900D01*
G01X750900D02*
Y512462D01*
G01X754100Y506262D02*
X750900D01*
G01X746900D02*
Y512462D01*
G01X750100D02*
Y506262D01*
G01D02*
X746900D01*
G01X738100Y512462D02*
Y506262D01*
G01X742495Y528981D02*
Y522781D01*
G01X739295D02*
Y528981D01*
G01X742495Y522781D02*
X739295D01*
G01X742900Y512462D02*
X746100D01*
G01X750900D02*
X754100D01*
G01X746900D02*
X750100D01*
G01X746900Y522762D02*
Y528962D01*
G01X750100D02*
Y522762D01*
G01D02*
X746900D01*
G01X750900D02*
Y528962D01*
G01X754100Y522762D02*
X750900D01*
G01X742900D02*
Y528962D01*
G01X746100D02*
Y522762D01*
G01D02*
X742900D01*
G01X738924Y528603D02*
Y522403D01*
G01X739295Y528981D02*
X742495D01*
G01X746900Y528962D02*
X750100D01*
G01X750900D02*
X754100D01*
G01X742900D02*
X746100D01*
G01X738100Y544962D02*
Y538762D01*
G01X750100Y544962D02*
Y538762D01*
G01D02*
X746900D01*
G01D02*
Y544962D01*
G01D02*
X750100D01*
G01X750900Y538762D02*
Y544962D01*
G01D02*
X754100D01*
G01Y538762D02*
X750900D01*
G01X742100Y544962D02*
Y538762D01*
G01D02*
X738900D01*
G01D02*
Y544962D01*
G01D02*
X742100D01*
G01X786502Y605413D02*
G02I-22900J0D01*
G01X751361Y683096D02*
X751553Y682786D01*
X751783Y682579D01*
X752051Y682476D01*
X752358Y682579D01*
X752588Y682786D01*
X752818Y683096D01*
X752895Y683509D01*
Y685576D01*
G01X754500Y685059D02*
X754730Y685369D01*
X754998Y685524D01*
X755305Y685576D01*
X755688Y685473D01*
X755956Y685214D01*
X756033Y684904D01*
X755995Y684594D01*
X755841Y684336D01*
X755075Y683819D01*
X754730Y683458D01*
X754500Y682941D01*
X754423Y682476D01*
X756033D01*
G01X757676Y682838D02*
X757945Y682579D01*
X758251Y682476D01*
X758558Y682579D01*
X758826Y682889D01*
X759018Y683354D01*
X759095Y683819D01*
Y684388D01*
X759018Y684853D01*
X758826Y685266D01*
X758596Y685473D01*
X758328Y685576D01*
X758021Y685473D01*
X757791Y685266D01*
X757638Y684956D01*
X757561Y684543D01*
X757638Y684181D01*
X757830Y683819D01*
X758060Y683613D01*
X758328Y683561D01*
X758635Y683664D01*
X758865Y683923D01*
X759095Y684388D01*
G01X751466Y1299191D02*
Y1317845D01*
G01X744339Y1299191D02*
X751466D01*
G01X748466Y1320845D02*
X744339D01*
G01X751466Y1317845D02*
X748466Y1320845D01*
G01X737782Y1328692D02*
Y1368062D01*
G01X744124Y1328692D02*
X737782D01*
G01X741496Y1372925D02*
Y1369725D01*
G01X737782Y1368062D02*
X744124D01*
G01X743096Y1371342D02*
Y1373942D01*
G01X743889Y1371342D02*
X743096D01*
G01X740039Y1386246D02*
Y1380046D01*
G01X740062Y1379425D02*
Y1373225D01*
G01X743096Y1380553D02*
Y1382251D01*
G01X739755Y1402014D02*
Y1398814D01*
G01X740039Y1396746D02*
Y1395400D01*
G01Y1392500D02*
Y1390546D01*
G01X743933Y1399177D02*
X740733D01*
G01X743933Y1405377D02*
Y1399177D01*
G01X740733D02*
Y1405377D01*
G01X750903Y1405271D02*
Y1402071D01*
G01X744703D02*
Y1405271D01*
G01X750903Y1402071D02*
X744703D01*
G01X743096Y1394964D02*
X744104D01*
G01X743096Y1393110D02*
Y1394964D01*
G01X740733Y1405377D02*
X743933D01*
G01X744703Y1405271D02*
X750903D01*
G01X741321Y1408096D02*
Y1411196D01*
X742241D01*
X742548Y1411041D01*
X742778Y1410679D01*
X742855Y1410266D01*
X742778Y1409853D01*
X742586Y1409543D01*
X742241Y1409388D01*
X741321D01*
G01X744421Y1411196D02*
Y1408096D01*
X745955D01*
G01X747445Y1408561D02*
X747675Y1408303D01*
X747943Y1408148D01*
X748288Y1408096D01*
X748633Y1408199D01*
X748901Y1408406D01*
X749093Y1408768D01*
X749131Y1409181D01*
X749055Y1409594D01*
X748863Y1409853D01*
X748595Y1410059D01*
X748326Y1410111D01*
X748058Y1410059D01*
X747713Y1409853D01*
X747828Y1411196D01*
X748863D01*
G01X750545Y1408561D02*
X750775Y1408303D01*
X751043Y1408148D01*
X751388Y1408096D01*
X751733Y1408199D01*
X752001Y1408406D01*
X752193Y1408768D01*
X752231Y1409181D01*
X752155Y1409594D01*
X751963Y1409853D01*
X751695Y1410059D01*
X751426Y1410111D01*
X751158Y1410059D01*
X750813Y1409853D01*
X750928Y1411196D01*
X751963D01*
G01X741383Y1413000D02*
Y1416100D01*
X742303D01*
X742610Y1415945D01*
X742840Y1415583D01*
X742917Y1415170D01*
X742840Y1414757D01*
X742648Y1414447D01*
X742303Y1414292D01*
X741383D01*
G01X744407Y1416100D02*
Y1413878D01*
X744560Y1413413D01*
X744867Y1413103D01*
X745250Y1413000D01*
X745633Y1413103D01*
X745940Y1413413D01*
X746093Y1413878D01*
Y1416100D01*
G01X748810Y1413000D02*
Y1416100D01*
X747392Y1413878D01*
X749308D01*
G01X750607Y1413465D02*
X750837Y1413207D01*
X751105Y1413052D01*
X751450Y1413000D01*
X751795Y1413103D01*
X752063Y1413310D01*
X752255Y1413672D01*
X752293Y1414085D01*
X752217Y1414498D01*
X752025Y1414757D01*
X751757Y1414963D01*
X751488Y1415015D01*
X751220Y1414963D01*
X750875Y1414757D01*
X750990Y1416100D01*
X752025D01*
G01X768031Y1431813D02*
X741259D01*
G01X768031D02*
G02I-13386J0D01*
G01X754441Y1527298D02*
X751341D01*
Y1528218D01*
X751496Y1528525D01*
X751858Y1528755D01*
X752271Y1528832D01*
X752684Y1528755D01*
X752994Y1528563D01*
X753149Y1528218D01*
Y1527298D01*
G01X753821Y1530398D02*
X754131Y1530590D01*
X754338Y1530820D01*
X754441Y1531088D01*
X754338Y1531395D01*
X754131Y1531625D01*
X753821Y1531855D01*
X753408Y1531932D01*
X751341D01*
G01X753821Y1533422D02*
X754183Y1533652D01*
X754389Y1533958D01*
X754441Y1534303D01*
X754389Y1534610D01*
X754131Y1534917D01*
X753821Y1535108D01*
X753511Y1535147D01*
X753149Y1535070D01*
X752891Y1534802D01*
X752788Y1534533D01*
Y1534188D01*
G01Y1534533D02*
X752633Y1534763D01*
X752374Y1534955D01*
X752064Y1535032D01*
X751754Y1534955D01*
X751496Y1534763D01*
X751341Y1534418D01*
X751393Y1534073D01*
X751599Y1533728D01*
G01X754441Y1537365D02*
X754389Y1537633D01*
X754234Y1537940D01*
X753976Y1538132D01*
X753614Y1538208D01*
X753253Y1538132D01*
X752943Y1537902D01*
X752788Y1537557D01*
Y1537173D01*
X752684Y1536943D01*
X752426Y1536752D01*
X752064Y1536675D01*
X751703Y1536790D01*
X751444Y1537058D01*
X751341Y1537365D01*
X751444Y1537672D01*
X751703Y1537940D01*
X752064Y1538055D01*
X752426Y1537978D01*
X752684Y1537787D01*
X752788Y1537557D01*
Y1537173D01*
X752943Y1536828D01*
X753253Y1536598D01*
X753614Y1536522D01*
X753976Y1536598D01*
X754234Y1536790D01*
X754389Y1537097D01*
X754441Y1537365D01*
G01X750510Y1581623D02*
X756710D01*
G01X750510Y1578423D02*
Y1581623D01*
G01X756710Y1578423D02*
X750510D01*
G01Y1574423D02*
Y1577623D01*
G01X756710Y1574423D02*
X750510D01*
G01Y1577623D02*
X756710D01*
G01X744479Y1568318D02*
Y1571418D01*
X745399D01*
X745706Y1571263D01*
X745936Y1570901D01*
X746013Y1570488D01*
X745936Y1570075D01*
X745744Y1569765D01*
X745399Y1569610D01*
X744479D01*
G01X747503Y1571418D02*
Y1569196D01*
X747656Y1568731D01*
X747963Y1568421D01*
X748346Y1568318D01*
X748729Y1568421D01*
X749036Y1568731D01*
X749189Y1569196D01*
Y1571418D01*
G01X750718Y1570901D02*
X750948Y1571211D01*
X751216Y1571366D01*
X751523Y1571418D01*
X751906Y1571315D01*
X752174Y1571056D01*
X752251Y1570746D01*
X752213Y1570436D01*
X752059Y1570178D01*
X751293Y1569661D01*
X750948Y1569300D01*
X750718Y1568783D01*
X750641Y1568318D01*
X752251D01*
G01X754546D02*
X754814Y1568370D01*
X755121Y1568525D01*
X755313Y1568783D01*
X755389Y1569145D01*
X755313Y1569506D01*
X755083Y1569816D01*
X754738Y1569971D01*
X754354D01*
X754124Y1570075D01*
X753933Y1570333D01*
X753856Y1570695D01*
X753971Y1571056D01*
X754239Y1571315D01*
X754546Y1571418D01*
X754853Y1571315D01*
X755121Y1571056D01*
X755236Y1570695D01*
X755159Y1570333D01*
X754968Y1570075D01*
X754738Y1569971D01*
X754354D01*
X754009Y1569816D01*
X753779Y1569506D01*
X753703Y1569145D01*
X753779Y1568783D01*
X753971Y1568525D01*
X754278Y1568370D01*
X754546Y1568318D01*
G01X756994Y1568680D02*
X757263Y1568421D01*
X757569Y1568318D01*
X757876Y1568421D01*
X758144Y1568731D01*
X758336Y1569196D01*
X758413Y1569661D01*
Y1570230D01*
X758336Y1570695D01*
X758144Y1571108D01*
X757914Y1571315D01*
X757646Y1571418D01*
X757339Y1571315D01*
X757109Y1571108D01*
X756956Y1570798D01*
X756879Y1570385D01*
X756956Y1570023D01*
X757148Y1569661D01*
X757378Y1569455D01*
X757646Y1569403D01*
X757953Y1569506D01*
X758183Y1569765D01*
X758413Y1570230D01*
G01X743489Y1572252D02*
Y1592470D01*
G01X750510Y1587423D02*
Y1590623D01*
G01X756710Y1587423D02*
X750510D01*
G01Y1590623D02*
X756710D01*
G01X750510Y1582423D02*
Y1585623D01*
G01X756710Y1582423D02*
X750510D01*
G01Y1585623D02*
X756710D01*
G01X738323Y1631620D02*
Y1625420D01*
G01X742323D02*
X739123D01*
G01X742323Y1631620D02*
Y1625420D01*
G01X739123D02*
Y1631620D01*
G01X750170Y1626683D02*
Y1632883D01*
G01D02*
X753370D01*
G01Y1626683D02*
X750170D01*
G01X739123Y1631620D02*
X742323D01*
G01X746294Y1639560D02*
X748516D01*
X748981Y1639713D01*
X749291Y1640020D01*
X749394Y1640403D01*
X749291Y1640786D01*
X748981Y1641093D01*
X748516Y1641246D01*
X746294D01*
G01X746811Y1642775D02*
X746501Y1643005D01*
X746346Y1643273D01*
X746294Y1643580D01*
X746397Y1643963D01*
X746656Y1644231D01*
X746966Y1644308D01*
X747276Y1644270D01*
X747534Y1644116D01*
X748051Y1643350D01*
X748412Y1643005D01*
X748929Y1642775D01*
X749394Y1642698D01*
Y1644308D01*
G01Y1646526D02*
X748722Y1646603D01*
X748154Y1646718D01*
X747637Y1646871D01*
X747069Y1647063D01*
X746294Y1647370D01*
Y1645836D01*
G01X749394Y1649703D02*
X749342Y1649971D01*
X749187Y1650278D01*
X748929Y1650470D01*
X748567Y1650546D01*
X748206Y1650470D01*
X747896Y1650240D01*
X747741Y1649895D01*
Y1649511D01*
X747637Y1649281D01*
X747379Y1649090D01*
X747017Y1649013D01*
X746656Y1649128D01*
X746397Y1649396D01*
X746294Y1649703D01*
X746397Y1650010D01*
X746656Y1650278D01*
X747017Y1650393D01*
X747379Y1650316D01*
X747637Y1650125D01*
X747741Y1649895D01*
Y1649511D01*
X747896Y1649166D01*
X748206Y1648936D01*
X748567Y1648860D01*
X748929Y1648936D01*
X749187Y1649128D01*
X749342Y1649435D01*
X749394Y1649703D01*
G01X751668Y1643681D02*
Y1639459D01*
G01D02*
X763872D01*
G01X752430Y1654483D02*
Y1660683D01*
G01X755630Y1654483D02*
X752430D01*
G01X741288Y1646584D02*
Y1663100D01*
G01X754270Y1646283D02*
X751668Y1643681D01*
G01X763872Y1653107D02*
X751668D01*
G01D02*
Y1648885D01*
G01D02*
X754270Y1646283D01*
G01X752430Y1660683D02*
X755630D01*
G01X752430Y1661483D02*
Y1667683D01*
G01D02*
X755630D01*
G01Y1661483D02*
X752430D01*
G01X750587Y1683894D02*
Y1690094D01*
G01X753787Y1683894D02*
X750587D01*
G01X753787Y1673394D02*
X750587D01*
G01D02*
Y1679594D01*
G01D02*
X753787D01*
G01X742926Y1682212D02*
X739726D01*
G01X742926Y1688412D02*
Y1682212D01*
G01X739726D02*
Y1688412D01*
G01X739068Y1691803D02*
Y1685603D01*
G01X739726Y1681657D02*
X742926D01*
G01D02*
Y1675457D01*
G01D02*
X739726D01*
G01D02*
Y1681657D01*
G01X739067Y1685207D02*
Y1679007D01*
G01X743937Y1681742D02*
X747137D01*
G01X743937Y1675542D02*
Y1681742D01*
G01X747137Y1675542D02*
X743937D01*
G01X747137Y1681742D02*
Y1675542D01*
G01X743782Y1685670D02*
Y1691870D01*
G01X746982Y1685670D02*
X743782D01*
G01X746982Y1691870D02*
Y1685670D01*
G01X750587Y1690094D02*
X753787D01*
G01X739726Y1688412D02*
X742926D01*
G01X743782Y1691870D02*
X746982D01*
G01X749341Y1701792D02*
X749571Y1701430D01*
X749877Y1701224D01*
X750222Y1701172D01*
X750529Y1701224D01*
X750836Y1701482D01*
X751027Y1701792D01*
X751066Y1702102D01*
X750989Y1702464D01*
X750721Y1702722D01*
X750452Y1702825D01*
X750107D01*
G01X750452D02*
X750682Y1702980D01*
X750874Y1703239D01*
X750951Y1703549D01*
X750874Y1703859D01*
X750682Y1704117D01*
X750337Y1704272D01*
X749992Y1704220D01*
X749647Y1704014D01*
G01X752263Y1697575D02*
Y1727969D01*
G01X762105Y1697575D02*
X752263D01*
G01X752017Y1729909D02*
X752209Y1729599D01*
X752439Y1729392D01*
X752707Y1729289D01*
X753014Y1729392D01*
X753244Y1729599D01*
X753474Y1729909D01*
X753551Y1730322D01*
Y1732389D01*
G01X755117Y1729289D02*
Y1732389D01*
X756037D01*
X756344Y1732234D01*
X756574Y1731872D01*
X756651Y1731459D01*
X756574Y1731046D01*
X756382Y1730736D01*
X756037Y1730581D01*
X755117D01*
G01X758984Y1729289D02*
Y1732389D01*
X758524Y1731769D01*
G01Y1729289D02*
X759444D01*
G01X762084Y1732389D02*
X761777Y1732286D01*
X761547Y1732027D01*
X761394Y1731717D01*
X761279Y1731304D01*
X761241Y1730839D01*
X761279Y1730374D01*
X761394Y1729961D01*
X761547Y1729651D01*
X761777Y1729392D01*
X762084Y1729289D01*
X762391Y1729392D01*
X762621Y1729651D01*
X762774Y1729961D01*
X762889Y1730374D01*
X762927Y1730839D01*
X762889Y1731304D01*
X762774Y1731717D01*
X762621Y1732027D01*
X762391Y1732286D01*
X762084Y1732389D01*
G01X752263Y1727969D02*
X762105D01*
G01X764654Y64566D02*
X753504D01*
G01X761718Y90948D02*
Y87748D01*
G01D02*
X755518D01*
G01D02*
Y90948D01*
G01X765516Y89518D02*
Y92618D01*
X766436D01*
X766743Y92463D01*
X766973Y92101D01*
X767050Y91688D01*
X766973Y91275D01*
X766781Y90965D01*
X766436Y90810D01*
X765516D01*
G01X768540Y89518D02*
Y92618D01*
X769306D01*
X769613Y92463D01*
X769843Y92256D01*
X770035Y91946D01*
X770188Y91585D01*
X770226Y91068D01*
X770188Y90551D01*
X770035Y90190D01*
X769843Y89880D01*
X769613Y89673D01*
X769306Y89518D01*
X768540D01*
G01X772483D02*
Y92618D01*
X772023Y91998D01*
G01Y89518D02*
X772943D01*
G01X775583D02*
Y92618D01*
X775123Y91998D01*
G01Y89518D02*
X776043D01*
G01X777955Y90810D02*
X778223Y91171D01*
X778453Y91378D01*
X778760Y91481D01*
X779028Y91378D01*
X779220Y91171D01*
X779373Y90861D01*
X779411Y90500D01*
X779373Y90190D01*
X779220Y89880D01*
X778990Y89621D01*
X778721Y89518D01*
X778415Y89621D01*
X778146Y89931D01*
X777993Y90396D01*
X777955Y90913D01*
X778031Y91585D01*
X778146Y91946D01*
X778338Y92308D01*
X778606Y92566D01*
X778875Y92618D01*
X779143Y92515D01*
X779335Y92256D01*
G01X755518Y90948D02*
X761718D01*
G01X758593Y99128D02*
Y105328D01*
G01D02*
X761793D01*
G01D02*
Y99128D01*
G01D02*
X758593D01*
G01X761793Y97948D02*
Y91748D01*
G01D02*
X758593D01*
G01D02*
Y97948D01*
G01D02*
X761793D01*
G01X763085Y104556D02*
Y107656D01*
X764005D01*
X764312Y107501D01*
X764542Y107139D01*
X764619Y106726D01*
X764542Y106313D01*
X764350Y106003D01*
X764005Y105848D01*
X763085D01*
G01X766109Y107656D02*
Y105434D01*
X766262Y104969D01*
X766569Y104659D01*
X766952Y104556D01*
X767335Y104659D01*
X767642Y104969D01*
X767795Y105434D01*
Y107656D01*
G01X769209Y105176D02*
X769439Y104814D01*
X769745Y104608D01*
X770090Y104556D01*
X770397Y104608D01*
X770704Y104866D01*
X770895Y105176D01*
X770934Y105486D01*
X770857Y105848D01*
X770589Y106106D01*
X770320Y106209D01*
X769975D01*
G01X770320D02*
X770550Y106364D01*
X770742Y106623D01*
X770819Y106933D01*
X770742Y107243D01*
X770550Y107501D01*
X770205Y107656D01*
X769860Y107604D01*
X769515Y107398D01*
G01X773152Y107656D02*
X772845Y107553D01*
X772615Y107294D01*
X772462Y106984D01*
X772347Y106571D01*
X772309Y106106D01*
X772347Y105641D01*
X772462Y105228D01*
X772615Y104918D01*
X772845Y104659D01*
X773152Y104556D01*
X773459Y104659D01*
X773689Y104918D01*
X773842Y105228D01*
X773957Y105641D01*
X773995Y106106D01*
X773957Y106571D01*
X773842Y106984D01*
X773689Y107294D01*
X773459Y107553D01*
X773152Y107656D01*
G01X776252D02*
X775945Y107553D01*
X775715Y107294D01*
X775562Y106984D01*
X775447Y106571D01*
X775409Y106106D01*
X775447Y105641D01*
X775562Y105228D01*
X775715Y104918D01*
X775945Y104659D01*
X776252Y104556D01*
X776559Y104659D01*
X776789Y104918D01*
X776942Y105228D01*
X777057Y105641D01*
X777095Y106106D01*
X777057Y106571D01*
X776942Y106984D01*
X776789Y107294D01*
X776559Y107553D01*
X776252Y107656D01*
G01X753991Y96864D02*
Y105052D01*
G01X756233Y116888D02*
Y113688D01*
G01Y112888D02*
Y109688D01*
G01X756235Y120772D02*
Y117572D01*
G01X758900Y114100D02*
X762100D01*
G01X758900Y107900D02*
Y114100D01*
G01X762100Y107900D02*
X758900D01*
G01X762100Y114100D02*
Y107900D01*
G01X762105Y136681D02*
X761798Y136733D01*
X761530Y136939D01*
X761300Y137249D01*
X761147Y137611D01*
X761070Y138024D01*
Y138438D01*
X761147Y138851D01*
X761300Y139213D01*
X761530Y139523D01*
X761798Y139729D01*
X762105Y139781D01*
X762412Y139729D01*
X762680Y139523D01*
X762910Y139213D01*
X763063Y138851D01*
X763140Y138438D01*
Y138024D01*
X763063Y137611D01*
X762910Y137249D01*
X762680Y136939D01*
X762412Y136733D01*
X762105Y136681D01*
G01X762412Y137508D02*
X762872Y136681D01*
G01X764362Y137301D02*
X764592Y136939D01*
X764898Y136733D01*
X765243Y136681D01*
X765550Y136733D01*
X765857Y136991D01*
X766048Y137301D01*
X766087Y137611D01*
X766010Y137973D01*
X765742Y138231D01*
X765473Y138334D01*
X765128D01*
G01X765473D02*
X765703Y138489D01*
X765895Y138748D01*
X765972Y139058D01*
X765895Y139368D01*
X765703Y139626D01*
X765358Y139781D01*
X765013Y139729D01*
X764668Y139523D01*
G01X767653Y137043D02*
X767922Y136784D01*
X768228Y136681D01*
X768535Y136784D01*
X768803Y137094D01*
X768995Y137559D01*
X769072Y138024D01*
Y138593D01*
X768995Y139058D01*
X768803Y139471D01*
X768573Y139678D01*
X768305Y139781D01*
X767998Y139678D01*
X767768Y139471D01*
X767615Y139161D01*
X767538Y138748D01*
X767615Y138386D01*
X767807Y138024D01*
X768037Y137818D01*
X768305Y137766D01*
X768612Y137869D01*
X768842Y138128D01*
X769072Y138593D01*
G01X764153Y126419D02*
X761913D01*
G01X763126Y124794D02*
Y128044D01*
G01X761085Y122482D02*
Y130356D01*
G01X753726Y126219D02*
X754826D01*
G01X753726Y127719D02*
Y124719D01*
G01X768935Y141063D02*
X757123D01*
G01D02*
Y153687D01*
G01X752835Y163063D02*
Y159863D01*
G01X757123Y153687D02*
X768935D01*
G01X752800Y169137D02*
Y165937D01*
G01X753100Y177100D02*
Y173900D01*
G01X759235Y175990D02*
X758928Y176042D01*
X758660Y176248D01*
X758430Y176558D01*
X758277Y176920D01*
X758200Y177333D01*
Y177747D01*
X758277Y178160D01*
X758430Y178522D01*
X758660Y178832D01*
X758928Y179038D01*
X759235Y179090D01*
X759542Y179038D01*
X759810Y178832D01*
X760040Y178522D01*
X760193Y178160D01*
X760270Y177747D01*
Y177333D01*
X760193Y176920D01*
X760040Y176558D01*
X759810Y176248D01*
X759542Y176042D01*
X759235Y175990D01*
G01X759542Y176817D02*
X760002Y175990D01*
G01X762335D02*
Y179090D01*
X761875Y178470D01*
G01Y175990D02*
X762795D01*
G01X764707Y178573D02*
X764937Y178883D01*
X765205Y179038D01*
X765512Y179090D01*
X765895Y178987D01*
X766163Y178728D01*
X766240Y178418D01*
X766202Y178108D01*
X766048Y177850D01*
X765282Y177333D01*
X764937Y176972D01*
X764707Y176455D01*
X764630Y175990D01*
X766240D01*
G01X767692Y176455D02*
X767922Y176197D01*
X768190Y176042D01*
X768535Y175990D01*
X768880Y176093D01*
X769148Y176300D01*
X769340Y176662D01*
X769378Y177075D01*
X769302Y177488D01*
X769110Y177747D01*
X768842Y177953D01*
X768573Y178005D01*
X768305Y177953D01*
X767960Y177747D01*
X768075Y179090D01*
X769110D01*
G01X770232Y165746D02*
X766885D01*
G01D02*
X764985Y167946D01*
G01D02*
X763085Y165746D01*
G01D02*
X759738D01*
G01D02*
Y174408D01*
G01D02*
X770232D01*
G01X755700Y204700D02*
Y194300D01*
G01Y206500D02*
Y204700D01*
G01X767405Y210291D02*
X767353Y209984D01*
X767147Y209716D01*
X766837Y209486D01*
X766475Y209333D01*
X766062Y209256D01*
X765648D01*
X765235Y209333D01*
X764873Y209486D01*
X764563Y209716D01*
X764357Y209984D01*
X764305Y210291D01*
X764357Y210598D01*
X764563Y210866D01*
X764873Y211096D01*
X765235Y211249D01*
X765648Y211326D01*
X766062D01*
X766475Y211249D01*
X766837Y211096D01*
X767147Y210866D01*
X767353Y210598D01*
X767405Y210291D01*
G01X766578Y210598D02*
X767405Y211058D01*
G01Y213391D02*
X767353Y213659D01*
X767198Y213966D01*
X766940Y214158D01*
X766578Y214234D01*
X766217Y214158D01*
X765907Y213928D01*
X765752Y213583D01*
Y213199D01*
X765648Y212969D01*
X765390Y212778D01*
X765028Y212701D01*
X764667Y212816D01*
X764408Y213084D01*
X764305Y213391D01*
X764408Y213698D01*
X764667Y213966D01*
X765028Y214081D01*
X765390Y214004D01*
X765648Y213813D01*
X765752Y213583D01*
Y213199D01*
X765907Y212854D01*
X766217Y212624D01*
X766578Y212548D01*
X766940Y212624D01*
X767198Y212816D01*
X767353Y213123D01*
X767405Y213391D01*
G01X764305Y216491D02*
X764408Y216184D01*
X764667Y215954D01*
X764977Y215801D01*
X765390Y215686D01*
X765855Y215648D01*
X766320Y215686D01*
X766733Y215801D01*
X767043Y215954D01*
X767302Y216184D01*
X767405Y216491D01*
X767302Y216798D01*
X767043Y217028D01*
X766733Y217181D01*
X766320Y217296D01*
X765855Y217334D01*
X765390Y217296D01*
X764977Y217181D01*
X764667Y217028D01*
X764408Y216798D01*
X764305Y216491D01*
G01Y219591D02*
X764408Y219284D01*
X764667Y219054D01*
X764977Y218901D01*
X765390Y218786D01*
X765855Y218748D01*
X766320Y218786D01*
X766733Y218901D01*
X767043Y219054D01*
X767302Y219284D01*
X767405Y219591D01*
X767302Y219898D01*
X767043Y220128D01*
X766733Y220281D01*
X766320Y220396D01*
X765855Y220434D01*
X765390Y220396D01*
X764977Y220281D01*
X764667Y220128D01*
X764408Y219898D01*
X764305Y219591D01*
G01X767405Y222691D02*
X764305D01*
X764925Y222231D01*
G01X767405D02*
Y223151D01*
G01X762600Y210900D02*
X759400D01*
G01X762600Y217100D02*
Y210900D01*
G01X759400Y217100D02*
X762600D01*
G01X759400Y210900D02*
Y217100D01*
G01X755331Y221747D02*
Y211253D01*
G01X759154Y229801D02*
Y226601D01*
G01X752954Y229801D02*
X759154D01*
G01X752954Y226601D02*
Y229801D01*
G01X759154Y226601D02*
X752954D01*
G01X761366Y270922D02*
Y267722D01*
G01D02*
X755166D01*
G01D02*
Y270922D01*
G01X761366Y266922D02*
Y263722D01*
G01D02*
X755166D01*
G01D02*
Y266922D01*
G01D02*
X761366D01*
G01X755166Y270922D02*
X761366D01*
G01X761367Y277922D02*
Y274722D01*
G01X755167Y277922D02*
X761367D01*
G01Y274722D02*
X755167D01*
G01D02*
Y277922D01*
G01X768343Y297679D02*
X762143D01*
G01D02*
Y300879D01*
G01X754924Y287459D02*
Y290559D01*
X755844D01*
X756151Y290404D01*
X756381Y290042D01*
X756458Y289629D01*
X756381Y289216D01*
X756189Y288906D01*
X755844Y288751D01*
X754924D01*
G01X757948Y290559D02*
Y288337D01*
X758101Y287872D01*
X758408Y287562D01*
X758791Y287459D01*
X759174Y287562D01*
X759481Y287872D01*
X759634Y288337D01*
Y290559D01*
G01X761163Y290042D02*
X761393Y290352D01*
X761661Y290507D01*
X761968Y290559D01*
X762351Y290456D01*
X762619Y290197D01*
X762696Y289887D01*
X762658Y289577D01*
X762504Y289319D01*
X761738Y288802D01*
X761393Y288441D01*
X761163Y287924D01*
X761086Y287459D01*
X762696D01*
G01X764339Y287821D02*
X764608Y287562D01*
X764914Y287459D01*
X765221Y287562D01*
X765489Y287872D01*
X765681Y288337D01*
X765758Y288802D01*
Y289371D01*
X765681Y289836D01*
X765489Y290249D01*
X765259Y290456D01*
X764991Y290559D01*
X764684Y290456D01*
X764454Y290249D01*
X764301Y289939D01*
X764224Y289526D01*
X764301Y289164D01*
X764493Y288802D01*
X764723Y288596D01*
X764991Y288544D01*
X765298Y288647D01*
X765528Y288906D01*
X765758Y289371D01*
G01X767248Y288079D02*
X767478Y287717D01*
X767784Y287511D01*
X768129Y287459D01*
X768436Y287511D01*
X768743Y287769D01*
X768934Y288079D01*
X768973Y288389D01*
X768896Y288751D01*
X768628Y289009D01*
X768359Y289112D01*
X768014D01*
G01X768359D02*
X768589Y289267D01*
X768781Y289526D01*
X768858Y289836D01*
X768781Y290146D01*
X768589Y290404D01*
X768244Y290559D01*
X767899Y290507D01*
X767554Y290301D01*
G01X762143Y300879D02*
X768343D01*
G01X760600Y368462D02*
Y362262D01*
G01D02*
X757400D01*
G01D02*
Y368462D01*
G01D02*
X760600D01*
G01X765100Y381462D02*
Y375262D01*
G01D02*
X761900D01*
G01D02*
Y381462D01*
G01D02*
X765100D01*
G01X757900Y375262D02*
Y381462D01*
G01D02*
X761100D01*
G01D02*
Y375262D01*
G01D02*
X757900D01*
G01X753100Y397962D02*
Y391762D01*
G01X769100D02*
X765900D01*
G01D02*
Y397962D01*
G01D02*
X769100D01*
G01X757900Y391762D02*
Y397962D01*
G01D02*
X761100D01*
G01D02*
Y391762D01*
G01D02*
X757900D01*
G01X765100Y397962D02*
Y391762D01*
G01D02*
X761900D01*
G01D02*
Y397962D01*
G01D02*
X765100D01*
G01X753900Y391762D02*
Y397962D01*
G01D02*
X757100D01*
G01D02*
Y391762D01*
G01D02*
X753900D01*
G01X762900Y506262D02*
Y512462D01*
G01X766100D02*
Y506262D01*
G01D02*
X762900D01*
G01X754900D02*
Y512462D01*
G01X758100D02*
Y506262D01*
G01D02*
X754900D01*
G01X758900D02*
Y512462D01*
G01X762100D02*
Y506262D01*
G01D02*
X758900D01*
G01X754100Y512462D02*
Y506262D01*
G01X762900Y512462D02*
X766100D01*
G01X754900D02*
X758100D01*
G01X758900D02*
X762100D01*
G01X754900Y522762D02*
Y528962D01*
G01X758100D02*
Y522762D01*
G01D02*
X754900D01*
G01X758900D02*
Y528962D01*
G01X762100D02*
Y522762D01*
G01D02*
X758900D01*
G01X762900D02*
Y528962D01*
G01X766100D02*
Y522762D01*
G01D02*
X762900D01*
G01X754100Y528962D02*
Y522762D01*
G01X754900Y528962D02*
X758100D01*
G01X758900D02*
X762100D01*
G01X762900D02*
X766100D01*
G01X762100Y544962D02*
Y538762D01*
G01D02*
X758900D01*
G01D02*
Y544962D01*
G01D02*
X762100D01*
G01X758100D02*
Y538762D01*
G01D02*
X754900D01*
G01D02*
Y544962D01*
G01D02*
X758100D01*
G01X766600D02*
Y538762D01*
G01X763400D02*
Y544962D01*
G01D02*
X766600D01*
G01Y538762D02*
X763400D01*
G01X754100Y544962D02*
Y538762D01*
G01X770300Y538900D02*
X767100D01*
G01Y545100D02*
X770300D01*
G01X767100Y538900D02*
Y545100D01*
G01X757323Y1297200D02*
Y687245D01*
G01X761434D02*
Y1294160D01*
G01X787024Y687245D02*
X761434D01*
G01X787024Y720710D02*
X761434D01*
G01X787024Y1291576D02*
X761434D01*
G01X753812Y1299191D02*
X760939D01*
G01X753812Y1317845D02*
Y1299191D01*
G01X757323Y1325041D02*
Y1323200D01*
G01X756812Y1320845D02*
X753812Y1317845D01*
G01X760939Y1320845D02*
X756812D01*
G01X768096Y1328692D02*
X761754D01*
G01Y1368062D02*
X768096D01*
G01X762782Y1371342D02*
X761989D01*
G01X762782Y1373942D02*
Y1371342D01*
G01X765739Y1386601D02*
X768939D01*
G01X765739Y1380401D02*
Y1386601D01*
G01X768939Y1380401D02*
X765739D01*
G01X758370Y1398177D02*
Y1404377D01*
G01X761570Y1398177D02*
X758370D01*
G01X761570Y1404377D02*
Y1398177D01*
G01X757528D02*
X754328D01*
G01X757528Y1404377D02*
Y1398177D01*
G01X754328D02*
Y1404377D01*
G01X762782Y1394964D02*
Y1392773D01*
G01X762049Y1394964D02*
X762782D01*
G01X758370Y1404377D02*
X761570D01*
G01X754328D02*
X757528D01*
G01X759538Y1414575D02*
Y1417675D01*
X760458D01*
X760765Y1417520D01*
X760995Y1417158D01*
X761072Y1416745D01*
X760995Y1416332D01*
X760803Y1416022D01*
X760458Y1415867D01*
X759538D01*
G01X764248Y1417417D02*
X764018Y1417572D01*
X763750Y1417675D01*
X763443D01*
X763098Y1417520D01*
X762830Y1417262D01*
X762638Y1416952D01*
X762485Y1416435D01*
X762447Y1415970D01*
X762523Y1415505D01*
X762638Y1415195D01*
X762868Y1414885D01*
X763137Y1414678D01*
X763405Y1414575D01*
X763673D01*
X763942Y1414678D01*
X764172Y1414833D01*
X764363Y1415040D01*
G01X765662D02*
X765892Y1414782D01*
X766160Y1414627D01*
X766505Y1414575D01*
X766850Y1414678D01*
X767118Y1414885D01*
X767310Y1415247D01*
X767348Y1415660D01*
X767272Y1416073D01*
X767080Y1416332D01*
X766812Y1416538D01*
X766543Y1416590D01*
X766275Y1416538D01*
X765930Y1416332D01*
X766045Y1417675D01*
X767080D01*
G01X768877Y1417158D02*
X769107Y1417468D01*
X769375Y1417623D01*
X769682Y1417675D01*
X770065Y1417572D01*
X770333Y1417313D01*
X770410Y1417003D01*
X770372Y1416693D01*
X770218Y1416435D01*
X769452Y1415918D01*
X769107Y1415557D01*
X768877Y1415040D01*
X768800Y1414575D01*
X770410D01*
G01X771977Y1417158D02*
X772207Y1417468D01*
X772475Y1417623D01*
X772782Y1417675D01*
X773165Y1417572D01*
X773433Y1417313D01*
X773510Y1417003D01*
X773472Y1416693D01*
X773318Y1416435D01*
X772552Y1415918D01*
X772207Y1415557D01*
X771977Y1415040D01*
X771900Y1414575D01*
X773510D01*
G01X781063Y1478388D02*
X761377D01*
G01Y1485399D02*
Y1489039D01*
G01Y1478388D02*
Y1478699D01*
G01Y1527973D02*
Y1531613D01*
G01Y1538624D02*
X781063D01*
G01X761377Y1538313D02*
Y1538624D01*
G01X761537Y1572233D02*
X767737D01*
G01X761537Y1569033D02*
Y1572233D01*
G01X767737Y1569033D02*
X761537D01*
G01X756710Y1581623D02*
Y1578423D01*
G01Y1577623D02*
Y1574423D01*
G01X761550Y1576333D02*
X767750D01*
G01X761550Y1573133D02*
Y1576333D01*
G01X767750Y1573133D02*
X761550D01*
G01Y1580333D02*
X767750D01*
G01X761550Y1577133D02*
Y1580333D01*
G01X767750Y1577133D02*
X761550D01*
G01Y1589333D02*
X767750D01*
G01X761550Y1586133D02*
Y1589333D01*
G01X767750Y1586133D02*
X761550D01*
G01X756710Y1590623D02*
Y1587423D01*
G01Y1585623D02*
Y1582423D01*
G01X761550Y1590133D02*
Y1593333D01*
G01X767750Y1590133D02*
X761550D01*
G01Y1593333D02*
X767750D01*
G01X753370Y1632883D02*
Y1626683D01*
G01X756170D02*
Y1632883D01*
G01D02*
X759370D01*
G01D02*
Y1626683D01*
G01D02*
X756170D01*
G01X760170D02*
Y1632883D01*
G01D02*
X763370D01*
G01D02*
Y1626683D01*
G01D02*
X760170D01*
G01X763872Y1639459D02*
Y1653107D01*
G01X755630Y1660683D02*
Y1654483D01*
G01X768981Y1668641D02*
X765781D01*
G01D02*
Y1674841D01*
G01X755630Y1667683D02*
Y1661483D01*
G01X759630D02*
X756430D01*
G01D02*
Y1667683D01*
G01D02*
X759630D01*
G01D02*
Y1661483D01*
G01X760430D02*
Y1667683D01*
G01D02*
X763630D01*
G01D02*
Y1661483D01*
G01D02*
X760430D01*
G01X768968Y1660962D02*
X765768D01*
G01Y1667162D02*
X768968D01*
G01X765768Y1660962D02*
Y1667162D01*
G01X765781Y1674841D02*
X768981D01*
G01X753787Y1690094D02*
Y1683894D01*
G01Y1679594D02*
Y1673394D01*
G01X754584Y1676645D02*
Y1674423D01*
X754737Y1673958D01*
X755044Y1673648D01*
X755427Y1673545D01*
X755810Y1673648D01*
X756117Y1673958D01*
X756270Y1674423D01*
Y1676645D01*
G01X758527Y1673545D02*
Y1676645D01*
X758067Y1676025D01*
G01Y1673545D02*
X758987D01*
G01X760975Y1673907D02*
X761244Y1673648D01*
X761550Y1673545D01*
X761857Y1673648D01*
X762125Y1673958D01*
X762317Y1674423D01*
X762394Y1674888D01*
Y1675457D01*
X762317Y1675922D01*
X762125Y1676335D01*
X761895Y1676542D01*
X761627Y1676645D01*
X761320Y1676542D01*
X761090Y1676335D01*
X760937Y1676025D01*
X760860Y1675612D01*
X760937Y1675250D01*
X761129Y1674888D01*
X761359Y1674682D01*
X761627Y1674630D01*
X761934Y1674733D01*
X762164Y1674992D01*
X762394Y1675457D01*
G01X764727Y1676645D02*
X764420Y1676542D01*
X764190Y1676283D01*
X764037Y1675973D01*
X763922Y1675560D01*
X763884Y1675095D01*
X763922Y1674630D01*
X764037Y1674217D01*
X764190Y1673907D01*
X764420Y1673648D01*
X764727Y1673545D01*
X765034Y1673648D01*
X765264Y1673907D01*
X765417Y1674217D01*
X765532Y1674630D01*
X765570Y1675095D01*
X765532Y1675560D01*
X765417Y1675973D01*
X765264Y1676283D01*
X765034Y1676542D01*
X764727Y1676645D01*
G01X767203Y1690144D02*
Y1677520D01*
G01X755391D02*
Y1690144D01*
G01X767203Y1677520D02*
X755391D01*
G01X755562Y1694969D02*
X761762D01*
G01D02*
Y1691769D01*
G01D02*
X755562D01*
G01D02*
Y1694969D01*
G01X755391Y1690144D02*
X767203D01*
G01X762105Y1727969D02*
Y1697575D01*
G01X774173Y79396D02*
X771933D01*
G01X773146Y77771D02*
Y81021D01*
G01X768529Y84986D02*
Y73490D01*
G01X779643Y110120D02*
Y113220D01*
G01X781253D02*
Y110120D01*
G01Y111670D02*
X779643D01*
G01X782896Y110482D02*
X783165Y110223D01*
X783471Y110120D01*
X783778Y110223D01*
X784046Y110533D01*
X784238Y110998D01*
X784315Y111463D01*
Y112032D01*
X784238Y112497D01*
X784046Y112910D01*
X783816Y113117D01*
X783548Y113220D01*
X783241Y113117D01*
X783011Y112910D01*
X782858Y112600D01*
X782781Y112187D01*
X782858Y111825D01*
X783050Y111463D01*
X783280Y111257D01*
X783548Y111205D01*
X783855Y111308D01*
X784085Y111567D01*
X784315Y112032D01*
G01X785920Y112703D02*
X786150Y113013D01*
X786418Y113168D01*
X786725Y113220D01*
X787108Y113117D01*
X787376Y112858D01*
X787453Y112548D01*
X787415Y112238D01*
X787261Y111980D01*
X786495Y111463D01*
X786150Y111102D01*
X785920Y110585D01*
X785843Y110120D01*
X787453D01*
G01X768935Y153687D02*
Y141063D01*
G01X779520Y161654D02*
X773320D01*
G01D02*
Y164854D01*
G01D02*
X779520D01*
G01D02*
Y161654D01*
G01X773189Y159626D02*
X779389D01*
G01D02*
Y156426D01*
G01D02*
X773189D01*
G01D02*
Y159626D01*
G01X773203Y155328D02*
X779403D01*
G01D02*
Y152128D01*
G01D02*
X773203D01*
G01D02*
Y155328D01*
G01X770232Y174408D02*
Y165746D01*
G01X837186Y204724D02*
G02I-31496J0D01*
G01X770371Y228965D02*
Y232065D01*
G01X771981D02*
Y228965D01*
G01Y230515D02*
X770371D01*
G01X774276Y228965D02*
Y232065D01*
X773816Y231445D01*
G01Y228965D02*
X774736D01*
G01X777376D02*
Y232065D01*
X776916Y231445D01*
G01Y228965D02*
X777836D01*
G01X779633Y229585D02*
X779863Y229223D01*
X780169Y229017D01*
X780514Y228965D01*
X780821Y229017D01*
X781128Y229275D01*
X781319Y229585D01*
X781358Y229895D01*
X781281Y230257D01*
X781013Y230515D01*
X780744Y230618D01*
X780399D01*
G01X780744D02*
X780974Y230773D01*
X781166Y231032D01*
X781243Y231342D01*
X781166Y231652D01*
X780974Y231910D01*
X780629Y232065D01*
X780284Y232013D01*
X779939Y231807D01*
G01X776456Y262792D02*
Y250792D01*
G01D02*
X770456D01*
G01D02*
Y262792D01*
G01D02*
X776456D01*
G01X779653Y278203D02*
Y268441D01*
G01D02*
X767879D01*
G01D02*
Y278203D01*
G01X772166Y279722D02*
Y285922D01*
G01X775366D02*
Y279722D01*
G01D02*
X772166D01*
G01X767879Y278203D02*
X779653D01*
G01X772166Y285922D02*
X775366D01*
G01X782143Y300879D02*
Y297679D01*
G01D02*
X775943D01*
G01D02*
Y300879D01*
G01X768343D02*
Y297679D01*
G01X777627Y301810D02*
X771427D01*
G01D02*
Y305010D01*
G01D02*
X777627D01*
G01D02*
Y301810D01*
G01X777542Y307155D02*
X771342D01*
G01D02*
Y310355D01*
G01D02*
X777542D01*
G01D02*
Y307155D01*
G01X775943Y300879D02*
X782143D01*
G01X777400Y369100D02*
X783600D01*
G01X777400Y365900D02*
Y369100D01*
G01X783600Y365900D02*
X777400D01*
G01Y369400D02*
Y372600D01*
G01X783600Y369400D02*
X777400D01*
G01Y372600D02*
X783600D01*
G01X777400Y362400D02*
Y365600D01*
G01X783600Y362400D02*
X777400D01*
G01Y365600D02*
X783600D01*
G01X770400Y362400D02*
Y365600D01*
G01X776600Y362400D02*
X770400D01*
G01X776600Y365600D02*
Y362400D01*
G01X770400Y365600D02*
X776600D01*
G01X786739Y370756D02*
Y372996D01*
G01X785114Y371783D02*
X788364D01*
G01X783056Y376517D02*
X779856D01*
G01Y382717D02*
X783056D01*
G01X779856Y376517D02*
Y382717D01*
G01X769100Y397962D02*
Y391762D01*
G01X773900D02*
Y397962D01*
G01D02*
X777100D01*
G01D02*
Y391762D01*
G01D02*
X773900D01*
G01X769900D02*
Y397962D01*
G01D02*
X773100D01*
G01D02*
Y391762D01*
G01D02*
X769900D01*
G01X779769Y421064D02*
Y417864D01*
G01D02*
X773569D01*
G01D02*
Y421064D01*
G01X780752Y413744D02*
X774552D01*
G01D02*
Y416944D01*
G01D02*
X780752D01*
G01D02*
Y413744D01*
G01X767804Y415562D02*
Y490366D01*
G01X773569Y421064D02*
X779769D01*
G01X779752Y429744D02*
X773552D01*
G01D02*
Y432944D01*
G01D02*
X779752D01*
G01D02*
Y429744D01*
G01Y425744D02*
X773552D01*
G01D02*
Y428944D01*
G01D02*
X779752D01*
G01D02*
Y425744D01*
G01Y421744D02*
X773552D01*
G01D02*
Y424944D01*
G01D02*
X779752D01*
G01D02*
Y421744D01*
G01Y433744D02*
X773552D01*
G01D02*
Y436944D01*
G01X779752D02*
Y433744D01*
G01Y445744D02*
X773552D01*
G01D02*
Y448944D01*
G01X779752D02*
Y445744D01*
G01Y441744D02*
X773552D01*
G01D02*
Y444944D01*
G01D02*
X779752D01*
G01D02*
Y441744D01*
G01Y437744D02*
X773552D01*
G01D02*
Y440944D01*
G01D02*
X779752D01*
G01D02*
Y437744D01*
G01X773552Y436944D02*
X779752D01*
G01X773552Y448944D02*
X779752D01*
G01X773552Y456944D02*
X779752D01*
G01D02*
Y453744D01*
G01D02*
X773552D01*
G01D02*
Y456944D01*
G01X779752Y449744D02*
X773552D01*
G01D02*
Y452944D01*
G01D02*
X779752D01*
G01D02*
Y449744D01*
G01Y464944D02*
Y461744D01*
G01D02*
X773552D01*
G01D02*
Y464944D01*
G01Y460944D02*
X779752D01*
G01D02*
Y457744D01*
G01D02*
X773552D01*
G01D02*
Y460944D01*
G01Y464944D02*
X779752D01*
G01X773552Y477944D02*
X779752D01*
G01D02*
Y474744D01*
G01D02*
X773552D01*
G01D02*
Y477944D01*
G01Y473944D02*
X779752D01*
G01D02*
Y470744D01*
G01D02*
X773552D01*
G01D02*
Y473944D01*
G01Y488944D02*
X779752D01*
G01D02*
Y485744D01*
G01D02*
X773552D01*
G01D02*
Y488944D01*
G01Y492944D02*
X779752D01*
G01D02*
Y489744D01*
G01D02*
X773552D01*
G01D02*
Y492944D01*
G01Y500944D02*
X779752D01*
G01D02*
Y497744D01*
G01D02*
X773552D01*
G01D02*
Y500944D01*
G01Y496944D02*
X779752D01*
G01D02*
Y493744D01*
G01D02*
X773552D01*
G01D02*
Y496944D01*
G01X773600Y528962D02*
Y522762D01*
G01D02*
X770400D01*
G01D02*
Y528962D01*
G01D02*
X773600D01*
G01X771400Y538762D02*
Y544962D01*
G01D02*
X774600D01*
G01D02*
Y538762D01*
G01D02*
X771400D01*
G01X770300Y545100D02*
Y538900D01*
G01X772062Y683596D02*
X772254Y683286D01*
X772484Y683079D01*
X772752Y682976D01*
X773059Y683079D01*
X773289Y683286D01*
X773519Y683596D01*
X773596Y684009D01*
Y686076D01*
G01X775277Y683338D02*
X775546Y683079D01*
X775852Y682976D01*
X776159Y683079D01*
X776427Y683389D01*
X776619Y683854D01*
X776696Y684319D01*
Y684888D01*
X776619Y685353D01*
X776427Y685766D01*
X776197Y685973D01*
X775929Y686076D01*
X775622Y685973D01*
X775392Y685766D01*
X775239Y685456D01*
X775162Y685043D01*
X775239Y684681D01*
X775431Y684319D01*
X775661Y684113D01*
X775929Y684061D01*
X776236Y684164D01*
X776466Y684423D01*
X776696Y684888D01*
G01X778377Y683338D02*
X778646Y683079D01*
X778952Y682976D01*
X779259Y683079D01*
X779527Y683389D01*
X779719Y683854D01*
X779796Y684319D01*
Y684888D01*
X779719Y685353D01*
X779527Y685766D01*
X779297Y685973D01*
X779029Y686076D01*
X778722Y685973D01*
X778492Y685766D01*
X778339Y685456D01*
X778262Y685043D01*
X778339Y684681D01*
X778531Y684319D01*
X778761Y684113D01*
X779029Y684061D01*
X779336Y684164D01*
X779566Y684423D01*
X779796Y684888D01*
G01X778091Y1295127D02*
Y1323867D01*
G01X784180Y1295127D02*
X778091D01*
G01X775466Y1299191D02*
Y1317845D01*
G01X768339Y1299191D02*
X775466D01*
G01X770150Y1325041D02*
X778940D01*
G01X778091Y1323867D02*
X784080D01*
G01X772466Y1320845D02*
X768339D01*
G01X775466Y1317845D02*
X772466Y1320845D01*
G01X781047Y1332656D02*
X777847D01*
G01X781047Y1338856D02*
Y1332656D01*
G01X777847Y1338856D02*
X781047D01*
G01X777847Y1332656D02*
Y1338856D01*
G01X768096Y1368062D02*
Y1328692D01*
G01X793173Y1352396D02*
X781173D01*
G01D02*
Y1358396D01*
G01X793173Y1359296D02*
X781173D01*
G01Y1365296D02*
X793173D01*
G01X781173Y1359296D02*
Y1365296D01*
G01Y1358396D02*
X793173D01*
G01X769616Y1386601D02*
X772816D01*
G01X769616Y1380401D02*
Y1386601D01*
G01X772816Y1380401D02*
X769616D01*
G01X772816Y1386601D02*
Y1380401D01*
G01X768939Y1386601D02*
Y1380401D01*
G01X780123Y1399338D02*
Y1402438D01*
G01X781733D02*
Y1399338D01*
G01Y1400888D02*
X780123D01*
G01X784488Y1399338D02*
Y1402438D01*
X783070Y1400216D01*
X784986D01*
G01X786476Y1399700D02*
X786745Y1399441D01*
X787051Y1399338D01*
X787358Y1399441D01*
X787626Y1399751D01*
X787818Y1400216D01*
X787895Y1400681D01*
Y1401250D01*
X787818Y1401715D01*
X787626Y1402128D01*
X787396Y1402335D01*
X787128Y1402438D01*
X786821Y1402335D01*
X786591Y1402128D01*
X786438Y1401818D01*
X786361Y1401405D01*
X786438Y1401043D01*
X786630Y1400681D01*
X786860Y1400475D01*
X787128Y1400423D01*
X787435Y1400526D01*
X787665Y1400785D01*
X787895Y1401250D01*
G01X771994Y1406557D02*
Y1412557D01*
G01X783994Y1406557D02*
X771994D01*
G01Y1412557D02*
X783994D01*
G01X781063Y1487071D02*
Y1485399D01*
G01Y1478699D02*
Y1478388D01*
G01Y1531613D02*
Y1529941D01*
G01Y1538624D02*
Y1538313D01*
G01X775154Y1555903D02*
X772054D01*
Y1556823D01*
X772209Y1557130D01*
X772571Y1557360D01*
X772984Y1557437D01*
X773397Y1557360D01*
X773707Y1557168D01*
X773862Y1556823D01*
Y1555903D01*
G01X772054Y1558927D02*
X774276D01*
X774741Y1559080D01*
X775051Y1559387D01*
X775154Y1559770D01*
X775051Y1560153D01*
X774741Y1560460D01*
X774276Y1560613D01*
X772054D01*
G01X772571Y1562142D02*
X772261Y1562372D01*
X772106Y1562640D01*
X772054Y1562947D01*
X772157Y1563330D01*
X772416Y1563598D01*
X772726Y1563675D01*
X773036Y1563637D01*
X773294Y1563483D01*
X773811Y1562717D01*
X774172Y1562372D01*
X774689Y1562142D01*
X775154Y1562065D01*
Y1563675D01*
G01Y1565970D02*
X775102Y1566238D01*
X774947Y1566545D01*
X774689Y1566737D01*
X774327Y1566813D01*
X773966Y1566737D01*
X773656Y1566507D01*
X773501Y1566162D01*
Y1565778D01*
X773397Y1565548D01*
X773139Y1565357D01*
X772777Y1565280D01*
X772416Y1565395D01*
X772157Y1565663D01*
X772054Y1565970D01*
X772157Y1566277D01*
X772416Y1566545D01*
X772777Y1566660D01*
X773139Y1566583D01*
X773397Y1566392D01*
X773501Y1566162D01*
Y1565778D01*
X773656Y1565433D01*
X773966Y1565203D01*
X774327Y1565127D01*
X774689Y1565203D01*
X774947Y1565395D01*
X775102Y1565702D01*
X775154Y1565970D01*
G01Y1568993D02*
X774482Y1569070D01*
X773914Y1569185D01*
X773397Y1569338D01*
X772829Y1569530D01*
X772054Y1569837D01*
Y1568303D01*
G01X772050Y1579433D02*
X768850D01*
G01X772050Y1585633D02*
Y1579433D01*
G01X768850D02*
Y1585633D01*
G01X767737Y1572233D02*
Y1569033D01*
G01X767750Y1576333D02*
Y1573133D01*
G01Y1580333D02*
Y1577133D01*
G01X775468Y1592472D02*
Y1572254D01*
G01D02*
X795686D01*
G01X768850Y1585633D02*
X772050D01*
G01X767750Y1589333D02*
Y1586133D01*
G01Y1593333D02*
Y1590133D01*
G01X795686Y1592472D02*
X775468D01*
G01X768981Y1674841D02*
Y1668641D01*
G01X768968Y1667162D02*
Y1660962D01*
G01X771477Y1668906D02*
Y1787213D01*
G01X1086083Y1668906D02*
X771477D01*
G01Y1787213D02*
X1086083D01*
G01X784126Y121994D02*
X798926D01*
G01X784126Y152998D02*
Y121994D01*
G01X784251Y156965D02*
Y160065D01*
X785210D01*
X785516Y159910D01*
X785708Y159703D01*
X785785Y159290D01*
X785708Y158877D01*
X785478Y158618D01*
X785210Y158463D01*
X784251D01*
G01X785210D02*
X785785Y156965D01*
G01X787275Y157585D02*
X787505Y157223D01*
X787811Y157017D01*
X788156Y156965D01*
X788463Y157017D01*
X788770Y157275D01*
X788961Y157585D01*
X789000Y157895D01*
X788923Y158257D01*
X788655Y158515D01*
X788386Y158618D01*
X788041D01*
G01X788386D02*
X788616Y158773D01*
X788808Y159032D01*
X788885Y159342D01*
X788808Y159652D01*
X788616Y159910D01*
X788271Y160065D01*
X787926Y160013D01*
X787581Y159807D01*
G01X790490Y158257D02*
X790758Y158618D01*
X790988Y158825D01*
X791295Y158928D01*
X791563Y158825D01*
X791755Y158618D01*
X791908Y158308D01*
X791946Y157947D01*
X791908Y157637D01*
X791755Y157327D01*
X791525Y157068D01*
X791256Y156965D01*
X790950Y157068D01*
X790681Y157378D01*
X790528Y157843D01*
X790490Y158360D01*
X790566Y159032D01*
X790681Y159393D01*
X790873Y159755D01*
X791141Y160013D01*
X791410Y160065D01*
X791678Y159962D01*
X791870Y159703D01*
G01X793475Y157585D02*
X793705Y157223D01*
X794011Y157017D01*
X794356Y156965D01*
X794663Y157017D01*
X794970Y157275D01*
X795161Y157585D01*
X795200Y157895D01*
X795123Y158257D01*
X794855Y158515D01*
X794586Y158618D01*
X794241D01*
G01X794586D02*
X794816Y158773D01*
X795008Y159032D01*
X795085Y159342D01*
X795008Y159652D01*
X794816Y159910D01*
X794471Y160065D01*
X794126Y160013D01*
X793781Y159807D01*
G01X796575Y157430D02*
X796805Y157172D01*
X797073Y157017D01*
X797418Y156965D01*
X797763Y157068D01*
X798031Y157275D01*
X798223Y157637D01*
X798261Y158050D01*
X798185Y158463D01*
X797993Y158722D01*
X797725Y158928D01*
X797456Y158980D01*
X797188Y158928D01*
X796843Y158722D01*
X796958Y160065D01*
X797993D01*
G01X798926Y152998D02*
X784126D01*
G01X792866Y269422D02*
Y266222D01*
G01X786666Y269422D02*
X792866D01*
G01Y266222D02*
X786666D01*
G01D02*
Y269422D01*
G01X792866Y283422D02*
Y280222D01*
G01X786666Y283422D02*
X792866D01*
G01Y280222D02*
X786666D01*
G01D02*
Y283422D01*
G01X792866Y276422D02*
Y273222D01*
G01D02*
X786666D01*
G01D02*
Y276422D01*
G01D02*
X792866D01*
G01X790727Y301810D02*
X784527D01*
G01D02*
Y305010D01*
G01D02*
X790727D01*
G01D02*
Y301810D01*
G01X790642Y307155D02*
X784442D01*
G01D02*
Y310355D01*
G01D02*
X790642D01*
G01D02*
Y307155D01*
G01X783600Y369100D02*
Y365900D01*
G01Y372600D02*
Y369400D01*
G01Y365600D02*
Y362400D01*
G01X794763Y366000D02*
X792795Y367969D01*
G01Y364031D02*
X794763Y366000D01*
G01X792795Y367969D02*
Y364031D01*
G01X795157Y367969D02*
Y364031D01*
G01X785926Y363244D02*
Y368756D01*
G01X802074Y363244D02*
X785926D01*
G01Y368756D02*
X802074D01*
G01X783056Y382717D02*
Y376517D01*
G01X785035Y392259D02*
Y390037D01*
X785188Y389572D01*
X785495Y389262D01*
X785878Y389159D01*
X786261Y389262D01*
X786568Y389572D01*
X786721Y390037D01*
Y392259D01*
G01X788250Y391742D02*
X788480Y392052D01*
X788748Y392207D01*
X789055Y392259D01*
X789438Y392156D01*
X789706Y391897D01*
X789783Y391587D01*
X789745Y391277D01*
X789591Y391019D01*
X788825Y390502D01*
X788480Y390141D01*
X788250Y389624D01*
X788173Y389159D01*
X789783D01*
G01X792078D02*
X792346Y389211D01*
X792653Y389366D01*
X792845Y389624D01*
X792921Y389986D01*
X792845Y390347D01*
X792615Y390657D01*
X792270Y390812D01*
X791886D01*
X791656Y390916D01*
X791465Y391174D01*
X791388Y391536D01*
X791503Y391897D01*
X791771Y392156D01*
X792078Y392259D01*
X792385Y392156D01*
X792653Y391897D01*
X792768Y391536D01*
X792691Y391174D01*
X792500Y390916D01*
X792270Y390812D01*
X791886D01*
X791541Y390657D01*
X791311Y390347D01*
X791235Y389986D01*
X791311Y389624D01*
X791503Y389366D01*
X791810Y389211D01*
X792078Y389159D01*
G01X794228Y387692D02*
X800828D01*
G01X792728Y385192D02*
X794228Y387692D01*
G01X791228D02*
X792728Y385192D01*
G01X784628Y387692D02*
X791228D01*
G01X784628Y374692D02*
Y387692D01*
G01X800828Y374692D02*
X784628D01*
G01X794100Y404600D02*
Y401400D01*
G01X787900D02*
Y404600D01*
G01X794100Y401400D02*
X787900D01*
G01X796900Y390900D02*
Y394100D01*
G01X803100Y390900D02*
X796900D01*
G01Y394100D02*
X803100D01*
G01X794100Y400600D02*
Y397400D01*
G01X787900Y400600D02*
X794100D01*
G01X787900Y397400D02*
Y400600D01*
G01X794100Y397400D02*
X787900D01*
G01X796459Y397818D02*
Y400058D01*
G01X794834Y398845D02*
X798084D01*
G01X794202Y417744D02*
X788002D01*
G01D02*
Y420944D01*
G01X794202D02*
Y417744D01*
G01X788002Y416944D02*
X794202D01*
G01D02*
Y413744D01*
G01D02*
X788002D01*
G01D02*
Y416944D01*
G01X787900Y404600D02*
X794100D01*
G01X787900Y405900D02*
Y409100D01*
G01X794100Y405900D02*
X787900D01*
G01X794100Y409100D02*
Y405900D01*
G01X787900Y409100D02*
X794100D01*
G01Y413100D02*
Y409900D01*
G01X787900Y413100D02*
X794100D01*
G01X787900Y409900D02*
Y413100D01*
G01X794100Y409900D02*
X787900D01*
G01X796617Y413221D02*
Y415461D01*
G01X794992Y414248D02*
X798242D01*
G01X788002Y420944D02*
X794202D01*
G01X794252Y433744D02*
X788052D01*
G01D02*
Y436944D01*
G01X794252D02*
Y433744D01*
G01X794202Y429744D02*
X788002D01*
G01D02*
Y432944D01*
G01D02*
X794202D01*
G01D02*
Y429744D01*
G01Y425744D02*
X788002D01*
G01D02*
Y428944D01*
G01D02*
X794202D01*
G01D02*
Y425744D01*
G01Y421744D02*
X788002D01*
G01D02*
Y424944D01*
G01D02*
X794202D01*
G01D02*
Y421744D01*
G01X788052Y440944D02*
X794252D01*
G01D02*
Y437744D01*
G01D02*
X788052D01*
G01D02*
Y440944D01*
G01Y436944D02*
X794252D01*
G01X794202Y441744D02*
X788002D01*
G01D02*
Y444944D01*
G01D02*
X794202D01*
G01D02*
Y441744D01*
G01X794252Y445744D02*
X788052D01*
G01D02*
Y448944D01*
G01X794252D02*
Y445744D01*
G01X788052Y452944D02*
X794252D01*
G01D02*
Y449744D01*
G01D02*
X788052D01*
G01D02*
Y452944D01*
G01X794252Y464944D02*
Y461744D01*
G01D02*
X788052D01*
G01D02*
Y464944D01*
G01Y448944D02*
X794252D01*
G01X788052Y460944D02*
X794252D01*
G01D02*
Y457744D01*
G01D02*
X788052D01*
G01D02*
Y460944D01*
G01Y456944D02*
X794252D01*
G01D02*
Y453744D01*
G01D02*
X788052D01*
G01D02*
Y456944D01*
G01Y464944D02*
X794252D01*
G01X788052Y472944D02*
X794252D01*
G01D02*
Y469744D01*
G01D02*
X788052D01*
G01D02*
Y472944D01*
G01X788221Y469246D02*
X794421D01*
G01D02*
Y466046D01*
G01D02*
X788221D01*
G01D02*
Y469246D01*
G01X788779Y477911D02*
Y481111D01*
G01X794979Y477911D02*
X788779D01*
G01X794979Y481111D02*
Y477911D01*
G01X788562Y485058D02*
X794762D01*
G01D02*
Y481858D01*
G01D02*
X788562D01*
G01D02*
Y485058D01*
G01X788779Y481111D02*
X794979D01*
G01X788400Y505400D02*
Y508600D01*
G01X794600Y505400D02*
X788400D01*
G01X794600Y508600D02*
Y505400D01*
G01X788400Y508600D02*
X794600D01*
G01X788647Y606713D02*
Y609813D01*
G01X790257D02*
Y606713D01*
G01Y608263D02*
X788647D01*
G01X792552Y606713D02*
Y609813D01*
X792092Y609193D01*
G01Y606713D02*
X793012D01*
G01X794924Y609296D02*
X795154Y609606D01*
X795422Y609761D01*
X795729Y609813D01*
X796112Y609710D01*
X796380Y609451D01*
X796457Y609141D01*
X796419Y608831D01*
X796265Y608573D01*
X795499Y608056D01*
X795154Y607695D01*
X794924Y607178D01*
X794847Y606713D01*
X796457D01*
G01X798024Y608005D02*
X798292Y608366D01*
X798522Y608573D01*
X798829Y608676D01*
X799097Y608573D01*
X799289Y608366D01*
X799442Y608056D01*
X799480Y607695D01*
X799442Y607385D01*
X799289Y607075D01*
X799059Y606816D01*
X798790Y606713D01*
X798484Y606816D01*
X798215Y607126D01*
X798062Y607591D01*
X798024Y608108D01*
X798100Y608780D01*
X798215Y609141D01*
X798407Y609503D01*
X798675Y609761D01*
X798944Y609813D01*
X799212Y609710D01*
X799404Y609451D01*
G01X788762Y683596D02*
X788954Y683286D01*
X789184Y683079D01*
X789452Y682976D01*
X789759Y683079D01*
X789989Y683286D01*
X790219Y683596D01*
X790296Y684009D01*
Y686076D01*
G01X791786Y683596D02*
X792016Y683234D01*
X792322Y683028D01*
X792667Y682976D01*
X792974Y683028D01*
X793281Y683286D01*
X793472Y683596D01*
X793511Y683906D01*
X793434Y684268D01*
X793166Y684526D01*
X792897Y684629D01*
X792552D01*
G01X792897D02*
X793127Y684784D01*
X793319Y685043D01*
X793396Y685353D01*
X793319Y685663D01*
X793127Y685921D01*
X792782Y686076D01*
X792437Y686024D01*
X792092Y685818D01*
G01X795652Y682976D02*
X795729Y683648D01*
X795844Y684216D01*
X795997Y684733D01*
X796189Y685301D01*
X796496Y686076D01*
X794962D01*
G01X808000Y687245D02*
X791134D01*
G01D02*
Y1292680D01*
G01X787024D02*
Y687245D01*
G01X816724Y720710D02*
X791134D01*
G01X816724Y1291576D02*
X791134D01*
G01X790746Y1327062D02*
Y1330262D01*
G01X796946Y1327062D02*
X790746D01*
G01X796946Y1330262D02*
Y1327062D01*
G01X790746Y1330262D02*
X796946D01*
G01X784662Y1333091D02*
X788464D01*
G01X784662Y1333362D02*
Y1333091D01*
G01X796866D02*
Y1333362D01*
G01X793064Y1333091D02*
X796866D01*
G01X790764Y1349233D02*
X784662D01*
G01X796866Y1348962D02*
Y1349233D01*
G01D02*
X793064D01*
G01X795469Y1354980D02*
Y1360980D01*
G01X807469Y1354980D02*
X795469D01*
G01X793173Y1358396D02*
Y1352396D01*
G01X795469Y1360980D02*
X807469D01*
G01X793173Y1365296D02*
Y1359296D01*
G01X795436Y1366493D02*
Y1361893D01*
G01X805436D02*
X795436D01*
G01Y1366493D02*
X805436D01*
G01X783994Y1412557D02*
Y1406557D01*
G01X790877Y1522729D02*
X787677D01*
G01X790877Y1528929D02*
Y1522729D01*
G01X787677Y1528929D02*
X790877D01*
G01X787677Y1522729D02*
Y1528929D01*
G01X795686Y1572254D02*
Y1592472D01*
G01X783174Y1631778D02*
Y1625778D01*
X789174D01*
G01X784814Y1641478D02*
X785561Y1640853D01*
X786401Y1640478D01*
X787147D01*
X787894Y1640853D01*
X788454Y1641478D01*
X788734Y1642353D01*
X788547Y1643228D01*
X788081Y1643978D01*
X787241Y1644478D01*
X786121Y1644728D01*
X785467Y1645228D01*
X785187Y1646103D01*
X785374Y1646978D01*
X785841Y1647603D01*
X786494Y1647978D01*
X787147D01*
X787801Y1647728D01*
X788361Y1647103D01*
G01X792594Y1640228D02*
X795954Y1647978D01*
G01X799627Y1640478D02*
Y1647978D01*
X803921Y1640478D01*
Y1647978D01*
G01X789174Y1649400D02*
X783174D01*
Y1643400D01*
G01X815872Y1682410D02*
X783288D01*
G01D02*
Y1692083D01*
G01Y1717697D02*
Y1775402D01*
G01X1074272Y1734890D02*
X783288D01*
G01Y1775402D02*
X1074272D01*
G01X798926Y121994D02*
Y152998D01*
G01X802957Y151492D02*
Y149270D01*
X803110Y148805D01*
X803417Y148495D01*
X803800Y148392D01*
X804183Y148495D01*
X804490Y148805D01*
X804643Y149270D01*
Y151492D01*
G01X806172Y150975D02*
X806402Y151285D01*
X806670Y151440D01*
X806977Y151492D01*
X807360Y151389D01*
X807628Y151130D01*
X807705Y150820D01*
X807667Y150510D01*
X807513Y150252D01*
X806747Y149735D01*
X806402Y149374D01*
X806172Y148857D01*
X806095Y148392D01*
X807705D01*
G01X809272Y149684D02*
X809540Y150045D01*
X809770Y150252D01*
X810077Y150355D01*
X810345Y150252D01*
X810537Y150045D01*
X810690Y149735D01*
X810728Y149374D01*
X810690Y149064D01*
X810537Y148754D01*
X810307Y148495D01*
X810038Y148392D01*
X809732Y148495D01*
X809463Y148805D01*
X809310Y149270D01*
X809272Y149787D01*
X809348Y150459D01*
X809463Y150820D01*
X809655Y151182D01*
X809923Y151440D01*
X810192Y151492D01*
X810460Y151389D01*
X810652Y151130D01*
G01X812257Y148857D02*
X812487Y148599D01*
X812755Y148444D01*
X813100Y148392D01*
X813445Y148495D01*
X813713Y148702D01*
X813905Y149064D01*
X813943Y149477D01*
X813867Y149890D01*
X813675Y150149D01*
X813407Y150355D01*
X813138Y150407D01*
X812870Y150355D01*
X812525Y150149D01*
X812640Y151492D01*
X813675D01*
G01X810201Y366922D02*
Y370022D01*
X810967D01*
X811274Y369867D01*
X811504Y369660D01*
X811696Y369350D01*
X811849Y368989D01*
X811887Y368472D01*
X811849Y367955D01*
X811696Y367594D01*
X811504Y367284D01*
X811274Y367077D01*
X810967Y366922D01*
X810201D01*
G01X814144D02*
X814412Y366974D01*
X814719Y367129D01*
X814911Y367387D01*
X814987Y367749D01*
X814911Y368110D01*
X814681Y368420D01*
X814336Y368575D01*
X813952D01*
X813722Y368679D01*
X813531Y368937D01*
X813454Y369299D01*
X813569Y369660D01*
X813837Y369919D01*
X814144Y370022D01*
X814451Y369919D01*
X814719Y369660D01*
X814834Y369299D01*
X814757Y368937D01*
X814566Y368679D01*
X814336Y368575D01*
X813952D01*
X813607Y368420D01*
X813377Y368110D01*
X813301Y367749D01*
X813377Y367387D01*
X813569Y367129D01*
X813876Y366974D01*
X814144Y366922D01*
G01X817244Y370022D02*
X816937Y369919D01*
X816707Y369660D01*
X816554Y369350D01*
X816439Y368937D01*
X816401Y368472D01*
X816439Y368007D01*
X816554Y367594D01*
X816707Y367284D01*
X816937Y367025D01*
X817244Y366922D01*
X817551Y367025D01*
X817781Y367284D01*
X817934Y367594D01*
X818049Y368007D01*
X818087Y368472D01*
X818049Y368937D01*
X817934Y369350D01*
X817781Y369660D01*
X817551Y369919D01*
X817244Y370022D01*
G01X820344D02*
X820037Y369919D01*
X819807Y369660D01*
X819654Y369350D01*
X819539Y368937D01*
X819501Y368472D01*
X819539Y368007D01*
X819654Y367594D01*
X819807Y367284D01*
X820037Y367025D01*
X820344Y366922D01*
X820651Y367025D01*
X820881Y367284D01*
X821034Y367594D01*
X821149Y368007D01*
X821187Y368472D01*
X821149Y368937D01*
X821034Y369350D01*
X820881Y369660D01*
X820651Y369919D01*
X820344Y370022D01*
G01X822716Y368214D02*
X822984Y368575D01*
X823214Y368782D01*
X823521Y368885D01*
X823789Y368782D01*
X823981Y368575D01*
X824134Y368265D01*
X824172Y367904D01*
X824134Y367594D01*
X823981Y367284D01*
X823751Y367025D01*
X823482Y366922D01*
X823176Y367025D01*
X822907Y367335D01*
X822754Y367800D01*
X822716Y368317D01*
X822792Y368989D01*
X822907Y369350D01*
X823099Y369712D01*
X823367Y369970D01*
X823636Y370022D01*
X823904Y369919D01*
X824096Y369660D01*
G01X807689Y365950D02*
X805263D01*
G01X803226Y363250D02*
X802726D01*
G01X803226Y368750D02*
Y363250D01*
G01X802476Y368750D02*
X803226D01*
G01X802476Y363500D02*
Y368750D01*
G01X802076Y363500D02*
X802476D01*
G01X802076Y363250D02*
Y363500D01*
G01X802776Y363250D02*
X802076D01*
G01X802776Y368750D02*
Y363250D01*
G01X802126Y368750D02*
X802776D01*
G01X802126Y368650D02*
Y368750D01*
G01X802074Y368756D02*
Y363244D01*
G01X803959Y385191D02*
Y388391D01*
G01X810159Y385191D02*
X803959D01*
G01X810159Y388391D02*
Y385191D01*
G01X803959Y388391D02*
X810159D01*
G01X803966Y379420D02*
Y382620D01*
G01X810166Y379420D02*
X803966D01*
G01X810166Y382620D02*
Y379420D01*
G01X803966Y382620D02*
X810166D01*
G01X803966Y375153D02*
Y378353D01*
G01X810166Y375153D02*
X803966D01*
G01X810166Y378353D02*
Y375153D01*
G01X803966Y378353D02*
X810166D01*
G01X800828Y387692D02*
Y374692D01*
G01X803100Y394100D02*
Y390900D01*
G01X810100Y394100D02*
Y390900D01*
G01X803900Y394100D02*
X810100D01*
G01X803900Y390900D02*
Y394100D01*
G01X810100Y390900D02*
X803900D01*
G01X810900Y394100D02*
X817100D01*
G01X810900Y390900D02*
Y394100D01*
G01X817100Y390900D02*
X810900D01*
G01X807263Y399500D02*
X805295Y401469D01*
G01Y397531D02*
X807263Y399500D01*
G01X805295Y401469D02*
Y397531D01*
G01X807657Y401469D02*
Y397531D01*
G01X798426Y396744D02*
Y402256D01*
G01X814574Y396744D02*
X798426D01*
G01Y402256D02*
X814574D01*
G01X800273Y413300D02*
Y416400D01*
X801039D01*
X801346Y416245D01*
X801576Y416038D01*
X801768Y415728D01*
X801921Y415367D01*
X801959Y414850D01*
X801921Y414333D01*
X801768Y413972D01*
X801576Y413662D01*
X801346Y413455D01*
X801039Y413300D01*
X800273D01*
G01X804216D02*
X804484Y413352D01*
X804791Y413507D01*
X804983Y413765D01*
X805059Y414127D01*
X804983Y414488D01*
X804753Y414798D01*
X804408Y414953D01*
X804024D01*
X803794Y415057D01*
X803603Y415315D01*
X803526Y415677D01*
X803641Y416038D01*
X803909Y416297D01*
X804216Y416400D01*
X804523Y416297D01*
X804791Y416038D01*
X804906Y415677D01*
X804829Y415315D01*
X804638Y415057D01*
X804408Y414953D01*
X804024D01*
X803679Y414798D01*
X803449Y414488D01*
X803373Y414127D01*
X803449Y413765D01*
X803641Y413507D01*
X803948Y413352D01*
X804216Y413300D01*
G01X807316Y416400D02*
X807009Y416297D01*
X806779Y416038D01*
X806626Y415728D01*
X806511Y415315D01*
X806473Y414850D01*
X806511Y414385D01*
X806626Y413972D01*
X806779Y413662D01*
X807009Y413403D01*
X807316Y413300D01*
X807623Y413403D01*
X807853Y413662D01*
X808006Y413972D01*
X808121Y414385D01*
X808159Y414850D01*
X808121Y415315D01*
X808006Y415728D01*
X807853Y416038D01*
X807623Y416297D01*
X807316Y416400D01*
G01X810416D02*
X810109Y416297D01*
X809879Y416038D01*
X809726Y415728D01*
X809611Y415315D01*
X809573Y414850D01*
X809611Y414385D01*
X809726Y413972D01*
X809879Y413662D01*
X810109Y413403D01*
X810416Y413300D01*
X810723Y413403D01*
X810953Y413662D01*
X811106Y413972D01*
X811221Y414385D01*
X811259Y414850D01*
X811221Y415315D01*
X811106Y415728D01*
X810953Y416038D01*
X810723Y416297D01*
X810416Y416400D01*
G01X812673Y413920D02*
X812903Y413558D01*
X813209Y413352D01*
X813554Y413300D01*
X813861Y413352D01*
X814168Y413610D01*
X814359Y413920D01*
X814398Y414230D01*
X814321Y414592D01*
X814053Y414850D01*
X813784Y414953D01*
X813439D01*
G01X813784D02*
X814014Y415108D01*
X814206Y415367D01*
X814283Y415677D01*
X814206Y415987D01*
X814014Y416245D01*
X813669Y416400D01*
X813324Y416348D01*
X812979Y416142D01*
G01X806263Y409500D02*
X804295Y411469D01*
G01Y407531D02*
X806263Y409500D01*
G01X804295Y411469D02*
Y407531D01*
G01X806657Y411469D02*
Y407531D01*
G01X797426Y406744D02*
Y412256D01*
G01X813574Y406744D02*
X797426D01*
G01Y412256D02*
X813574D01*
G01X804975Y424287D02*
X811175D01*
G01D02*
Y421087D01*
G01D02*
X804975D01*
G01D02*
Y424287D01*
G01X811135Y425744D02*
X804935D01*
G01D02*
Y428944D01*
G01D02*
X811135D01*
G01D02*
Y425744D01*
G01X804786Y432944D02*
X810986D01*
G01D02*
Y429744D01*
G01D02*
X804786D01*
G01D02*
Y432944D01*
G01X811109Y434028D02*
X804909D01*
G01D02*
Y437228D01*
G01D02*
X811109D01*
G01D02*
Y434028D01*
G01X810009Y438028D02*
X803809D01*
G01D02*
Y441228D01*
G01D02*
X810009D01*
G01D02*
Y438028D01*
G01X810814Y451402D02*
Y448202D01*
G01D02*
X804614D01*
G01D02*
Y451402D01*
G01X811033Y457744D02*
X804833D01*
G01D02*
Y460944D01*
G01D02*
X811033D01*
G01D02*
Y457744D01*
G01Y453744D02*
X804833D01*
G01D02*
Y456944D01*
G01D02*
X811033D01*
G01D02*
Y453744D01*
G01X810902Y465178D02*
Y461978D01*
G01D02*
X804702D01*
G01D02*
Y465178D01*
G01X804614Y451402D02*
X810814D01*
G01X804833Y472944D02*
X811033D01*
G01D02*
Y469744D01*
G01D02*
X804833D01*
G01D02*
Y472944D01*
G01X804702Y465178D02*
X810902D01*
G01X804946Y477759D02*
X811146D01*
G01D02*
Y474559D01*
G01D02*
X804946D01*
G01D02*
Y477759D01*
G01X804833Y488944D02*
X811033D01*
G01D02*
Y485744D01*
G01D02*
X804833D01*
G01D02*
Y488944D01*
G01X804902Y492944D02*
X811102D01*
G01D02*
Y489744D01*
G01D02*
X804902D01*
G01D02*
Y492944D01*
G01X804946Y481759D02*
X811146D01*
G01D02*
Y478559D01*
G01D02*
X804946D01*
G01D02*
Y481759D01*
G01X811100Y502400D02*
X804900D01*
G01X811100Y505600D02*
Y502400D01*
G01X804900Y505600D02*
X811100D01*
G01X804900Y502400D02*
Y505600D01*
G01X805019Y496944D02*
X811219D01*
G01D02*
Y493744D01*
G01D02*
X805019D01*
G01D02*
Y496944D01*
G01X811100Y509600D02*
Y506400D01*
G01X804900D02*
Y509600D01*
G01X811100Y506400D02*
X804900D01*
G01Y510400D02*
Y513600D01*
G01X811100Y510400D02*
X804900D01*
G01X811100Y513600D02*
Y510400D01*
G01X804900Y513600D02*
X811100D01*
G01X804900Y509600D02*
X811100D01*
G01X804900Y514400D02*
Y517600D01*
G01X811100Y514400D02*
X804900D01*
G01X811100Y517600D02*
Y514400D01*
G01X804900Y517600D02*
X811100D01*
G01X808839Y522729D02*
X808787Y522422D01*
X808581Y522154D01*
X808271Y521924D01*
X807909Y521771D01*
X807496Y521694D01*
X807082D01*
X806669Y521771D01*
X806307Y521924D01*
X805997Y522154D01*
X805791Y522422D01*
X805739Y522729D01*
X805791Y523036D01*
X805997Y523304D01*
X806307Y523534D01*
X806669Y523687D01*
X807082Y523764D01*
X807496D01*
X807909Y523687D01*
X808271Y523534D01*
X808581Y523304D01*
X808787Y523036D01*
X808839Y522729D01*
G01X808012Y523036D02*
X808839Y523496D01*
G01X808219Y524986D02*
X808581Y525216D01*
X808787Y525522D01*
X808839Y525867D01*
X808787Y526174D01*
X808529Y526481D01*
X808219Y526672D01*
X807909Y526711D01*
X807547Y526634D01*
X807289Y526366D01*
X807186Y526097D01*
Y525752D01*
G01Y526097D02*
X807031Y526327D01*
X806772Y526519D01*
X806462Y526596D01*
X806152Y526519D01*
X805894Y526327D01*
X805739Y525982D01*
X805791Y525637D01*
X805997Y525292D01*
G01X806900Y532900D02*
Y536100D01*
G01X813100Y532900D02*
X806900D01*
G01Y536100D02*
X813100D01*
G01X806608Y539848D02*
Y543048D01*
G01X812808Y539848D02*
X806608D01*
G01Y543048D02*
X812808D01*
G01X811417Y560337D02*
X808217D01*
G01X811417Y566537D02*
Y560337D01*
G01X808217Y566537D02*
X811417D01*
G01X808217Y560337D02*
Y566537D01*
G01X804469Y1295127D02*
X798380D01*
G01X804469Y1323897D02*
Y1295127D01*
G01X809269Y1300116D02*
X806069D01*
G01X809269Y1306316D02*
Y1300116D01*
G01X806069Y1306316D02*
X809269D01*
G01X806069Y1300116D02*
Y1306316D01*
G01X809220Y1312886D02*
X806120D01*
Y1313806D01*
X806275Y1314113D01*
X806637Y1314343D01*
X807050Y1314420D01*
X807463Y1314343D01*
X807773Y1314151D01*
X807928Y1313806D01*
Y1312886D01*
G01X806120Y1315986D02*
X809220D01*
Y1317520D01*
G01Y1319776D02*
X808548Y1319853D01*
X807980Y1319968D01*
X807463Y1320121D01*
X806895Y1320313D01*
X806120Y1320620D01*
Y1319086D01*
G01X806637Y1322225D02*
X806327Y1322455D01*
X806172Y1322723D01*
X806120Y1323030D01*
X806223Y1323413D01*
X806482Y1323681D01*
X806792Y1323758D01*
X807102Y1323720D01*
X807360Y1323566D01*
X807877Y1322800D01*
X808238Y1322455D01*
X808755Y1322225D01*
X809220Y1322148D01*
Y1323758D01*
G01X804900Y1325400D02*
Y1331600D01*
G01X808100Y1325400D02*
X804900D01*
G01X808100Y1331600D02*
Y1325400D01*
G01X799480Y1325041D02*
X816724D01*
G01X798380Y1323867D02*
X804469D01*
G01X802764Y1339162D02*
Y1342362D01*
G01X808964Y1339162D02*
X802764D01*
G01X808964Y1342362D02*
Y1339162D01*
G01X802764Y1342362D02*
X808964D01*
G01X804900Y1331600D02*
X808100D01*
G01X802764Y1334734D02*
Y1337934D01*
G01X808964Y1334734D02*
X802764D01*
G01X808964Y1337934D02*
Y1334734D01*
G01X802764Y1337934D02*
X808964D01*
G01X797900Y1328400D02*
Y1331600D01*
G01X804100Y1328400D02*
X797900D01*
G01X804100Y1331600D02*
Y1328400D01*
G01X797900Y1331600D02*
X804100D01*
G01X814005Y1331617D02*
X810905D01*
Y1332537D01*
X811060Y1332844D01*
X811422Y1333074D01*
X811835Y1333151D01*
X812248Y1333074D01*
X812558Y1332882D01*
X812713Y1332537D01*
Y1331617D01*
G01X810905Y1334641D02*
X813127D01*
X813592Y1334794D01*
X813902Y1335101D01*
X814005Y1335484D01*
X813902Y1335867D01*
X813592Y1336174D01*
X813127Y1336327D01*
X810905D01*
G01X813540Y1337741D02*
X813798Y1337971D01*
X813953Y1338239D01*
X814005Y1338584D01*
X813902Y1338929D01*
X813695Y1339197D01*
X813333Y1339389D01*
X812920Y1339427D01*
X812507Y1339351D01*
X812248Y1339159D01*
X812042Y1338891D01*
X811990Y1338622D01*
X812042Y1338354D01*
X812248Y1338009D01*
X810905Y1338124D01*
Y1339159D01*
G01X813540Y1340841D02*
X813798Y1341071D01*
X813953Y1341339D01*
X814005Y1341684D01*
X813902Y1342029D01*
X813695Y1342297D01*
X813333Y1342489D01*
X812920Y1342527D01*
X812507Y1342451D01*
X812248Y1342259D01*
X812042Y1341991D01*
X811990Y1341722D01*
X812042Y1341454D01*
X812248Y1341109D01*
X810905Y1341224D01*
Y1342259D01*
G01X803171Y1350388D02*
Y1353588D01*
G01X809371Y1350388D02*
X803171D01*
G01X809371Y1353588D02*
Y1350388D01*
G01X803171Y1353588D02*
X809371D01*
G01X810926Y1349853D02*
X814126D01*
G01X810926Y1343653D02*
Y1349853D01*
G01X814126Y1343653D02*
X810926D01*
G01X806926Y1349853D02*
X810126D01*
G01X806926Y1343653D02*
Y1349853D01*
G01X810126Y1343653D02*
X806926D01*
G01X810126Y1349853D02*
Y1343653D01*
G01X802859Y1349855D02*
X806059Y1349851D01*
G01X802853Y1343655D02*
X802859Y1349855D01*
G01X806053Y1343651D02*
X802853Y1343655D01*
G01X806059Y1349851D02*
X806053Y1343651D01*
G01X807469Y1360980D02*
Y1354980D01*
G01X806311Y1362593D02*
Y1365793D01*
G01X812511Y1362593D02*
X806311D01*
G01Y1365793D02*
X812511D01*
G01X805436Y1366493D02*
Y1361893D01*
G01Y1361993D02*
Y1361893D01*
G01X799814Y1405805D02*
X809475Y1396144D01*
Y1396759D01*
X800353Y1405881D01*
Y1405937D01*
X800879D01*
X809532Y1397284D01*
Y1397209D01*
X809550Y1397227D01*
Y1397886D01*
X801536Y1405900D01*
X802090D01*
X809561Y1398429D01*
X809626D01*
Y1399030D01*
X802907Y1405749D01*
X802831D01*
X802906Y1405674D01*
X803525D01*
X809494Y1399705D01*
Y1399387D01*
X809588Y1399481D01*
Y1400344D01*
X804294Y1405638D01*
X803963D01*
X803981Y1405656D01*
X804882D01*
X809687Y1400851D01*
Y1400701D01*
X809669Y1400719D01*
Y1401527D01*
X805464Y1405732D01*
X805051D01*
X805126Y1405807D01*
X805933D01*
X809556Y1402184D01*
Y1401996D01*
X809575Y1402015D01*
Y1402897D01*
X806759Y1405713D01*
X806421D01*
X806533Y1405825D01*
X807191D01*
X809537Y1403479D01*
Y1404230D01*
X807979Y1405788D01*
X807585D01*
X807698Y1405675D01*
X808542D01*
X809518Y1404699D01*
Y1404680D01*
X809443Y1404755D01*
Y1405375D01*
X809105Y1405713D01*
X808937D01*
X808993Y1405769D01*
X809424D01*
X809612Y1405581D01*
G01X801536Y1405900D02*
Y1405879D01*
X809529Y1397886D01*
X809550D01*
G01X802090Y1405900D02*
X802981D01*
X809626Y1399255D01*
Y1399030D01*
X809401D01*
X802626Y1405805D01*
X798790D01*
X798687Y1405702D01*
X798865D01*
X809553Y1395014D01*
Y1395558D01*
X799306Y1405805D01*
X799814D01*
X809475Y1396144D01*
Y1396046D01*
G01X803525Y1405674D02*
X804258D01*
X809588Y1400344D01*
Y1399799D01*
X809494Y1399705D01*
X808713Y1400486D01*
Y1400925D01*
X808150Y1401488D01*
X807963D01*
X803963Y1405488D01*
Y1405638D01*
X805416D01*
X809669Y1401385D01*
Y1400719D01*
X808783Y1401605D01*
Y1401633D01*
X804778Y1405638D01*
X804294D01*
G01X806759Y1405713D02*
Y1405019D01*
X809575Y1402203D01*
X809537D01*
X809556Y1402184D01*
X809575Y1402203D01*
Y1402897D01*
X806759Y1405713D01*
X806421D01*
X806496Y1405788D01*
X807979D01*
X807866Y1405675D01*
X807698D01*
X809143Y1404230D01*
X809537D01*
Y1403479D01*
X809424Y1403592D01*
G01X798071Y1406063D02*
X809882Y1394252D01*
G01D02*
Y1406063D01*
G01D02*
X798071D01*
G01X872736Y1420331D02*
G02I-31496J0D01*
G01X809747Y1449818D02*
Y1452918D01*
G01X811357D02*
Y1449818D01*
G01Y1451368D02*
X809747D01*
G01X813652Y1449818D02*
Y1452918D01*
X813192Y1452298D01*
G01Y1449818D02*
X814112D01*
G01X816752D02*
Y1452918D01*
X816292Y1452298D01*
G01Y1449818D02*
X817212D01*
G01X819852D02*
Y1452918D01*
X819392Y1452298D01*
G01Y1449818D02*
X820312D01*
G01X803050Y1572233D02*
X809250D01*
G01D02*
Y1569033D01*
G01X803050D02*
Y1572233D01*
G01X809250Y1569033D02*
X803050D01*
G01X814350Y1580333D02*
X811150D01*
G01D02*
Y1586533D01*
G01X803050Y1573033D02*
Y1576233D01*
G01X809250Y1573033D02*
X803050D01*
G01X809250Y1576233D02*
Y1573033D01*
G01X803050Y1576233D02*
X809250D01*
G01Y1584233D02*
Y1581033D01*
G01X803050D02*
Y1584233D01*
G01X809250Y1581033D02*
X803050D01*
G01X809250Y1580233D02*
Y1577033D01*
G01X803050Y1580233D02*
X809250D01*
G01X803050Y1577033D02*
Y1580233D01*
G01X809250Y1577033D02*
X803050D01*
G01X811150Y1586533D02*
X814350D01*
G01X809250Y1596233D02*
Y1593033D01*
G01X803050Y1596233D02*
X809250D01*
G01X803050Y1593033D02*
Y1596233D01*
G01X809250Y1593033D02*
X803050D01*
G01Y1589033D02*
Y1592233D01*
G01X809250Y1589033D02*
X803050D01*
G01X809250Y1592233D02*
Y1589033D01*
G01X803050Y1592233D02*
X809250D01*
G01X803050Y1584233D02*
X809250D01*
G01X803050Y1604233D02*
X809250D01*
G01D02*
Y1601033D01*
G01X803050D02*
Y1604233D01*
G01X809250Y1601033D02*
X803050D01*
G01Y1597033D02*
Y1600233D01*
G01X809250Y1597033D02*
X803050D01*
G01X809250Y1600233D02*
Y1597033D01*
G01X803050Y1600233D02*
X809250D01*
G01X803050Y1605033D02*
Y1608233D01*
G01X809250Y1605033D02*
X803050D01*
G01X809250Y1608233D02*
Y1605033D01*
G01X803050Y1608233D02*
X809250D01*
G01X800929Y1654057D02*
Y1661557D01*
X803169D01*
X803916Y1661182D01*
X804476Y1660307D01*
X804663Y1659307D01*
X804476Y1658307D01*
X804009Y1657557D01*
X803169Y1657182D01*
X800929D01*
G01X810296Y1654057D02*
X809736Y1654182D01*
X809176Y1654682D01*
X808803Y1655557D01*
X808616Y1656557D01*
X808803Y1657557D01*
X809176Y1658432D01*
X809736Y1658932D01*
X810296Y1659057D01*
X810856Y1658932D01*
X811416Y1658432D01*
X811789Y1657557D01*
X811883Y1656557D01*
X811789Y1655557D01*
X811416Y1654682D01*
X810856Y1654182D01*
X810296Y1654057D01*
G01X815463Y1659057D02*
X816583Y1654057D01*
X817796Y1659057D01*
X819009Y1654057D01*
X820129Y1659057D01*
G01X823896Y1657432D02*
X826883D01*
X826603Y1658307D01*
X826136Y1658807D01*
X825483Y1659057D01*
X824829Y1658932D01*
X824269Y1658557D01*
X823896Y1657682D01*
X823709Y1656932D01*
Y1656182D01*
X823896Y1655432D01*
X824363Y1654682D01*
X824923Y1654182D01*
X825576Y1654057D01*
X826229Y1654307D01*
X826883Y1655057D01*
G01X831489Y1654057D02*
Y1659057D01*
G01Y1658057D02*
X831956Y1658557D01*
X832423Y1658932D01*
X833076Y1659057D01*
X833543Y1658932D01*
X834103Y1658557D01*
G01X849849Y1660932D02*
X849289Y1661307D01*
X848636Y1661557D01*
X847889D01*
X847049Y1661182D01*
X846396Y1660557D01*
X845929Y1659807D01*
X845556Y1658557D01*
X845463Y1657432D01*
X845649Y1656307D01*
X845929Y1655557D01*
X846489Y1654807D01*
X847143Y1654307D01*
X847796Y1654057D01*
X848449D01*
X849103Y1654307D01*
X849663Y1654682D01*
X850129Y1655182D01*
G01X855296Y1654057D02*
X854736Y1654182D01*
X854176Y1654682D01*
X853803Y1655557D01*
X853616Y1656557D01*
X853803Y1657557D01*
X854176Y1658432D01*
X854736Y1658932D01*
X855296Y1659057D01*
X855856Y1658932D01*
X856416Y1658432D01*
X856789Y1657557D01*
X856883Y1656557D01*
X856789Y1655557D01*
X856416Y1654682D01*
X855856Y1654182D01*
X855296Y1654057D01*
G01X861209D02*
Y1659057D01*
G01Y1657807D02*
X861583Y1658432D01*
X862143Y1658932D01*
X862889Y1659057D01*
X863543Y1658932D01*
X864103Y1658432D01*
X864383Y1657557D01*
Y1654057D01*
G01X868709D02*
Y1659057D01*
G01Y1657807D02*
X869083Y1658432D01*
X869643Y1658932D01*
X870389Y1659057D01*
X871043Y1658932D01*
X871603Y1658432D01*
X871883Y1657557D01*
Y1654057D01*
G01X819467Y-22930D02*
X819777Y-22738D01*
X819984Y-22508D01*
X820087Y-22240D01*
X819984Y-21933D01*
X819777Y-21703D01*
X819467Y-21473D01*
X819054Y-21396D01*
X816987D01*
G01X820087Y-19140D02*
X819415Y-19063D01*
X818847Y-18948D01*
X818330Y-18795D01*
X817762Y-18603D01*
X816987Y-18296D01*
Y-19830D01*
G01X819725Y-16615D02*
X819984Y-16346D01*
X820087Y-16040D01*
X819984Y-15733D01*
X819674Y-15465D01*
X819209Y-15273D01*
X818744Y-15196D01*
X818175D01*
X817710Y-15273D01*
X817297Y-15465D01*
X817090Y-15695D01*
X816987Y-15963D01*
X817090Y-16270D01*
X817297Y-16500D01*
X817607Y-16653D01*
X818020Y-16730D01*
X818382Y-16653D01*
X818744Y-16461D01*
X818950Y-16231D01*
X819002Y-15963D01*
X818899Y-15656D01*
X818640Y-15426D01*
X818175Y-15196D01*
G01X819845Y-4036D02*
X820155Y-3844D01*
X820362Y-3614D01*
X820465Y-3346D01*
X820362Y-3039D01*
X820155Y-2809D01*
X819845Y-2579D01*
X819432Y-2502D01*
X817365D01*
G01X820465Y-246D02*
X819793Y-169D01*
X819225Y-54D01*
X818708Y99D01*
X818140Y291D01*
X817365Y598D01*
Y-936D01*
G01X820000Y2088D02*
X820258Y2318D01*
X820413Y2586D01*
X820465Y2931D01*
X820362Y3276D01*
X820155Y3544D01*
X819793Y3736D01*
X819380Y3774D01*
X818967Y3698D01*
X818708Y3506D01*
X818502Y3238D01*
X818450Y2969D01*
X818502Y2701D01*
X818708Y2356D01*
X817365Y2471D01*
Y3506D01*
G01X820143Y16650D02*
X820453Y16842D01*
X820660Y17072D01*
X820763Y17340D01*
X820660Y17647D01*
X820453Y17877D01*
X820143Y18107D01*
X819730Y18184D01*
X817663D01*
G01X820763Y20440D02*
X820091Y20517D01*
X819523Y20632D01*
X819006Y20785D01*
X818438Y20977D01*
X817663Y21284D01*
Y19750D01*
G01X820763Y23617D02*
X820711Y23885D01*
X820556Y24192D01*
X820298Y24384D01*
X819936Y24460D01*
X819575Y24384D01*
X819265Y24154D01*
X819110Y23809D01*
Y23425D01*
X819006Y23195D01*
X818748Y23004D01*
X818386Y22927D01*
X818025Y23042D01*
X817766Y23310D01*
X817663Y23617D01*
X817766Y23924D01*
X818025Y24192D01*
X818386Y24307D01*
X818748Y24230D01*
X819006Y24039D01*
X819110Y23809D01*
Y23425D01*
X819265Y23080D01*
X819575Y22850D01*
X819936Y22774D01*
X820298Y22850D01*
X820556Y23042D01*
X820711Y23349D01*
X820763Y23617D01*
G01X820714Y116098D02*
X817514D01*
G01X820714Y122298D02*
Y116098D01*
G01X817514D02*
Y122298D01*
G01X824714Y116098D02*
X821514D01*
G01X824714Y122298D02*
Y116098D01*
G01X821514D02*
Y122298D01*
G01X828714Y116098D02*
X825514D01*
G01D02*
Y122298D01*
G01X817514D02*
X820714D01*
G01X821514D02*
X824714D01*
G01X825514D02*
X828714D01*
G01X817608Y130992D02*
Y132945D01*
G01X819561Y130992D02*
X817608D01*
G01X828214Y145598D02*
X825014D01*
G01D02*
Y151798D01*
G01X817608Y142804D02*
X819561D01*
G01X817608Y140851D02*
Y142804D01*
G01X825014Y151798D02*
X828214D01*
G01X832820Y165262D02*
X826620D01*
G01D02*
Y168462D01*
G01D02*
X832820D01*
G01X826620Y177962D02*
X832820D01*
G01Y174762D02*
X826620D01*
G01D02*
Y177962D01*
G01X817100Y394100D02*
Y390900D01*
G01X825583Y406947D02*
X831783D01*
Y403747D01*
X825583D01*
Y406947D01*
G01X819454Y406222D02*
X817028D01*
G01X818766Y395426D02*
Y398526D01*
X819532D01*
X819839Y398371D01*
X820069Y398164D01*
X820261Y397854D01*
X820414Y397493D01*
X820452Y396976D01*
X820414Y396459D01*
X820261Y396098D01*
X820069Y395788D01*
X819839Y395581D01*
X819532Y395426D01*
X818766D01*
G01X822709D02*
X822977Y395478D01*
X823284Y395633D01*
X823476Y395891D01*
X823552Y396253D01*
X823476Y396614D01*
X823246Y396924D01*
X822901Y397079D01*
X822517D01*
X822287Y397183D01*
X822096Y397441D01*
X822019Y397803D01*
X822134Y398164D01*
X822402Y398423D01*
X822709Y398526D01*
X823016Y398423D01*
X823284Y398164D01*
X823399Y397803D01*
X823322Y397441D01*
X823131Y397183D01*
X822901Y397079D01*
X822517D01*
X822172Y396924D01*
X821942Y396614D01*
X821866Y396253D01*
X821942Y395891D01*
X822134Y395633D01*
X822441Y395478D01*
X822709Y395426D01*
G01X825809Y398526D02*
X825502Y398423D01*
X825272Y398164D01*
X825119Y397854D01*
X825004Y397441D01*
X824966Y396976D01*
X825004Y396511D01*
X825119Y396098D01*
X825272Y395788D01*
X825502Y395529D01*
X825809Y395426D01*
X826116Y395529D01*
X826346Y395788D01*
X826499Y396098D01*
X826614Y396511D01*
X826652Y396976D01*
X826614Y397441D01*
X826499Y397854D01*
X826346Y398164D01*
X826116Y398423D01*
X825809Y398526D01*
G01X828909D02*
X828602Y398423D01*
X828372Y398164D01*
X828219Y397854D01*
X828104Y397441D01*
X828066Y396976D01*
X828104Y396511D01*
X828219Y396098D01*
X828372Y395788D01*
X828602Y395529D01*
X828909Y395426D01*
X829216Y395529D01*
X829446Y395788D01*
X829599Y396098D01*
X829714Y396511D01*
X829752Y396976D01*
X829714Y397441D01*
X829599Y397854D01*
X829446Y398164D01*
X829216Y398423D01*
X828909Y398526D01*
G01X832469Y395426D02*
Y398526D01*
X831051Y396304D01*
X832967D01*
G01X820189Y399450D02*
X817763D01*
G01X815726Y396750D02*
X815226D01*
G01X815726Y402250D02*
Y396750D01*
G01X814976Y402250D02*
X815726D01*
G01X814976Y397000D02*
Y402250D01*
G01X814576Y397000D02*
X814976D01*
G01X814576Y396750D02*
Y397000D01*
G01X815276Y396750D02*
X814576D01*
G01X815276Y402250D02*
Y396750D01*
G01X814626Y402250D02*
X815276D01*
G01X814626Y402150D02*
Y402250D01*
G01X814574Y402256D02*
Y396744D01*
G01X819319Y416944D02*
X825519D01*
G01D02*
Y413744D01*
G01D02*
X819319D01*
G01D02*
Y416944D01*
G01X825519Y420944D02*
Y417744D01*
G01D02*
X819319D01*
G01D02*
Y420944D01*
G01X824600Y411100D02*
Y407900D01*
G01X818400Y411100D02*
X824600D01*
G01X818400Y407900D02*
Y411100D01*
G01X824600Y407900D02*
X818400D01*
G01X825400Y411100D02*
X831600D01*
G01X825400Y407900D02*
Y411100D01*
G01X831600Y407900D02*
X825400D01*
G01X814726Y406750D02*
X814226D01*
G01X814726Y412250D02*
Y406750D01*
G01X813976Y412250D02*
X814726D01*
G01X813976Y407000D02*
Y412250D01*
G01X813576Y407000D02*
X813976D01*
G01X813576Y406750D02*
Y407000D01*
G01X814276Y406750D02*
X813576D01*
G01X814276Y412250D02*
Y406750D01*
G01X813626Y412250D02*
X814276D01*
G01X813626Y412150D02*
Y412250D01*
G01X813574Y412256D02*
Y406744D01*
G01X819311Y421499D02*
Y424699D01*
G01X825511Y421499D02*
X819311D01*
G01X825511Y424699D02*
Y421499D01*
G01X819311Y424699D02*
X825511D01*
G01X825519Y425744D02*
X819319D01*
G01D02*
Y428944D01*
G01D02*
X825519D01*
G01D02*
Y425744D01*
G01Y429744D02*
X819319D01*
G01D02*
Y432944D01*
G01D02*
X825519D01*
G01D02*
Y429744D01*
G01X819319Y420944D02*
X825519D01*
G01Y441952D02*
X819319D01*
G01D02*
Y445152D01*
G01D02*
X825519D01*
G01D02*
Y441952D01*
G01Y448202D02*
X819319D01*
G01D02*
Y451402D01*
G01X825519D02*
Y448202D01*
G01X825646Y437679D02*
X819446D01*
G01D02*
Y440879D01*
G01D02*
X825646D01*
G01D02*
Y437679D01*
G01X825519Y434028D02*
X819319D01*
G01D02*
Y437228D01*
G01D02*
X825519D01*
G01D02*
Y434028D01*
G01X819319Y456944D02*
X825519D01*
G01D02*
Y453744D01*
G01D02*
X819319D01*
G01D02*
Y456944D01*
G01Y451402D02*
X825519D01*
G01X825458Y465178D02*
Y461978D01*
G01D02*
X819258D01*
G01D02*
Y465178D01*
G01X825519Y457744D02*
X819319D01*
G01D02*
Y460944D01*
G01D02*
X825519D01*
G01D02*
Y457744D01*
G01X819258Y472944D02*
X825458D01*
G01D02*
Y469744D01*
G01D02*
X819258D01*
G01D02*
Y472944D01*
G01Y469168D02*
X825458D01*
G01D02*
Y465968D01*
G01D02*
X819258D01*
G01D02*
Y469168D01*
G01Y465178D02*
X825458D01*
G01X831985Y484626D02*
X818631D01*
G01D02*
Y493484D01*
G01X826068Y499512D02*
X832268D01*
G01Y496312D02*
X826068D01*
G01D02*
Y499512D01*
G01X826100Y506900D02*
X822900D01*
G01X826100Y513100D02*
Y506900D01*
G01X822900D02*
Y513100D01*
G01X822100Y506900D02*
X818900D01*
G01X822100Y513100D02*
Y506900D01*
G01X818900D02*
Y513100D01*
G01X816034Y502277D02*
Y500055D01*
X816187Y499590D01*
X816494Y499280D01*
X816877Y499177D01*
X817260Y499280D01*
X817567Y499590D01*
X817720Y500055D01*
Y502277D01*
G01X819900Y499177D02*
X819977Y499849D01*
X820092Y500417D01*
X820245Y500934D01*
X820437Y501502D01*
X820744Y502277D01*
X819210D01*
G01X822234Y499642D02*
X822464Y499384D01*
X822732Y499229D01*
X823077Y499177D01*
X823422Y499280D01*
X823690Y499487D01*
X823882Y499849D01*
X823920Y500262D01*
X823844Y500675D01*
X823652Y500934D01*
X823384Y501140D01*
X823115Y501192D01*
X822847Y501140D01*
X822502Y500934D01*
X822617Y502277D01*
X823652D01*
G01X818631Y493484D02*
X831985D01*
G01X822900Y513100D02*
X826100D01*
G01X818900D02*
X822100D01*
G01X824331Y519253D02*
X815669D01*
G01X824331Y529747D02*
Y519253D01*
G01X815669Y522600D02*
X817869Y524500D01*
G01X815669Y519253D02*
Y522600D01*
G01X813100Y536100D02*
Y532900D01*
G01X815669Y529747D02*
X824331D01*
G01X815669Y526400D02*
Y529747D01*
G01X817869Y524500D02*
X815669Y526400D01*
G01X819618Y533966D02*
Y545778D01*
G01X832242Y533966D02*
X819618D01*
G01X812808Y543048D02*
Y539848D01*
G01X819618Y545778D02*
X832242D01*
G01X819934Y568847D02*
X819627Y568899D01*
X819359Y569105D01*
X819129Y569415D01*
X818976Y569777D01*
X818899Y570190D01*
Y570604D01*
X818976Y571017D01*
X819129Y571379D01*
X819359Y571689D01*
X819627Y571895D01*
X819934Y571947D01*
X820241Y571895D01*
X820509Y571689D01*
X820739Y571379D01*
X820892Y571017D01*
X820969Y570604D01*
Y570190D01*
X820892Y569777D01*
X820739Y569415D01*
X820509Y569105D01*
X820241Y568899D01*
X819934Y568847D01*
G01X820241Y569674D02*
X820701Y568847D01*
G01X822191Y569312D02*
X822421Y569054D01*
X822689Y568899D01*
X823034Y568847D01*
X823379Y568950D01*
X823647Y569157D01*
X823839Y569519D01*
X823877Y569932D01*
X823801Y570345D01*
X823609Y570604D01*
X823341Y570810D01*
X823072Y570862D01*
X822804Y570810D01*
X822459Y570604D01*
X822574Y571947D01*
X823609D01*
G01X826594Y568847D02*
Y571947D01*
X825176Y569725D01*
X827092D01*
G01X831596Y555441D02*
X818972D01*
G01D02*
Y567253D01*
G01D02*
X831596D01*
G01X816724Y687245D02*
X814000D01*
G01X816724Y690500D02*
Y687245D01*
G01Y1325041D02*
Y695500D01*
G01X814126Y1349853D02*
Y1343653D01*
G01X812511Y1365793D02*
Y1362593D01*
G01X817866Y1555676D02*
X814766D01*
Y1556596D01*
X814921Y1556903D01*
X815283Y1557133D01*
X815696Y1557210D01*
X816109Y1557133D01*
X816419Y1556941D01*
X816574Y1556596D01*
Y1555676D01*
G01X814766Y1558700D02*
X816988D01*
X817453Y1558853D01*
X817763Y1559160D01*
X817866Y1559543D01*
X817763Y1559926D01*
X817453Y1560233D01*
X816988Y1560386D01*
X814766D01*
G01X815283Y1561915D02*
X814973Y1562145D01*
X814818Y1562413D01*
X814766Y1562720D01*
X814869Y1563103D01*
X815128Y1563371D01*
X815438Y1563448D01*
X815748Y1563410D01*
X816006Y1563256D01*
X816523Y1562490D01*
X816884Y1562145D01*
X817401Y1561915D01*
X817866Y1561838D01*
Y1563448D01*
G01Y1565743D02*
X817814Y1566011D01*
X817659Y1566318D01*
X817401Y1566510D01*
X817039Y1566586D01*
X816678Y1566510D01*
X816368Y1566280D01*
X816213Y1565935D01*
Y1565551D01*
X816109Y1565321D01*
X815851Y1565130D01*
X815489Y1565053D01*
X815128Y1565168D01*
X814869Y1565436D01*
X814766Y1565743D01*
X814869Y1566050D01*
X815128Y1566318D01*
X815489Y1566433D01*
X815851Y1566356D01*
X816109Y1566165D01*
X816213Y1565935D01*
Y1565551D01*
X816368Y1565206D01*
X816678Y1564976D01*
X817039Y1564900D01*
X817401Y1564976D01*
X817659Y1565168D01*
X817814Y1565475D01*
X817866Y1565743D01*
G01Y1568843D02*
X817814Y1569111D01*
X817659Y1569418D01*
X817401Y1569610D01*
X817039Y1569686D01*
X816678Y1569610D01*
X816368Y1569380D01*
X816213Y1569035D01*
Y1568651D01*
X816109Y1568421D01*
X815851Y1568230D01*
X815489Y1568153D01*
X815128Y1568268D01*
X814869Y1568536D01*
X814766Y1568843D01*
X814869Y1569150D01*
X815128Y1569418D01*
X815489Y1569533D01*
X815851Y1569456D01*
X816109Y1569265D01*
X816213Y1569035D01*
Y1568651D01*
X816368Y1568306D01*
X816678Y1568076D01*
X817039Y1568000D01*
X817401Y1568076D01*
X817659Y1568268D01*
X817814Y1568575D01*
X817866Y1568843D01*
G01X814350Y1586533D02*
Y1580333D01*
G01X817468Y1592472D02*
Y1572254D01*
G01D02*
X837686D01*
G01Y1592472D02*
X817468D01*
G01X841302Y-11871D02*
Y-28151D01*
X831702D01*
Y-11871D01*
X841302D01*
G01Y8129D02*
Y-8151D01*
X831702D01*
Y8129D01*
X841302D01*
G01Y28129D02*
Y11849D01*
X831702D01*
Y28129D01*
X841302D01*
G01X829862Y60232D02*
X836062D01*
G01D02*
Y57032D01*
G01D02*
X829862D01*
G01D02*
Y60232D01*
G01X838676Y61088D02*
X837776D01*
G01D02*
Y78808D01*
G01X833140Y67443D02*
Y61243D01*
G01D02*
X829940D01*
G01D02*
Y67443D01*
G01D02*
X833140D01*
G01X841926Y88851D02*
X835726D01*
G01D02*
Y92051D01*
G01X841926D02*
Y88851D01*
G01X837776Y78808D02*
X838676D01*
G01X836216Y108881D02*
Y102681D01*
G01D02*
X833016D01*
G01D02*
Y108881D01*
G01X835726Y92051D02*
X841926D01*
G01X838240Y108888D02*
Y96714D01*
X853590D01*
Y108888D01*
X838240D01*
G01X833016Y108881D02*
X836216D01*
G01X832714Y116098D02*
X829514D01*
G01X832714Y122298D02*
Y116098D01*
G01X829514D02*
Y122298D01*
G01X840960Y115982D02*
X837760D01*
G01X840960Y122182D02*
Y115982D01*
G01X837760D02*
Y122182D01*
G01X828714Y122298D02*
Y116098D01*
G01X833514D02*
Y122298D01*
G01X836714Y116098D02*
X833514D01*
G01X836714Y122298D02*
Y116098D01*
G01X837620Y130962D02*
X843820D01*
G01X837620Y127762D02*
Y130962D01*
G01X843820Y127762D02*
X837620D01*
G01Y134262D02*
Y137462D01*
G01X843820Y134262D02*
X837620D01*
G01X829514Y122298D02*
X832714D01*
G01X837760Y122182D02*
X840960D01*
G01X833514Y122298D02*
X836714D01*
G01X829420Y130992D02*
X827467D01*
G01X829420Y132945D02*
Y130992D01*
G01X828214Y151798D02*
Y145598D01*
G01X837620Y137462D02*
X843820D01*
G01X829420Y142804D02*
Y140851D01*
G01X827467Y142804D02*
X829420D01*
G01X832820Y168462D02*
Y165262D01*
G01Y177962D02*
Y174762D01*
G01X838621Y183262D02*
Y189462D01*
G01D02*
X841821D01*
G01D02*
Y183262D01*
G01D02*
X838621D01*
G01X838620Y202462D02*
X841820D01*
G01Y196262D02*
X838620D01*
G01X841820Y202462D02*
Y196262D01*
G01X838620D02*
Y202462D01*
G01X841573Y208485D02*
Y210438D01*
G01X843526Y208485D02*
X841573D01*
G01X832115Y223468D02*
Y229668D01*
G01X835315Y223468D02*
X832115D01*
G01X835315Y229668D02*
Y223468D01*
G01X841573Y220297D02*
X843526D01*
G01X841573Y218344D02*
Y220297D01*
G01X832115Y229668D02*
X835315D01*
G01X839111Y249577D02*
X836011D01*
Y250497D01*
X836166Y250804D01*
X836528Y251034D01*
X836941Y251111D01*
X837354Y251034D01*
X837664Y250842D01*
X837819Y250497D01*
Y249577D01*
G01X839111Y252601D02*
X836011D01*
Y253367D01*
X836166Y253674D01*
X836373Y253904D01*
X836683Y254096D01*
X837044Y254249D01*
X837561Y254287D01*
X838078Y254249D01*
X838439Y254096D01*
X838749Y253904D01*
X838956Y253674D01*
X839111Y253367D01*
Y252601D01*
G01Y256544D02*
X836011D01*
X836631Y256084D01*
G01X839111D02*
Y257004D01*
G01Y259644D02*
X836011D01*
X836631Y259184D01*
G01X839111D02*
Y260104D01*
G01X838491Y261901D02*
X838853Y262131D01*
X839059Y262437D01*
X839111Y262782D01*
X839059Y263089D01*
X838801Y263396D01*
X838491Y263587D01*
X838181Y263626D01*
X837819Y263549D01*
X837561Y263281D01*
X837458Y263012D01*
Y262667D01*
G01Y263012D02*
X837303Y263242D01*
X837044Y263434D01*
X836734Y263511D01*
X836424Y263434D01*
X836166Y263242D01*
X836011Y262897D01*
X836063Y262552D01*
X836269Y262207D01*
G01X840604Y248473D02*
Y278032D01*
G01X852100Y248473D02*
X840604D01*
G01X845952Y281673D02*
Y279433D01*
G01X847577Y280646D02*
X844327D01*
G01X840604Y278032D02*
X852100D01*
G01X840600Y384400D02*
X837400D01*
G01X840600Y390600D02*
Y384400D01*
G01X837400D02*
Y390600D01*
G01X834400Y391400D02*
Y394600D01*
G01X840600Y391400D02*
X834400D01*
G01X840600Y394600D02*
Y391400D01*
G01X834400Y394600D02*
X840600D01*
G01X837400Y390600D02*
X840600D01*
G01X831600Y411100D02*
Y407900D01*
G01X841658Y437152D02*
Y433952D01*
G01X835458Y437152D02*
X841658D01*
G01X835458Y433952D02*
Y437152D01*
G01X841658Y433952D02*
X835458D01*
G01X841658Y441152D02*
Y437952D01*
G01X835458Y441152D02*
X841658D01*
G01X835458Y437952D02*
Y441152D01*
G01X841658Y437952D02*
X835458D01*
G01X841658Y445152D02*
Y441952D01*
G01X835458Y445152D02*
X841658D01*
G01X835458Y441952D02*
Y445152D01*
G01X841658Y441952D02*
X835458D01*
G01X841658Y461178D02*
Y457978D01*
G01X835458Y461178D02*
X841658D01*
G01X835458Y457978D02*
Y461178D01*
G01X841658Y457978D02*
X835458D01*
G01X841658Y457178D02*
Y453978D01*
G01X835458Y457178D02*
X841658D01*
G01X835458Y453978D02*
Y457178D01*
G01X841658Y453978D02*
X835458D01*
G01X841658Y465178D02*
Y461978D01*
G01X835458D02*
Y465178D01*
G01X841658Y461978D02*
X835458D01*
G01X840100Y476600D02*
Y473400D01*
G01X833900Y476600D02*
X840100D01*
G01X833900Y473400D02*
Y476600D01*
G01X840100Y473400D02*
X833900D01*
G01X835458Y465178D02*
X841658D01*
G01X830400Y469400D02*
Y472600D01*
G01X836600Y469400D02*
X830400D01*
G01X836600Y472600D02*
Y469400D01*
G01X830400Y472600D02*
X836600D01*
G01X839101Y492167D02*
X845301D01*
G01Y488967D02*
X839101D01*
G01D02*
Y492167D01*
G01X845186Y493061D02*
X838986D01*
G01D02*
Y496261D01*
G01X839137Y488078D02*
X845337D01*
G01Y484878D02*
X839137D01*
G01D02*
Y488078D01*
G01X839100Y483728D02*
X845300D01*
G01Y480528D02*
X839100D01*
G01D02*
Y483728D01*
G01X831985Y493484D02*
Y484626D01*
G01X832268Y499512D02*
Y496312D01*
G01X838986Y496261D02*
X845186D01*
G01X829400Y506900D02*
Y513100D01*
G01X832600Y506900D02*
X829400D01*
G01X832600Y513100D02*
Y506900D01*
G01X829400Y513100D02*
X832600D01*
G01X840272Y533585D02*
Y539785D01*
G01X843472Y533585D02*
X840272D01*
G01X832242Y545778D02*
Y533966D01*
G01X840272Y539785D02*
X843472D01*
G01X840300Y546897D02*
X843500D01*
G01X840300Y540697D02*
Y546897D01*
G01X843500Y540697D02*
X840300D01*
G01X828717Y550625D02*
Y548403D01*
X828870Y547938D01*
X829177Y547628D01*
X829560Y547525D01*
X829943Y547628D01*
X830250Y547938D01*
X830403Y548403D01*
Y550625D01*
G01X832660Y547525D02*
Y550625D01*
X832200Y550005D01*
G01Y547525D02*
X833120D01*
G01X834917Y547990D02*
X835147Y547732D01*
X835415Y547577D01*
X835760Y547525D01*
X836105Y547628D01*
X836373Y547835D01*
X836565Y548197D01*
X836603Y548610D01*
X836527Y549023D01*
X836335Y549282D01*
X836067Y549488D01*
X835798Y549540D01*
X835530Y549488D01*
X835185Y549282D01*
X835300Y550625D01*
X836335D01*
G01X838860Y547525D02*
X839128Y547577D01*
X839435Y547732D01*
X839627Y547990D01*
X839703Y548352D01*
X839627Y548713D01*
X839397Y549023D01*
X839052Y549178D01*
X838668D01*
X838438Y549282D01*
X838247Y549540D01*
X838170Y549902D01*
X838285Y550263D01*
X838553Y550522D01*
X838860Y550625D01*
X839167Y550522D01*
X839435Y550263D01*
X839550Y549902D01*
X839473Y549540D01*
X839282Y549282D01*
X839052Y549178D01*
X838668D01*
X838323Y549023D01*
X838093Y548713D01*
X838017Y548352D01*
X838093Y547990D01*
X838285Y547732D01*
X838592Y547577D01*
X838860Y547525D01*
G01X833150Y564622D02*
Y570822D01*
G01X836350Y564622D02*
X833150D01*
G01X836350Y570822D02*
Y564622D01*
G01X831596Y567253D02*
Y555441D01*
G01X833150Y570822D02*
X836350D01*
G01X837618Y1537054D02*
X834518D01*
Y1537974D01*
X834673Y1538281D01*
X835035Y1538511D01*
X835448Y1538588D01*
X835861Y1538511D01*
X836171Y1538319D01*
X836326Y1537974D01*
Y1537054D01*
G01X837618Y1540078D02*
X834518D01*
Y1540844D01*
X834673Y1541151D01*
X834880Y1541381D01*
X835190Y1541573D01*
X835551Y1541726D01*
X836068Y1541764D01*
X836585Y1541726D01*
X836946Y1541573D01*
X837256Y1541381D01*
X837463Y1541151D01*
X837618Y1540844D01*
Y1540078D01*
G01Y1544021D02*
X834518D01*
X835138Y1543561D01*
G01X837618D02*
Y1544481D01*
G01Y1547121D02*
X834518D01*
X835138Y1546661D01*
G01X837618D02*
Y1547581D01*
G01Y1550221D02*
X834518D01*
X835138Y1549761D01*
G01X837618D02*
Y1550681D01*
G01X839385Y1522985D02*
Y1550865D01*
G01X859385Y1522985D02*
X839385D01*
G01Y1550865D02*
X859385D01*
G01X837686Y1572254D02*
Y1592472D01*
G01X850872Y1682410D02*
X831688D01*
G01X849076Y61088D02*
X849976D01*
G01D02*
Y67648D01*
G01X858230Y61393D02*
X855030D01*
G01D02*
Y67593D01*
G01D02*
X858230D01*
G01X851436Y73533D02*
X853658D01*
X854123Y73686D01*
X854433Y73993D01*
X854536Y74376D01*
X854433Y74759D01*
X854123Y75066D01*
X853658Y75219D01*
X851436D01*
G01X854174Y76824D02*
X854433Y77093D01*
X854536Y77399D01*
X854433Y77706D01*
X854123Y77974D01*
X853658Y78166D01*
X853193Y78243D01*
X852624D01*
X852159Y78166D01*
X851746Y77974D01*
X851539Y77744D01*
X851436Y77476D01*
X851539Y77169D01*
X851746Y76939D01*
X852056Y76786D01*
X852469Y76709D01*
X852831Y76786D01*
X853193Y76978D01*
X853399Y77208D01*
X853451Y77476D01*
X853348Y77783D01*
X853089Y78013D01*
X852624Y78243D01*
G01X851436Y80576D02*
X851539Y80269D01*
X851798Y80039D01*
X852108Y79886D01*
X852521Y79771D01*
X852986Y79733D01*
X853451Y79771D01*
X853864Y79886D01*
X854174Y80039D01*
X854433Y80269D01*
X854536Y80576D01*
X854433Y80883D01*
X854174Y81113D01*
X853864Y81266D01*
X853451Y81381D01*
X852986Y81419D01*
X852521Y81381D01*
X852108Y81266D01*
X851798Y81113D01*
X851539Y80883D01*
X851436Y80576D01*
G01X849976Y67648D02*
X847676Y69948D01*
G01D02*
X849976Y72248D01*
G01D02*
Y78808D01*
G01Y62048D02*
Y67648D01*
G01X843336Y88651D02*
Y94851D01*
G01X846536D02*
Y88651D01*
G01D02*
X843336D01*
G01X851616Y94851D02*
Y88651D01*
G01D02*
X848416D01*
G01D02*
Y94851D01*
G01X849976Y78808D02*
X849076D01*
G01X843336Y94851D02*
X846536D01*
G01X848416D02*
X851616D01*
G01X846787Y111605D02*
X846480Y111657D01*
X846212Y111863D01*
X845982Y112173D01*
X845829Y112535D01*
X845752Y112948D01*
Y113362D01*
X845829Y113775D01*
X845982Y114137D01*
X846212Y114447D01*
X846480Y114653D01*
X846787Y114705D01*
X847094Y114653D01*
X847362Y114447D01*
X847592Y114137D01*
X847745Y113775D01*
X847822Y113362D01*
Y112948D01*
X847745Y112535D01*
X847592Y112173D01*
X847362Y111863D01*
X847094Y111657D01*
X846787Y111605D01*
G01X849082Y112018D02*
X849389Y111760D01*
X849734Y111605D01*
X850040D01*
X850347Y111760D01*
X850577Y112018D01*
X850692Y112380D01*
X850615Y112742D01*
X850424Y113052D01*
X850079Y113258D01*
X849619Y113362D01*
X849350Y113568D01*
X849235Y113930D01*
X849312Y114292D01*
X849504Y114550D01*
X849772Y114705D01*
X850040D01*
X850309Y114602D01*
X850539Y114343D01*
G01X853830Y114447D02*
X853600Y114602D01*
X853332Y114705D01*
X853025D01*
X852680Y114550D01*
X852412Y114292D01*
X852220Y113982D01*
X852067Y113465D01*
X852029Y113000D01*
X852105Y112535D01*
X852220Y112225D01*
X852450Y111915D01*
X852719Y111708D01*
X852987Y111605D01*
X853255D01*
X853524Y111708D01*
X853754Y111863D01*
X853945Y112070D01*
G01X856087Y111605D02*
Y114705D01*
X855627Y114085D01*
G01Y111605D02*
X856547D01*
G01X843820Y130962D02*
Y127762D01*
G01Y137462D02*
Y134262D01*
G01X853321D02*
X847121D01*
G01D02*
Y137462D01*
G01X853321D02*
Y134262D01*
G01Y127762D02*
X847121D01*
G01D02*
Y130962D01*
G01D02*
X853321D01*
G01D02*
Y127762D01*
G01X847121Y137462D02*
X853321D01*
G01X847220Y164362D02*
X853420D01*
G01D02*
Y161162D01*
G01D02*
X847220D01*
G01D02*
Y164362D01*
G01X848782Y183079D02*
Y180857D01*
X848935Y180392D01*
X849242Y180082D01*
X849625Y179979D01*
X850008Y180082D01*
X850315Y180392D01*
X850468Y180857D01*
Y183079D01*
G01X851997Y182562D02*
X852227Y182872D01*
X852495Y183027D01*
X852802Y183079D01*
X853185Y182976D01*
X853453Y182717D01*
X853530Y182407D01*
X853492Y182097D01*
X853338Y181839D01*
X852572Y181322D01*
X852227Y180961D01*
X851997Y180444D01*
X851920Y179979D01*
X853530D01*
G01X855748D02*
X855825Y180651D01*
X855940Y181219D01*
X856093Y181736D01*
X856285Y182304D01*
X856592Y183079D01*
X855058D01*
G01X858273Y180341D02*
X858542Y180082D01*
X858848Y179979D01*
X859155Y180082D01*
X859423Y180392D01*
X859615Y180857D01*
X859692Y181322D01*
Y181891D01*
X859615Y182356D01*
X859423Y182769D01*
X859193Y182976D01*
X858925Y183079D01*
X858618Y182976D01*
X858388Y182769D01*
X858235Y182459D01*
X858158Y182046D01*
X858235Y181684D01*
X858427Y181322D01*
X858657Y181116D01*
X858925Y181064D01*
X859232Y181167D01*
X859462Y181426D01*
X859692Y181891D01*
G01X856887Y166096D02*
X854227D01*
G01D02*
X851125Y169198D01*
G01D02*
X848125Y166096D01*
G01D02*
X845363D01*
G01D02*
Y178300D01*
G01D02*
X856887D01*
G01D02*
Y166096D01*
G01X842621Y183262D02*
Y189462D01*
G01D02*
X845821D01*
G01D02*
Y183262D01*
G01D02*
X842621D01*
G01X842620Y202462D02*
X845820D01*
G01Y196262D02*
X842620D01*
G01X845820Y202462D02*
Y196262D01*
G01X842620D02*
Y202462D01*
G01X853385Y208485D02*
X851432D01*
G01X853385Y210438D02*
Y208485D01*
G01Y220297D02*
Y218344D01*
G01X851432Y220297D02*
X853385D01*
G01X862692Y238841D02*
X856492D01*
G01D02*
Y242041D01*
G01X853076Y231068D02*
Y237068D01*
G01D02*
X865076D01*
G01Y231068D02*
X853076D01*
G01X856492Y242041D02*
X862692D01*
G01X854928Y248336D02*
Y250762D01*
G01X852100Y278032D02*
Y248473D01*
G01X860903Y267457D02*
X854703D01*
G01D02*
Y270657D01*
G01X860903Y263457D02*
X854703D01*
G01D02*
Y266657D01*
G01D02*
X860903D01*
G01X854733Y274817D02*
X860933D01*
G01Y271617D02*
X854733D01*
G01D02*
Y274817D01*
G01X861413Y281927D02*
X855213D01*
G01D02*
Y285127D01*
G01X854703Y270657D02*
X860903D01*
G01X861413Y278427D02*
X855213D01*
G01D02*
Y281627D01*
G01D02*
X861413D01*
G01X855213Y285127D02*
X861413D01*
G01X853100Y382600D02*
Y379400D01*
G01X846900Y382600D02*
X853100D01*
G01X846900Y379400D02*
Y382600D01*
G01X853100Y379400D02*
X846900D01*
G01X853100Y386600D02*
Y383400D01*
G01X846900Y386600D02*
X853100D01*
G01X846900Y383400D02*
Y386600D01*
G01X853100Y383400D02*
X846900D01*
G01X854621Y382430D02*
Y385630D01*
G01X860821Y382430D02*
X854621D01*
G01Y385630D02*
X860821D01*
G01X843100Y388669D02*
Y397331D01*
G01X854900Y388669D02*
X843100D01*
G01X854900Y397331D02*
Y388669D01*
G01X857300Y399680D02*
X851100D01*
Y402880D01*
X857300D01*
Y399680D01*
G01X843810Y398797D02*
X846032D01*
X846497Y398950D01*
X846807Y399257D01*
X846910Y399640D01*
X846807Y400023D01*
X846497Y400330D01*
X846032Y400483D01*
X843810D01*
G01X846548Y402088D02*
X846807Y402357D01*
X846910Y402663D01*
X846807Y402970D01*
X846497Y403238D01*
X846032Y403430D01*
X845567Y403507D01*
X844998D01*
X844533Y403430D01*
X844120Y403238D01*
X843913Y403008D01*
X843810Y402740D01*
X843913Y402433D01*
X844120Y402203D01*
X844430Y402050D01*
X844843Y401973D01*
X845205Y402050D01*
X845567Y402242D01*
X845773Y402472D01*
X845825Y402740D01*
X845722Y403047D01*
X845463Y403277D01*
X844998Y403507D01*
G01X843810Y405840D02*
X843913Y405533D01*
X844172Y405303D01*
X844482Y405150D01*
X844895Y405035D01*
X845360Y404997D01*
X845825Y405035D01*
X846238Y405150D01*
X846548Y405303D01*
X846807Y405533D01*
X846910Y405840D01*
X846807Y406147D01*
X846548Y406377D01*
X846238Y406530D01*
X845825Y406645D01*
X845360Y406683D01*
X844895Y406645D01*
X844482Y406530D01*
X844172Y406377D01*
X843913Y406147D01*
X843810Y405840D01*
G01Y408940D02*
X843913Y408633D01*
X844172Y408403D01*
X844482Y408250D01*
X844895Y408135D01*
X845360Y408097D01*
X845825Y408135D01*
X846238Y408250D01*
X846548Y408403D01*
X846807Y408633D01*
X846910Y408940D01*
X846807Y409247D01*
X846548Y409477D01*
X846238Y409630D01*
X845825Y409745D01*
X845360Y409783D01*
X844895Y409745D01*
X844482Y409630D01*
X844172Y409477D01*
X843913Y409247D01*
X843810Y408940D01*
G01X844327Y411312D02*
X844017Y411542D01*
X843862Y411810D01*
X843810Y412117D01*
X843913Y412500D01*
X844172Y412768D01*
X844482Y412845D01*
X844792Y412807D01*
X845050Y412653D01*
X845567Y411887D01*
X845928Y411542D01*
X846445Y411312D01*
X846910Y411235D01*
Y412845D01*
G01X843100Y397331D02*
X854900D01*
G01X850100Y453400D02*
X846900D01*
G01X850100Y459600D02*
Y453400D01*
G01X846900Y459600D02*
X850100D01*
G01X846900Y453400D02*
Y459600D01*
G01X842398Y474602D02*
X845000Y472000D01*
G01X842398Y478824D02*
Y474602D01*
G01X854602Y465176D02*
Y478824D01*
G01X842398Y465176D02*
X854602D01*
G01X842398Y469398D02*
Y465176D01*
G01X845000Y472000D02*
X842398Y469398D01*
G01X845301Y492167D02*
Y488967D01*
G01X845186Y496261D02*
Y493061D01*
G01X845337Y488078D02*
Y484878D01*
G01X845300Y483728D02*
Y480528D01*
G01X851419Y492985D02*
Y496185D01*
G01X857619Y492985D02*
X851419D01*
G01X853600Y484400D02*
X850400D01*
G01X853600Y490600D02*
Y484400D01*
G01X850400Y490600D02*
X853600D01*
G01X850400Y484400D02*
Y490600D01*
G01X854602Y478824D02*
X842398D01*
G01X850857Y508706D02*
Y505506D01*
G01D02*
X844657D01*
G01D02*
Y508706D01*
G01X851419Y496185D02*
X857619D01*
G01X851225Y501554D02*
Y504754D01*
G01X857425Y501554D02*
X851225D01*
G01Y504754D02*
X857425D01*
G01X851491Y497261D02*
Y500461D01*
G01X857691Y497261D02*
X851491D01*
G01Y500461D02*
X857691D01*
G01X847162Y522888D02*
Y529088D01*
G01X850362D02*
Y522888D01*
G01D02*
X847162D01*
G01X844657Y508706D02*
X850857D01*
G01X857362Y522813D02*
X851162D01*
G01D02*
Y526013D01*
G01X847162Y529088D02*
X850362D01*
G01X843472Y539785D02*
Y533585D01*
G01X851162Y526013D02*
X857362D01*
G01X867192Y528246D02*
X851838D01*
G01D02*
Y540924D01*
G01X843500Y546897D02*
Y540697D01*
G01X850815Y542352D02*
X850508Y542404D01*
X850240Y542610D01*
X850010Y542920D01*
X849857Y543282D01*
X849780Y543695D01*
Y544109D01*
X849857Y544522D01*
X850010Y544884D01*
X850240Y545194D01*
X850508Y545400D01*
X850815Y545452D01*
X851122Y545400D01*
X851390Y545194D01*
X851620Y544884D01*
X851773Y544522D01*
X851850Y544109D01*
Y543695D01*
X851773Y543282D01*
X851620Y542920D01*
X851390Y542610D01*
X851122Y542404D01*
X850815Y542352D01*
G01X851122Y543179D02*
X851582Y542352D01*
G01X853187Y543644D02*
X853455Y544005D01*
X853685Y544212D01*
X853992Y544315D01*
X854260Y544212D01*
X854452Y544005D01*
X854605Y543695D01*
X854643Y543334D01*
X854605Y543024D01*
X854452Y542714D01*
X854222Y542455D01*
X853953Y542352D01*
X853647Y542455D01*
X853378Y542765D01*
X853225Y543230D01*
X853187Y543747D01*
X853263Y544419D01*
X853378Y544780D01*
X853570Y545142D01*
X853838Y545400D01*
X854107Y545452D01*
X854375Y545349D01*
X854567Y545090D01*
G01X857475Y542352D02*
Y545452D01*
X856057Y543230D01*
X857973D01*
G01X851838Y540924D02*
X867192D01*
G01X859876Y1555506D02*
X856776D01*
Y1556426D01*
X856931Y1556733D01*
X857293Y1556963D01*
X857706Y1557040D01*
X858119Y1556963D01*
X858429Y1556771D01*
X858584Y1556426D01*
Y1555506D01*
G01X856776Y1558530D02*
X858998D01*
X859463Y1558683D01*
X859773Y1558990D01*
X859876Y1559373D01*
X859773Y1559756D01*
X859463Y1560063D01*
X858998Y1560216D01*
X856776D01*
G01X857293Y1561745D02*
X856983Y1561975D01*
X856828Y1562243D01*
X856776Y1562550D01*
X856879Y1562933D01*
X857138Y1563201D01*
X857448Y1563278D01*
X857758Y1563240D01*
X858016Y1563086D01*
X858533Y1562320D01*
X858894Y1561975D01*
X859411Y1561745D01*
X859876Y1561668D01*
Y1563278D01*
G01X859514Y1564921D02*
X859773Y1565190D01*
X859876Y1565496D01*
X859773Y1565803D01*
X859463Y1566071D01*
X858998Y1566263D01*
X858533Y1566340D01*
X857964D01*
X857499Y1566263D01*
X857086Y1566071D01*
X856879Y1565841D01*
X856776Y1565573D01*
X856879Y1565266D01*
X857086Y1565036D01*
X857396Y1564883D01*
X857809Y1564806D01*
X858171Y1564883D01*
X858533Y1565075D01*
X858739Y1565305D01*
X858791Y1565573D01*
X858688Y1565880D01*
X858429Y1566110D01*
X857964Y1566340D01*
G01X858584Y1567945D02*
X858223Y1568213D01*
X858016Y1568443D01*
X857913Y1568750D01*
X858016Y1569018D01*
X858223Y1569210D01*
X858533Y1569363D01*
X858894Y1569401D01*
X859204Y1569363D01*
X859514Y1569210D01*
X859773Y1568980D01*
X859876Y1568711D01*
X859773Y1568405D01*
X859463Y1568136D01*
X858998Y1567983D01*
X858481Y1567945D01*
X857809Y1568021D01*
X857448Y1568136D01*
X857086Y1568328D01*
X856828Y1568596D01*
X856776Y1568865D01*
X856879Y1569133D01*
X857138Y1569325D01*
G01X845050Y1572233D02*
X851250D01*
G01D02*
Y1569033D01*
G01X845050D02*
Y1572233D01*
G01X851250Y1569033D02*
X845050D01*
G01X856350Y1580333D02*
X853150D01*
G01X856350Y1586533D02*
Y1580333D01*
G01X853150D02*
Y1586533D01*
G01X845050Y1573033D02*
Y1576233D01*
G01X851250Y1573033D02*
X845050D01*
G01X851250Y1576233D02*
Y1573033D01*
G01X845050Y1576233D02*
X851250D01*
G01Y1580233D02*
Y1577033D01*
G01X845050Y1580233D02*
X851250D01*
G01X845050Y1577033D02*
Y1580233D01*
G01X851250Y1577033D02*
X845050D01*
G01X851250Y1584233D02*
Y1581033D01*
G01X845050D02*
Y1584233D01*
G01X851250Y1581033D02*
X845050D01*
G01X853150Y1586533D02*
X856350D01*
G01X851250Y1596233D02*
Y1593033D01*
G01X845050Y1596233D02*
X851250D01*
G01X845050Y1593033D02*
Y1596233D01*
G01X851250Y1593033D02*
X845050D01*
G01Y1589033D02*
Y1592233D01*
G01X851250Y1589033D02*
X845050D01*
G01X851250Y1592233D02*
Y1589033D01*
G01X845050Y1592233D02*
X851250D01*
G01X845050Y1584233D02*
X851250D01*
G01X845050Y1604233D02*
X851250D01*
G01D02*
Y1601033D01*
G01X845050D02*
Y1604233D01*
G01X851250Y1601033D02*
X845050D01*
G01Y1597033D02*
Y1600233D01*
G01X851250Y1597033D02*
X845050D01*
G01X851250Y1600233D02*
Y1597033D01*
G01X845050Y1600233D02*
X851250D01*
G01X845050Y1605033D02*
Y1608233D01*
G01X851250Y1605033D02*
X845050D01*
G01X851250Y1608233D02*
Y1605033D01*
G01X845050Y1608233D02*
X851250D01*
G01X858230Y67593D02*
Y61393D01*
G01X875820Y164762D02*
X869620D01*
G01D02*
Y167962D01*
G01D02*
X875820D01*
G01Y169762D02*
X869620D01*
G01D02*
Y172962D01*
G01D02*
X875820D01*
G01Y175262D02*
X869620D01*
G01D02*
Y178462D01*
G01D02*
X875820D01*
G01X860383Y229083D02*
Y222883D01*
G01X857183D02*
Y229083D01*
G01X860383Y222883D02*
X857183D01*
G01X869993Y225363D02*
Y222163D01*
G01X863793D02*
Y225363D01*
G01X869993Y222163D02*
X863793D01*
G01X859109Y215273D02*
Y213051D01*
X859262Y212586D01*
X859569Y212276D01*
X859952Y212173D01*
X860335Y212276D01*
X860642Y212586D01*
X860795Y213051D01*
Y215273D01*
G01X862324Y214756D02*
X862554Y215066D01*
X862822Y215221D01*
X863129Y215273D01*
X863512Y215170D01*
X863780Y214911D01*
X863857Y214601D01*
X863819Y214291D01*
X863665Y214033D01*
X862899Y213516D01*
X862554Y213155D01*
X862324Y212638D01*
X862247Y212173D01*
X863857D01*
G01X866075D02*
X866152Y212845D01*
X866267Y213413D01*
X866420Y213930D01*
X866612Y214498D01*
X866919Y215273D01*
X865385D01*
G01X868524Y213465D02*
X868792Y213826D01*
X869022Y214033D01*
X869329Y214136D01*
X869597Y214033D01*
X869789Y213826D01*
X869942Y213516D01*
X869980Y213155D01*
X869942Y212845D01*
X869789Y212535D01*
X869559Y212276D01*
X869290Y212173D01*
X868984Y212276D01*
X868715Y212586D01*
X868562Y213051D01*
X868524Y213568D01*
X868600Y214240D01*
X868715Y214601D01*
X868907Y214963D01*
X869175Y215221D01*
X869444Y215273D01*
X869712Y215170D01*
X869904Y214911D01*
G01X862692Y242041D02*
Y238841D01*
G01X857183Y229083D02*
X860383D01*
G01X869993Y229363D02*
Y226163D01*
G01X863793Y229363D02*
X869993D01*
G01X863793Y226163D02*
Y229363D01*
G01X869993Y226163D02*
X863793D01*
G01Y225363D02*
X869993D01*
G01X865076Y237068D02*
Y231068D01*
G01X860903Y270657D02*
Y267457D01*
G01X864894Y270636D02*
Y264436D01*
G01D02*
X861694D01*
G01D02*
Y270636D01*
G01X860903Y266657D02*
Y263457D01*
G01X867238Y268545D02*
Y271645D01*
X868158D01*
X868465Y271490D01*
X868695Y271128D01*
X868772Y270715D01*
X868695Y270302D01*
X868503Y269992D01*
X868158Y269837D01*
X867238D01*
G01X870262Y271645D02*
Y269423D01*
X870415Y268958D01*
X870722Y268648D01*
X871105Y268545D01*
X871488Y268648D01*
X871795Y268958D01*
X871948Y269423D01*
Y271645D01*
G01X873477Y271128D02*
X873707Y271438D01*
X873975Y271593D01*
X874282Y271645D01*
X874665Y271542D01*
X874933Y271283D01*
X875010Y270973D01*
X874972Y270663D01*
X874818Y270405D01*
X874052Y269888D01*
X873707Y269527D01*
X873477Y269010D01*
X873400Y268545D01*
X875010D01*
G01X876653Y268907D02*
X876922Y268648D01*
X877228Y268545D01*
X877535Y268648D01*
X877803Y268958D01*
X877995Y269423D01*
X878072Y269888D01*
Y270457D01*
X877995Y270922D01*
X877803Y271335D01*
X877573Y271542D01*
X877305Y271645D01*
X876998Y271542D01*
X876768Y271335D01*
X876615Y271025D01*
X876538Y270612D01*
X876615Y270250D01*
X876807Y269888D01*
X877037Y269682D01*
X877305Y269630D01*
X877612Y269733D01*
X877842Y269992D01*
X878072Y270457D01*
G01X879562Y269010D02*
X879792Y268752D01*
X880060Y268597D01*
X880405Y268545D01*
X880750Y268648D01*
X881018Y268855D01*
X881210Y269217D01*
X881248Y269630D01*
X881172Y270043D01*
X880980Y270302D01*
X880712Y270508D01*
X880443Y270560D01*
X880175Y270508D01*
X879830Y270302D01*
X879945Y271645D01*
X880980D01*
G01X860933Y274817D02*
Y271617D01*
G01X861413Y285127D02*
Y281927D01*
G01X861694Y270636D02*
X864894D01*
G01X861413Y281627D02*
Y278427D01*
G01X880301Y283111D02*
X866325D01*
G01D02*
Y274923D01*
G01D02*
X880301D01*
G01X865171Y298485D02*
Y292285D01*
G01D02*
X861971D01*
G01D02*
Y298485D01*
G01D02*
X865171D01*
G01X869143Y287711D02*
X862943D01*
G01D02*
Y290911D01*
G01D02*
X869143D01*
G01D02*
Y287711D01*
G01X869171Y298485D02*
Y292285D01*
G01D02*
X865971D01*
G01D02*
Y298485D01*
G01D02*
X869171D01*
G01X873100Y314900D02*
X869900D01*
G01Y321100D02*
X873100D01*
G01X869900Y314900D02*
Y321100D01*
G01X860821Y385630D02*
Y382430D01*
G01X865590Y383160D02*
Y389360D01*
X868790D01*
Y383160D01*
X865590D01*
G01X869590D02*
Y389360D01*
X872790D01*
Y383160D01*
X869590D01*
G01X857400Y393900D02*
Y397100D01*
G01X863600Y393900D02*
X857400D01*
G01X863600Y397100D02*
Y393900D01*
G01X857400Y397100D02*
X863600D01*
G01Y393100D02*
Y389900D01*
G01X857400Y393100D02*
X863600D01*
G01X857400Y389900D02*
Y393100D01*
G01X863600Y389900D02*
X857400D01*
G01X866140Y402690D02*
X868742Y400088D01*
X872964D01*
Y412292D01*
X859316D01*
Y400088D01*
X863538D01*
X866140Y402690D01*
G01X866920Y420320D02*
X873120D01*
Y417120D01*
X866920D01*
Y420320D01*
G01X862783Y464821D02*
X865005D01*
X865470Y464974D01*
X865780Y465281D01*
X865883Y465664D01*
X865780Y466047D01*
X865470Y466354D01*
X865005Y466507D01*
X862783D01*
G01X865521Y468112D02*
X865780Y468381D01*
X865883Y468687D01*
X865780Y468994D01*
X865470Y469262D01*
X865005Y469454D01*
X864540Y469531D01*
X863971D01*
X863506Y469454D01*
X863093Y469262D01*
X862886Y469032D01*
X862783Y468764D01*
X862886Y468457D01*
X863093Y468227D01*
X863403Y468074D01*
X863816Y467997D01*
X864178Y468074D01*
X864540Y468266D01*
X864746Y468496D01*
X864798Y468764D01*
X864695Y469071D01*
X864436Y469301D01*
X863971Y469531D01*
G01X862783Y471864D02*
X862886Y471557D01*
X863145Y471327D01*
X863455Y471174D01*
X863868Y471059D01*
X864333Y471021D01*
X864798Y471059D01*
X865211Y471174D01*
X865521Y471327D01*
X865780Y471557D01*
X865883Y471864D01*
X865780Y472171D01*
X865521Y472401D01*
X865211Y472554D01*
X864798Y472669D01*
X864333Y472707D01*
X863868Y472669D01*
X863455Y472554D01*
X863145Y472401D01*
X862886Y472171D01*
X862783Y471864D01*
G01Y474964D02*
X862886Y474657D01*
X863145Y474427D01*
X863455Y474274D01*
X863868Y474159D01*
X864333Y474121D01*
X864798Y474159D01*
X865211Y474274D01*
X865521Y474427D01*
X865780Y474657D01*
X865883Y474964D01*
X865780Y475271D01*
X865521Y475501D01*
X865211Y475654D01*
X864798Y475769D01*
X864333Y475807D01*
X863868Y475769D01*
X863455Y475654D01*
X863145Y475501D01*
X862886Y475271D01*
X862783Y474964D01*
G01X865883Y478064D02*
X862783D01*
X863403Y477604D01*
G01X865883D02*
Y478524D01*
G01X857619Y496185D02*
Y492985D01*
G01X857425Y504754D02*
Y501554D01*
G01X857691Y500461D02*
Y497261D01*
G01X862465Y514436D02*
Y520636D01*
G01D02*
X865665D01*
G01D02*
Y514436D01*
G01D02*
X862465D01*
G01X857362Y526013D02*
Y522813D01*
G01X867192Y540727D02*
Y528246D01*
G01X866250Y1160445D02*
Y1163545D01*
G01X867860D02*
Y1160445D01*
G01Y1161995D02*
X866250D01*
G01X870155Y1160445D02*
X870423Y1160497D01*
X870730Y1160652D01*
X870922Y1160910D01*
X870998Y1161272D01*
X870922Y1161633D01*
X870692Y1161943D01*
X870347Y1162098D01*
X869963D01*
X869733Y1162202D01*
X869542Y1162460D01*
X869465Y1162822D01*
X869580Y1163183D01*
X869848Y1163442D01*
X870155Y1163545D01*
X870462Y1163442D01*
X870730Y1163183D01*
X870845Y1162822D01*
X870768Y1162460D01*
X870577Y1162202D01*
X870347Y1162098D01*
X869963D01*
X869618Y1161943D01*
X869388Y1161633D01*
X869312Y1161272D01*
X869388Y1160910D01*
X869580Y1160652D01*
X869887Y1160497D01*
X870155Y1160445D01*
G01X874483Y1168572D02*
X871383D01*
Y1169492D01*
X871538Y1169799D01*
X871900Y1170029D01*
X872313Y1170106D01*
X872726Y1170029D01*
X873036Y1169837D01*
X873191Y1169492D01*
Y1168572D01*
G01X871383Y1171672D02*
X874483D01*
Y1173206D01*
G01X873191Y1174811D02*
X872830Y1175079D01*
X872623Y1175309D01*
X872520Y1175616D01*
X872623Y1175884D01*
X872830Y1176076D01*
X873140Y1176229D01*
X873501Y1176267D01*
X873811Y1176229D01*
X874121Y1176076D01*
X874380Y1175846D01*
X874483Y1175577D01*
X874380Y1175271D01*
X874070Y1175002D01*
X873605Y1174849D01*
X873088Y1174811D01*
X872416Y1174887D01*
X872055Y1175002D01*
X871693Y1175194D01*
X871435Y1175462D01*
X871383Y1175731D01*
X871486Y1175999D01*
X871745Y1176191D01*
G01X874018Y1177796D02*
X874276Y1178026D01*
X874431Y1178294D01*
X874483Y1178639D01*
X874380Y1178984D01*
X874173Y1179252D01*
X873811Y1179444D01*
X873398Y1179482D01*
X872985Y1179406D01*
X872726Y1179214D01*
X872520Y1178946D01*
X872468Y1178677D01*
X872520Y1178409D01*
X872726Y1178064D01*
X871383Y1178179D01*
Y1179214D01*
G01Y1181739D02*
X871486Y1181432D01*
X871745Y1181202D01*
X872055Y1181049D01*
X872468Y1180934D01*
X872933Y1180896D01*
X873398Y1180934D01*
X873811Y1181049D01*
X874121Y1181202D01*
X874380Y1181432D01*
X874483Y1181739D01*
X874380Y1182046D01*
X874121Y1182276D01*
X873811Y1182429D01*
X873398Y1182544D01*
X872933Y1182582D01*
X872468Y1182544D01*
X872055Y1182429D01*
X871745Y1182276D01*
X871486Y1182046D01*
X871383Y1181739D01*
G01X871900Y1184111D02*
X871590Y1184341D01*
X871435Y1184609D01*
X871383Y1184916D01*
X871486Y1185299D01*
X871745Y1185567D01*
X872055Y1185644D01*
X872365Y1185606D01*
X872623Y1185452D01*
X873140Y1184686D01*
X873501Y1184341D01*
X874018Y1184111D01*
X874483Y1184034D01*
Y1185644D01*
G01X873500Y1236883D02*
X870400D01*
Y1237803D01*
X870555Y1238110D01*
X870917Y1238340D01*
X871330Y1238417D01*
X871743Y1238340D01*
X872053Y1238148D01*
X872208Y1237803D01*
Y1236883D01*
G01X870658Y1241593D02*
X870503Y1241363D01*
X870400Y1241095D01*
Y1240788D01*
X870555Y1240443D01*
X870813Y1240175D01*
X871123Y1239983D01*
X871640Y1239830D01*
X872105Y1239792D01*
X872570Y1239868D01*
X872880Y1239983D01*
X873190Y1240213D01*
X873397Y1240482D01*
X873500Y1240750D01*
Y1241018D01*
X873397Y1241287D01*
X873242Y1241517D01*
X873035Y1241708D01*
G01X872208Y1243122D02*
X871847Y1243390D01*
X871640Y1243620D01*
X871537Y1243927D01*
X871640Y1244195D01*
X871847Y1244387D01*
X872157Y1244540D01*
X872518Y1244578D01*
X872828Y1244540D01*
X873138Y1244387D01*
X873397Y1244157D01*
X873500Y1243888D01*
X873397Y1243582D01*
X873087Y1243313D01*
X872622Y1243160D01*
X872105Y1243122D01*
X871433Y1243198D01*
X871072Y1243313D01*
X870710Y1243505D01*
X870452Y1243773D01*
X870400Y1244042D01*
X870503Y1244310D01*
X870762Y1244502D01*
G01X873500Y1246950D02*
X873448Y1247218D01*
X873293Y1247525D01*
X873035Y1247717D01*
X872673Y1247793D01*
X872312Y1247717D01*
X872002Y1247487D01*
X871847Y1247142D01*
Y1246758D01*
X871743Y1246528D01*
X871485Y1246337D01*
X871123Y1246260D01*
X870762Y1246375D01*
X870503Y1246643D01*
X870400Y1246950D01*
X870503Y1247257D01*
X870762Y1247525D01*
X871123Y1247640D01*
X871485Y1247563D01*
X871743Y1247372D01*
X871847Y1247142D01*
Y1246758D01*
X872002Y1246413D01*
X872312Y1246183D01*
X872673Y1246107D01*
X873035Y1246183D01*
X873293Y1246375D01*
X873448Y1246682D01*
X873500Y1246950D01*
G01X870400Y1250050D02*
X870503Y1249743D01*
X870762Y1249513D01*
X871072Y1249360D01*
X871485Y1249245D01*
X871950Y1249207D01*
X872415Y1249245D01*
X872828Y1249360D01*
X873138Y1249513D01*
X873397Y1249743D01*
X873500Y1250050D01*
X873397Y1250357D01*
X873138Y1250587D01*
X872828Y1250740D01*
X872415Y1250855D01*
X871950Y1250893D01*
X871485Y1250855D01*
X871072Y1250740D01*
X870762Y1250587D01*
X870503Y1250357D01*
X870400Y1250050D01*
G01X873500Y1253610D02*
X870400D01*
X872622Y1252192D01*
Y1254108D01*
G01X859385Y1550865D02*
Y1522985D01*
G01X859468Y1592472D02*
Y1572254D01*
G01D02*
X879686D01*
G01Y1592472D02*
X859468D01*
G01X885872Y1682410D02*
X866688D01*
G01X875820Y167962D02*
Y164762D01*
G01X877620Y172962D02*
X883820D01*
G01D02*
Y169762D01*
G01D02*
X877620D01*
G01D02*
Y172962D01*
G01Y178462D02*
X883820D01*
G01D02*
Y175262D01*
G01D02*
X877620D01*
G01D02*
Y178462D01*
G01X875820Y172962D02*
Y169762D01*
G01Y178462D02*
Y175262D01*
G01X885825Y190455D02*
X879625D01*
G01D02*
Y193655D01*
G01D02*
X885825D01*
G01D02*
Y190455D01*
G01X879625Y189049D02*
X885825D01*
G01D02*
Y185849D01*
G01D02*
X879625D01*
G01D02*
Y189049D01*
G01X879615Y184769D02*
X885815D01*
G01D02*
Y181569D01*
G01D02*
X879615D01*
G01D02*
Y184769D01*
G01X874783Y241435D02*
Y210431D01*
X889583D01*
Y241435D01*
X874783D01*
G01X874883Y243000D02*
Y246100D01*
X875842D01*
X876148Y245945D01*
X876340Y245738D01*
X876417Y245325D01*
X876340Y244912D01*
X876110Y244653D01*
X875842Y244498D01*
X874883D01*
G01X875842D02*
X876417Y243000D01*
G01X877907Y243620D02*
X878137Y243258D01*
X878443Y243052D01*
X878788Y243000D01*
X879095Y243052D01*
X879402Y243310D01*
X879593Y243620D01*
X879632Y243930D01*
X879555Y244292D01*
X879287Y244550D01*
X879018Y244653D01*
X878673D01*
G01X879018D02*
X879248Y244808D01*
X879440Y245067D01*
X879517Y245377D01*
X879440Y245687D01*
X879248Y245945D01*
X878903Y246100D01*
X878558Y246048D01*
X878213Y245842D01*
G01X881773Y243000D02*
X881850Y243672D01*
X881965Y244240D01*
X882118Y244757D01*
X882310Y245325D01*
X882617Y246100D01*
X881083D01*
G01X884222Y244292D02*
X884490Y244653D01*
X884720Y244860D01*
X885027Y244963D01*
X885295Y244860D01*
X885487Y244653D01*
X885640Y244343D01*
X885678Y243982D01*
X885640Y243672D01*
X885487Y243362D01*
X885257Y243103D01*
X884988Y243000D01*
X884682Y243103D01*
X884413Y243413D01*
X884260Y243878D01*
X884222Y244395D01*
X884298Y245067D01*
X884413Y245428D01*
X884605Y245790D01*
X884873Y246048D01*
X885142Y246100D01*
X885410Y245997D01*
X885602Y245738D01*
G01X887973Y243000D02*
X888050Y243672D01*
X888165Y244240D01*
X888318Y244757D01*
X888510Y245325D01*
X888817Y246100D01*
X887283D01*
G01X882328Y269007D02*
X888528D01*
G01Y265807D02*
X882328D01*
G01D02*
Y269007D01*
G01X888103Y269807D02*
X884903D01*
G01D02*
Y276007D01*
G01Y277187D02*
Y283387D01*
G01D02*
X888103D01*
G01Y277187D02*
X884903D01*
G01Y276007D02*
X888103D01*
G01X880301Y274923D02*
Y283111D01*
G01X882543Y291747D02*
X876343D01*
G01D02*
Y294947D01*
G01D02*
X882543D01*
G01D02*
Y291747D01*
G01X876315Y291039D02*
X882515D01*
G01D02*
Y287839D01*
G01D02*
X876315D01*
G01D02*
Y291039D01*
G01X882566Y295765D02*
X876366D01*
G01D02*
Y298965D01*
G01D02*
X882566D01*
G01D02*
Y295765D01*
G01X882600Y303100D02*
Y299900D01*
G01X876400Y303100D02*
X882600D01*
G01X876400Y299900D02*
Y303100D01*
G01X882600Y299900D02*
X876400D01*
G01X875094Y308572D02*
Y322428D01*
G01X886906Y308572D02*
X875094D01*
G01X883400Y324400D02*
Y327600D01*
G01X889600Y324400D02*
X883400D01*
G01Y327600D02*
X889600D01*
G01X873100Y321100D02*
Y314900D01*
G01X882100Y327600D02*
Y324400D01*
G01X875900Y327600D02*
X882100D01*
G01X875900Y324400D02*
Y327600D01*
G01X882100Y324400D02*
X875900D01*
G01X875094Y322428D02*
X886906D01*
G01X877660Y401077D02*
X879882D01*
X880347Y401230D01*
X880657Y401537D01*
X880760Y401920D01*
X880657Y402303D01*
X880347Y402610D01*
X879882Y402763D01*
X877660D01*
G01X880398Y404368D02*
X880657Y404637D01*
X880760Y404943D01*
X880657Y405250D01*
X880347Y405518D01*
X879882Y405710D01*
X879417Y405787D01*
X878848D01*
X878383Y405710D01*
X877970Y405518D01*
X877763Y405288D01*
X877660Y405020D01*
X877763Y404713D01*
X877970Y404483D01*
X878280Y404330D01*
X878693Y404253D01*
X879055Y404330D01*
X879417Y404522D01*
X879623Y404752D01*
X879675Y405020D01*
X879572Y405327D01*
X879313Y405557D01*
X878848Y405787D01*
G01X877660Y408120D02*
X877763Y407813D01*
X878022Y407583D01*
X878332Y407430D01*
X878745Y407315D01*
X879210Y407277D01*
X879675Y407315D01*
X880088Y407430D01*
X880398Y407583D01*
X880657Y407813D01*
X880760Y408120D01*
X880657Y408427D01*
X880398Y408657D01*
X880088Y408810D01*
X879675Y408925D01*
X879210Y408963D01*
X878745Y408925D01*
X878332Y408810D01*
X878022Y408657D01*
X877763Y408427D01*
X877660Y408120D01*
G01X880295Y410377D02*
X880553Y410607D01*
X880708Y410875D01*
X880760Y411220D01*
X880657Y411565D01*
X880450Y411833D01*
X880088Y412025D01*
X879675Y412063D01*
X879262Y411987D01*
X879003Y411795D01*
X878797Y411527D01*
X878745Y411258D01*
X878797Y410990D01*
X879003Y410645D01*
X877660Y410760D01*
Y411795D01*
G01Y414320D02*
X877763Y414013D01*
X878022Y413783D01*
X878332Y413630D01*
X878745Y413515D01*
X879210Y413477D01*
X879675Y413515D01*
X880088Y413630D01*
X880398Y413783D01*
X880657Y414013D01*
X880760Y414320D01*
X880657Y414627D01*
X880398Y414857D01*
X880088Y415010D01*
X879675Y415125D01*
X879210Y415163D01*
X878745Y415125D01*
X878332Y415010D01*
X878022Y414857D01*
X877763Y414627D01*
X877660Y414320D01*
G01X884382Y1054433D02*
Y1057633D01*
G01X890582Y1054433D02*
X884382D01*
G01Y1057633D02*
X890582D01*
G01X878624Y1059675D02*
Y1063083D01*
G01X896340Y1059675D02*
X878624D01*
G01Y1073983D02*
Y1077391D01*
G01D02*
X896340D01*
G01X873342Y1079421D02*
X895177D01*
G01X873342Y1089107D02*
Y1079421D01*
G01Y1096507D02*
Y1106193D01*
G01X873883Y1108000D02*
Y1111100D01*
X874803D01*
X875110Y1110945D01*
X875340Y1110583D01*
X875417Y1110170D01*
X875340Y1109757D01*
X875148Y1109447D01*
X874803Y1109292D01*
X873883D01*
G01X878593Y1110842D02*
X878363Y1110997D01*
X878095Y1111100D01*
X877788D01*
X877443Y1110945D01*
X877175Y1110687D01*
X876983Y1110377D01*
X876830Y1109860D01*
X876792Y1109395D01*
X876868Y1108930D01*
X876983Y1108620D01*
X877213Y1108310D01*
X877482Y1108103D01*
X877750Y1108000D01*
X878018D01*
X878287Y1108103D01*
X878517Y1108258D01*
X878708Y1108465D01*
G01X880122Y1109292D02*
X880390Y1109653D01*
X880620Y1109860D01*
X880927Y1109963D01*
X881195Y1109860D01*
X881387Y1109653D01*
X881540Y1109343D01*
X881578Y1108982D01*
X881540Y1108672D01*
X881387Y1108362D01*
X881157Y1108103D01*
X880888Y1108000D01*
X880582Y1108103D01*
X880313Y1108413D01*
X880160Y1108878D01*
X880122Y1109395D01*
X880198Y1110067D01*
X880313Y1110428D01*
X880505Y1110790D01*
X880773Y1111048D01*
X881042Y1111100D01*
X881310Y1110997D01*
X881502Y1110738D01*
G01X883950Y1108000D02*
X884218Y1108052D01*
X884525Y1108207D01*
X884717Y1108465D01*
X884793Y1108827D01*
X884717Y1109188D01*
X884487Y1109498D01*
X884142Y1109653D01*
X883758D01*
X883528Y1109757D01*
X883337Y1110015D01*
X883260Y1110377D01*
X883375Y1110738D01*
X883643Y1110997D01*
X883950Y1111100D01*
X884257Y1110997D01*
X884525Y1110738D01*
X884640Y1110377D01*
X884563Y1110015D01*
X884372Y1109757D01*
X884142Y1109653D01*
X883758D01*
X883413Y1109498D01*
X883183Y1109188D01*
X883107Y1108827D01*
X883183Y1108465D01*
X883375Y1108207D01*
X883682Y1108052D01*
X883950Y1108000D01*
G01X887050Y1111100D02*
X886743Y1110997D01*
X886513Y1110738D01*
X886360Y1110428D01*
X886245Y1110015D01*
X886207Y1109550D01*
X886245Y1109085D01*
X886360Y1108672D01*
X886513Y1108362D01*
X886743Y1108103D01*
X887050Y1108000D01*
X887357Y1108103D01*
X887587Y1108362D01*
X887740Y1108672D01*
X887855Y1109085D01*
X887893Y1109550D01*
X887855Y1110015D01*
X887740Y1110428D01*
X887587Y1110738D01*
X887357Y1110997D01*
X887050Y1111100D01*
G01X890150Y1108000D02*
Y1111100D01*
X889690Y1110480D01*
G01Y1108000D02*
X890610D01*
G01X873342Y1106193D02*
X895177D01*
G01X926847Y1168189D02*
X876453D01*
G01D02*
Y1226789D01*
G01X883596Y1232593D02*
X887723D01*
G01X880596Y1235593D02*
X883596Y1232593D01*
G01X880596Y1254247D02*
Y1235593D01*
G01X876453Y1226789D02*
X926847D01*
G01X878523Y1240820D02*
X875323D01*
G01X878523Y1247020D02*
Y1240820D01*
G01X875323Y1247020D02*
X878523D01*
G01X875323Y1240820D02*
Y1247020D01*
G01X887723Y1254247D02*
X880596D01*
G01X879686Y1572254D02*
Y1592472D01*
G01X889473Y1631778D02*
Y1625778D01*
X883473D01*
G01Y1649400D02*
X889473D01*
Y1643400D01*
G01X888528Y269007D02*
Y265807D01*
G01X888103Y276007D02*
Y269807D01*
G01Y283387D02*
Y277187D01*
G01X890602Y308197D02*
X892824D01*
X893289Y308350D01*
X893599Y308657D01*
X893702Y309040D01*
X893599Y309423D01*
X893289Y309730D01*
X892824Y309883D01*
X890602D01*
G01X893702Y312140D02*
X893650Y312408D01*
X893495Y312715D01*
X893237Y312907D01*
X892875Y312983D01*
X892514Y312907D01*
X892204Y312677D01*
X892049Y312332D01*
Y311948D01*
X891945Y311718D01*
X891687Y311527D01*
X891325Y311450D01*
X890964Y311565D01*
X890705Y311833D01*
X890602Y312140D01*
X890705Y312447D01*
X890964Y312715D01*
X891325Y312830D01*
X891687Y312753D01*
X891945Y312562D01*
X892049Y312332D01*
Y311948D01*
X892204Y311603D01*
X892514Y311373D01*
X892875Y311297D01*
X893237Y311373D01*
X893495Y311565D01*
X893650Y311872D01*
X893702Y312140D01*
G01X890602Y315240D02*
X890705Y314933D01*
X890964Y314703D01*
X891274Y314550D01*
X891687Y314435D01*
X892152Y314397D01*
X892617Y314435D01*
X893030Y314550D01*
X893340Y314703D01*
X893599Y314933D01*
X893702Y315240D01*
X893599Y315547D01*
X893340Y315777D01*
X893030Y315930D01*
X892617Y316045D01*
X892152Y316083D01*
X891687Y316045D01*
X891274Y315930D01*
X890964Y315777D01*
X890705Y315547D01*
X890602Y315240D01*
G01Y318340D02*
X890705Y318033D01*
X890964Y317803D01*
X891274Y317650D01*
X891687Y317535D01*
X892152Y317497D01*
X892617Y317535D01*
X893030Y317650D01*
X893340Y317803D01*
X893599Y318033D01*
X893702Y318340D01*
X893599Y318647D01*
X893340Y318877D01*
X893030Y319030D01*
X892617Y319145D01*
X892152Y319183D01*
X891687Y319145D01*
X891274Y319030D01*
X890964Y318877D01*
X890705Y318647D01*
X890602Y318340D01*
G01X893082Y320597D02*
X893444Y320827D01*
X893650Y321133D01*
X893702Y321478D01*
X893650Y321785D01*
X893392Y322092D01*
X893082Y322283D01*
X892772Y322322D01*
X892410Y322245D01*
X892152Y321977D01*
X892049Y321708D01*
Y321363D01*
G01Y321708D02*
X891894Y321938D01*
X891635Y322130D01*
X891325Y322207D01*
X891015Y322130D01*
X890757Y321938D01*
X890602Y321593D01*
X890654Y321248D01*
X890860Y320903D01*
G01X886906Y322428D02*
Y308572D01*
G01X960236Y321654D02*
G03I-31496J0D01*
G01X889600Y327600D02*
Y324400D01*
G01X907051Y595849D02*
X900851D01*
G01D02*
Y599049D01*
G01D02*
X907051D01*
G01X906900Y600582D02*
X900700D01*
G01D02*
Y603782D01*
G01D02*
X906900D01*
G01X900681Y608515D02*
X906881D01*
G01Y605315D02*
X900681D01*
G01D02*
Y608515D01*
G01X890582Y1057633D02*
Y1054433D01*
G01X892383Y1054000D02*
Y1057100D01*
X893303D01*
X893610Y1056945D01*
X893840Y1056583D01*
X893917Y1056170D01*
X893840Y1055757D01*
X893648Y1055447D01*
X893303Y1055292D01*
X892383D01*
G01X895483Y1057100D02*
Y1054000D01*
X897017D01*
G01X898622Y1055292D02*
X898890Y1055653D01*
X899120Y1055860D01*
X899427Y1055963D01*
X899695Y1055860D01*
X899887Y1055653D01*
X900040Y1055343D01*
X900078Y1054982D01*
X900040Y1054672D01*
X899887Y1054362D01*
X899657Y1054103D01*
X899388Y1054000D01*
X899082Y1054103D01*
X898813Y1054413D01*
X898660Y1054878D01*
X898622Y1055395D01*
X898698Y1056067D01*
X898813Y1056428D01*
X899005Y1056790D01*
X899273Y1057048D01*
X899542Y1057100D01*
X899810Y1056997D01*
X900002Y1056738D01*
G01X901607Y1054465D02*
X901837Y1054207D01*
X902105Y1054052D01*
X902450Y1054000D01*
X902795Y1054103D01*
X903063Y1054310D01*
X903255Y1054672D01*
X903293Y1055085D01*
X903217Y1055498D01*
X903025Y1055757D01*
X902757Y1055963D01*
X902488Y1056015D01*
X902220Y1055963D01*
X901875Y1055757D01*
X901990Y1057100D01*
X903025D01*
G01X905550D02*
X905243Y1056997D01*
X905013Y1056738D01*
X904860Y1056428D01*
X904745Y1056015D01*
X904707Y1055550D01*
X904745Y1055085D01*
X904860Y1054672D01*
X905013Y1054362D01*
X905243Y1054103D01*
X905550Y1054000D01*
X905857Y1054103D01*
X906087Y1054362D01*
X906240Y1054672D01*
X906355Y1055085D01*
X906393Y1055550D01*
X906355Y1056015D01*
X906240Y1056428D01*
X906087Y1056738D01*
X905857Y1056997D01*
X905550Y1057100D01*
G01X907807Y1054620D02*
X908037Y1054258D01*
X908343Y1054052D01*
X908688Y1054000D01*
X908995Y1054052D01*
X909302Y1054310D01*
X909493Y1054620D01*
X909532Y1054930D01*
X909455Y1055292D01*
X909187Y1055550D01*
X908918Y1055653D01*
X908573D01*
G01X908918D02*
X909148Y1055808D01*
X909340Y1056067D01*
X909417Y1056377D01*
X909340Y1056687D01*
X909148Y1056945D01*
X908803Y1057100D01*
X908458Y1057048D01*
X908113Y1056842D01*
G01X896340Y1063083D02*
Y1059675D01*
G01Y1077391D02*
Y1073983D01*
G01X895177Y1079421D02*
X900114Y1084358D01*
G01D02*
Y1089107D01*
G01X895177Y1106193D02*
X900114Y1101256D01*
G01D02*
Y1096507D01*
G01X911000Y1114787D02*
X899000D01*
G01D02*
Y1120787D01*
G01X911000Y1107979D02*
X899000D01*
G01Y1113979D02*
X911000D01*
G01X899000Y1107979D02*
Y1113979D01*
G01Y1120787D02*
X911000D01*
G01X899000Y1121595D02*
Y1127595D01*
X911000D01*
Y1121595D01*
X899000D01*
G01Y1128403D02*
Y1134403D01*
X911000D01*
Y1128403D01*
X899000D01*
G01X898723Y1139443D02*
Y1136243D01*
G01X892523Y1139443D02*
X898723D01*
G01X892523Y1136243D02*
Y1139443D01*
G01X898723Y1136243D02*
X892523D01*
G01X890968Y1139978D02*
X887768D01*
G01X890968Y1146178D02*
Y1139978D01*
G01X887768Y1146178D02*
X890968D01*
G01X887768Y1139978D02*
Y1146178D01*
G01X899130Y1150669D02*
Y1147469D01*
G01X892930D02*
Y1150669D01*
G01X899130Y1147469D02*
X892930D01*
G01X894968Y1139978D02*
X891768D01*
G01X894968Y1146178D02*
Y1139978D01*
G01X891768Y1146178D02*
X894968D01*
G01X891768Y1139978D02*
Y1146178D01*
G01X899035Y1139976D02*
X895835Y1139980D01*
G01X899041Y1146176D02*
X899035Y1139976D01*
G01X895841Y1146180D02*
X899041Y1146176D01*
G01X895835Y1139980D02*
X895841Y1146180D01*
G01X892930Y1150669D02*
X899130D01*
G01X896994Y1158231D02*
X893794D01*
G01X896994Y1164431D02*
Y1158231D01*
G01X893794D02*
Y1164431D01*
G01X899130Y1155097D02*
Y1151897D01*
G01X892930Y1155097D02*
X899130D01*
G01X892930Y1151897D02*
Y1155097D01*
G01X899130Y1151897D02*
X892930D01*
G01X897794Y1161431D02*
X903994D01*
G01X897794Y1158231D02*
Y1161431D01*
G01X903994Y1158231D02*
X897794D01*
G01X893794Y1164431D02*
X896994D01*
G01X899250Y1232593D02*
X902250Y1235593D01*
G01X895123Y1232593D02*
X899250D01*
G01X902250Y1254247D02*
X895123D01*
G01X902646Y1555306D02*
X899546D01*
Y1556226D01*
X899701Y1556533D01*
X900063Y1556763D01*
X900476Y1556840D01*
X900889Y1556763D01*
X901199Y1556571D01*
X901354Y1556226D01*
Y1555306D01*
G01X899546Y1558330D02*
X901768D01*
X902233Y1558483D01*
X902543Y1558790D01*
X902646Y1559173D01*
X902543Y1559556D01*
X902233Y1559863D01*
X901768Y1560016D01*
X899546D01*
G01X900063Y1561545D02*
X899753Y1561775D01*
X899598Y1562043D01*
X899546Y1562350D01*
X899649Y1562733D01*
X899908Y1563001D01*
X900218Y1563078D01*
X900528Y1563040D01*
X900786Y1562886D01*
X901303Y1562120D01*
X901664Y1561775D01*
X902181Y1561545D01*
X902646Y1561468D01*
Y1563078D01*
G01X902284Y1564721D02*
X902543Y1564990D01*
X902646Y1565296D01*
X902543Y1565603D01*
X902233Y1565871D01*
X901768Y1566063D01*
X901303Y1566140D01*
X900734D01*
X900269Y1566063D01*
X899856Y1565871D01*
X899649Y1565641D01*
X899546Y1565373D01*
X899649Y1565066D01*
X899856Y1564836D01*
X900166Y1564683D01*
X900579Y1564606D01*
X900941Y1564683D01*
X901303Y1564875D01*
X901509Y1565105D01*
X901561Y1565373D01*
X901458Y1565680D01*
X901199Y1565910D01*
X900734Y1566140D01*
G01X902646Y1568396D02*
X901974Y1568473D01*
X901406Y1568588D01*
X900889Y1568741D01*
X900321Y1568933D01*
X899546Y1569240D01*
Y1567706D01*
G01X898350Y1580333D02*
X895150D01*
G01X898350Y1586533D02*
Y1580333D01*
G01X895150D02*
Y1586533D01*
G01X887050Y1572233D02*
X893250D01*
G01D02*
Y1569033D01*
G01X887050D02*
Y1572233D01*
G01X893250Y1569033D02*
X887050D01*
G01Y1573033D02*
Y1576233D01*
G01X893250Y1573033D02*
X887050D01*
G01X893250Y1576233D02*
Y1573033D01*
G01X887050Y1576233D02*
X893250D01*
G01Y1580233D02*
Y1577033D01*
G01X887050Y1580233D02*
X893250D01*
G01X887050Y1577033D02*
Y1580233D01*
G01X893250Y1577033D02*
X887050D01*
G01X893250Y1584233D02*
Y1581033D01*
G01X887050D02*
Y1584233D01*
G01X893250Y1581033D02*
X887050D01*
G01X901468Y1592472D02*
Y1572254D01*
G01D02*
X921686D01*
G01X895150Y1586533D02*
X898350D01*
G01X893250Y1596233D02*
Y1593033D01*
G01X887050Y1596233D02*
X893250D01*
G01X887050Y1593033D02*
Y1596233D01*
G01X893250Y1593033D02*
X887050D01*
G01Y1589033D02*
Y1592233D01*
G01X893250Y1589033D02*
X887050D01*
G01X893250Y1592233D02*
Y1589033D01*
G01X887050Y1592233D02*
X893250D01*
G01X887050Y1584233D02*
X893250D01*
G01X921686Y1592472D02*
X901468D01*
G01X887050Y1604233D02*
X893250D01*
G01D02*
Y1601033D01*
G01X887050D02*
Y1604233D01*
G01X893250Y1601033D02*
X887050D01*
G01Y1597033D02*
Y1600233D01*
G01X893250Y1597033D02*
X887050D01*
G01X893250Y1600233D02*
Y1597033D01*
G01X887050Y1600233D02*
X893250D01*
G01X887050Y1605033D02*
Y1608233D01*
G01X893250Y1605033D02*
X887050D01*
G01X893250Y1608233D02*
Y1605033D01*
G01X887050Y1608233D02*
X893250D01*
G01X896913Y1671061D02*
Y1678561D01*
X899153D01*
X899900Y1678186D01*
X900460Y1677311D01*
X900647Y1676311D01*
X900460Y1675311D01*
X899993Y1674561D01*
X899153Y1674186D01*
X896913D01*
G01X904413Y1671061D02*
Y1678561D01*
X906747D01*
X907493Y1678186D01*
X907960Y1677686D01*
X908147Y1676686D01*
X907960Y1675686D01*
X907400Y1675061D01*
X906747Y1674686D01*
X904413D01*
G01X906747D02*
X908147Y1671061D01*
G01X915647D02*
X911913D01*
Y1678561D01*
X915647D01*
G01X914153Y1674936D02*
X911913D01*
G01X919320Y1672061D02*
X920067Y1671436D01*
X920907Y1671061D01*
X921653D01*
X922400Y1671436D01*
X922960Y1672061D01*
X923240Y1672936D01*
X923053Y1673811D01*
X922587Y1674561D01*
X921747Y1675061D01*
X920627Y1675311D01*
X919973Y1675811D01*
X919693Y1676686D01*
X919880Y1677561D01*
X920347Y1678186D01*
X921000Y1678561D01*
X921653D01*
X922307Y1678311D01*
X922867Y1677686D01*
G01X926820Y1672061D02*
X927567Y1671436D01*
X928407Y1671061D01*
X929153D01*
X929900Y1671436D01*
X930460Y1672061D01*
X930740Y1672936D01*
X930553Y1673811D01*
X930087Y1674561D01*
X929247Y1675061D01*
X928127Y1675311D01*
X927473Y1675811D01*
X927193Y1676686D01*
X927380Y1677561D01*
X927847Y1678186D01*
X928500Y1678561D01*
X929153D01*
X929807Y1678311D01*
X930367Y1677686D01*
G01X935067Y1673561D02*
X937493D01*
G01X942007Y1671061D02*
Y1678561D01*
X945553D01*
G01X944247Y1674936D02*
X942007D01*
G01X950160Y1678561D02*
X952400D01*
G01X951280D02*
Y1671061D01*
G01X950160D02*
X952400D01*
G01X958780Y1678561D02*
Y1671061D01*
G01X956633Y1678561D02*
X960927D01*
G01X906755Y150442D02*
X907065Y150634D01*
X907272Y150864D01*
X907375Y151132D01*
X907272Y151439D01*
X907065Y151669D01*
X906755Y151899D01*
X906342Y151976D01*
X904275D01*
G01X907013Y153657D02*
X907272Y153926D01*
X907375Y154232D01*
X907272Y154539D01*
X906962Y154807D01*
X906497Y154999D01*
X906032Y155076D01*
X905463D01*
X904998Y154999D01*
X904585Y154807D01*
X904378Y154577D01*
X904275Y154309D01*
X904378Y154002D01*
X904585Y153772D01*
X904895Y153619D01*
X905308Y153542D01*
X905670Y153619D01*
X906032Y153811D01*
X906238Y154041D01*
X906290Y154309D01*
X906187Y154616D01*
X905928Y154846D01*
X905463Y155076D01*
G01X904275Y157409D02*
X904378Y157102D01*
X904637Y156872D01*
X904947Y156719D01*
X905360Y156604D01*
X905825Y156566D01*
X906290Y156604D01*
X906703Y156719D01*
X907013Y156872D01*
X907272Y157102D01*
X907375Y157409D01*
X907272Y157716D01*
X907013Y157946D01*
X906703Y158099D01*
X906290Y158214D01*
X905825Y158252D01*
X905360Y158214D01*
X904947Y158099D01*
X904637Y157946D01*
X904378Y157716D01*
X904275Y157409D01*
G01X910039Y151358D02*
Y204500D01*
G01X910335Y151752D02*
Y204500D01*
G01X916420Y151358D02*
X910039D01*
G01X916015Y151752D02*
X910335D01*
G01X910039Y208500D02*
Y212000D01*
G01X910335Y208500D02*
Y212000D01*
G01Y215500D02*
Y218500D01*
G01X910039Y215500D02*
Y218500D01*
G01Y222500D02*
Y225500D01*
G01X910335Y222500D02*
Y225500D01*
G01Y230000D02*
Y246358D01*
G01X910039Y230000D02*
Y246752D01*
G01D02*
X916420D01*
G01X910335Y246358D02*
X916015D01*
G01X914668Y270759D02*
Y276959D01*
G01D02*
X917868D01*
G01Y270759D02*
X914668D01*
G01X908409Y562015D02*
X908102Y562067D01*
X907834Y562273D01*
X907604Y562583D01*
X907451Y562945D01*
X907374Y563358D01*
Y563772D01*
X907451Y564185D01*
X907604Y564547D01*
X907834Y564857D01*
X908102Y565063D01*
X908409Y565115D01*
X908716Y565063D01*
X908984Y564857D01*
X909214Y564547D01*
X909367Y564185D01*
X909444Y563772D01*
Y563358D01*
X909367Y562945D01*
X909214Y562583D01*
X908984Y562273D01*
X908716Y562067D01*
X908409Y562015D01*
G01X908716Y562842D02*
X909176Y562015D01*
G01X910781Y563307D02*
X911049Y563668D01*
X911279Y563875D01*
X911586Y563978D01*
X911854Y563875D01*
X912046Y563668D01*
X912199Y563358D01*
X912237Y562997D01*
X912199Y562687D01*
X912046Y562377D01*
X911816Y562118D01*
X911547Y562015D01*
X911241Y562118D01*
X910972Y562428D01*
X910819Y562893D01*
X910781Y563410D01*
X910857Y564082D01*
X910972Y564443D01*
X911164Y564805D01*
X911432Y565063D01*
X911701Y565115D01*
X911969Y565012D01*
X912161Y564753D01*
G01X913766Y562635D02*
X913996Y562273D01*
X914302Y562067D01*
X914647Y562015D01*
X914954Y562067D01*
X915261Y562325D01*
X915452Y562635D01*
X915491Y562945D01*
X915414Y563307D01*
X915146Y563565D01*
X914877Y563668D01*
X914532D01*
G01X914877D02*
X915107Y563823D01*
X915299Y564082D01*
X915376Y564392D01*
X915299Y564702D01*
X915107Y564960D01*
X914762Y565115D01*
X914417Y565063D01*
X914072Y564857D01*
G01X911272Y580812D02*
X905072D01*
G01D02*
Y584012D01*
G01X911272D02*
Y580812D01*
G01X915356Y572306D02*
X921556D01*
G01Y569106D02*
X915356D01*
G01D02*
Y572306D01*
G01X907051Y599049D02*
Y595849D01*
G01X905072Y584012D02*
X911272D01*
G01X908231Y609758D02*
X902031D01*
G01D02*
Y612958D01*
G01X908231D02*
Y609758D01*
G01X906900Y603782D02*
Y600582D01*
G01X906881Y608515D02*
Y605315D01*
G01X911272Y624312D02*
X905072D01*
G01D02*
Y627512D01*
G01D02*
X911272D01*
G01D02*
Y624312D01*
G01X902031Y612958D02*
X908231D01*
G01X915208Y1094134D02*
Y1097234D01*
G01X916818D02*
Y1094134D01*
G01Y1095684D02*
X915208D01*
G01X919113Y1094134D02*
Y1097234D01*
X918653Y1096614D01*
G01Y1094134D02*
X919573D01*
G01X922213Y1097234D02*
X921906Y1097131D01*
X921676Y1096872D01*
X921523Y1096562D01*
X921408Y1096149D01*
X921370Y1095684D01*
X921408Y1095219D01*
X921523Y1094806D01*
X921676Y1094496D01*
X921906Y1094237D01*
X922213Y1094134D01*
X922520Y1094237D01*
X922750Y1094496D01*
X922903Y1094806D01*
X923018Y1095219D01*
X923056Y1095684D01*
X923018Y1096149D01*
X922903Y1096562D01*
X922750Y1096872D01*
X922520Y1097131D01*
X922213Y1097234D01*
G01X925313D02*
X925006Y1097131D01*
X924776Y1096872D01*
X924623Y1096562D01*
X924508Y1096149D01*
X924470Y1095684D01*
X924508Y1095219D01*
X924623Y1094806D01*
X924776Y1094496D01*
X925006Y1094237D01*
X925313Y1094134D01*
X925620Y1094237D01*
X925850Y1094496D01*
X926003Y1094806D01*
X926118Y1095219D01*
X926156Y1095684D01*
X926118Y1096149D01*
X926003Y1096562D01*
X925850Y1096872D01*
X925620Y1097131D01*
X925313Y1097234D01*
G01X912200Y1119200D02*
X924200D01*
G01X912200Y1113200D02*
Y1119200D01*
G01X924200Y1113200D02*
X912200D01*
G01Y1112200D02*
X924200D01*
G01X912200Y1106200D02*
Y1112200D01*
G01X924200Y1106200D02*
X912200D01*
G01X911000Y1120787D02*
Y1114787D01*
G01Y1113979D02*
Y1107979D01*
G01X912200Y1126200D02*
X924200D01*
G01X912200Y1120200D02*
Y1126200D01*
G01X924200Y1120200D02*
X912200D01*
G01X924200Y1133200D02*
Y1127200D01*
X912200D01*
Y1133200D01*
X924200D01*
G01X905028Y1140598D02*
X908830D01*
G01X905028Y1140869D02*
Y1140598D01*
G01X911130D02*
X917232D01*
G01X911148Y1162769D02*
Y1159569D01*
G01X904948Y1162769D02*
X911148D01*
G01X904948Y1159569D02*
Y1162769D01*
G01X911148Y1159569D02*
X904948D01*
G01X903994Y1161431D02*
Y1158231D01*
G01X915507Y1161084D02*
Y1164184D01*
X916427D01*
X916734Y1164029D01*
X916964Y1163667D01*
X917041Y1163254D01*
X916964Y1162841D01*
X916772Y1162531D01*
X916427Y1162376D01*
X915507D01*
G01X918531Y1164184D02*
Y1161962D01*
X918684Y1161497D01*
X918991Y1161187D01*
X919374Y1161084D01*
X919757Y1161187D01*
X920064Y1161497D01*
X920217Y1161962D01*
Y1164184D01*
G01X921746Y1162376D02*
X922014Y1162737D01*
X922244Y1162944D01*
X922551Y1163047D01*
X922819Y1162944D01*
X923011Y1162737D01*
X923164Y1162427D01*
X923202Y1162066D01*
X923164Y1161756D01*
X923011Y1161446D01*
X922781Y1161187D01*
X922512Y1161084D01*
X922206Y1161187D01*
X921937Y1161497D01*
X921784Y1161962D01*
X921746Y1162479D01*
X921822Y1163151D01*
X921937Y1163512D01*
X922129Y1163874D01*
X922397Y1164132D01*
X922666Y1164184D01*
X922934Y1164081D01*
X923126Y1163822D01*
G01X924731Y1161549D02*
X924961Y1161291D01*
X925229Y1161136D01*
X925574Y1161084D01*
X925919Y1161187D01*
X926187Y1161394D01*
X926379Y1161756D01*
X926417Y1162169D01*
X926341Y1162582D01*
X926149Y1162841D01*
X925881Y1163047D01*
X925612Y1163099D01*
X925344Y1163047D01*
X924999Y1162841D01*
X925114Y1164184D01*
X926149D01*
G01X928674D02*
X928367Y1164081D01*
X928137Y1163822D01*
X927984Y1163512D01*
X927869Y1163099D01*
X927831Y1162634D01*
X927869Y1162169D01*
X927984Y1161756D01*
X928137Y1161446D01*
X928367Y1161187D01*
X928674Y1161084D01*
X928981Y1161187D01*
X929211Y1161446D01*
X929364Y1161756D01*
X929479Y1162169D01*
X929517Y1162634D01*
X929479Y1163099D01*
X929364Y1163512D01*
X929211Y1163822D01*
X928981Y1164081D01*
X928674Y1164184D01*
G01X931774Y1161084D02*
Y1164184D01*
X931314Y1163564D01*
G01Y1161084D02*
X932234D01*
G01X905028Y1156740D02*
Y1156469D01*
G01X908830Y1156740D02*
X905028D01*
G01X917232D02*
X913430D01*
G01X907596Y1232593D02*
X911723D01*
G01X904596Y1235593D02*
X907596Y1232593D01*
G01X904596Y1254247D02*
Y1235593D01*
G01X902250D02*
Y1254247D01*
G01X911723D02*
X904596D01*
G01X912303Y1410935D02*
Y1414035D01*
G01X913913D02*
Y1410935D01*
G01Y1412485D02*
X912303D01*
G01X916208Y1410935D02*
Y1414035D01*
X915748Y1413415D01*
G01Y1410935D02*
X916668D01*
G01X919308Y1414035D02*
X919001Y1413932D01*
X918771Y1413673D01*
X918618Y1413363D01*
X918503Y1412950D01*
X918465Y1412485D01*
X918503Y1412020D01*
X918618Y1411607D01*
X918771Y1411297D01*
X919001Y1411038D01*
X919308Y1410935D01*
X919615Y1411038D01*
X919845Y1411297D01*
X919998Y1411607D01*
X920113Y1412020D01*
X920151Y1412485D01*
X920113Y1412950D01*
X919998Y1413363D01*
X919845Y1413673D01*
X919615Y1413932D01*
X919308Y1414035D01*
G01X921565Y1411400D02*
X921795Y1411142D01*
X922063Y1410987D01*
X922408Y1410935D01*
X922753Y1411038D01*
X923021Y1411245D01*
X923213Y1411607D01*
X923251Y1412020D01*
X923175Y1412433D01*
X922983Y1412692D01*
X922715Y1412898D01*
X922446Y1412950D01*
X922178Y1412898D01*
X921833Y1412692D01*
X921948Y1414035D01*
X922983D01*
G01X915442Y1528036D02*
X912342D01*
G01Y1529646D02*
X915442D01*
G01X913892D02*
Y1528036D01*
G01X914150Y1531213D02*
X913789Y1531481D01*
X913582Y1531711D01*
X913479Y1532018D01*
X913582Y1532286D01*
X913789Y1532478D01*
X914099Y1532631D01*
X914460Y1532669D01*
X914770Y1532631D01*
X915080Y1532478D01*
X915339Y1532248D01*
X915442Y1531979D01*
X915339Y1531673D01*
X915029Y1531404D01*
X914564Y1531251D01*
X914047Y1531213D01*
X913375Y1531289D01*
X913014Y1531404D01*
X912652Y1531596D01*
X912394Y1531864D01*
X912342Y1532133D01*
X912445Y1532401D01*
X912704Y1532593D01*
G01X912342Y1535041D02*
X912445Y1534734D01*
X912704Y1534504D01*
X913014Y1534351D01*
X913427Y1534236D01*
X913892Y1534198D01*
X914357Y1534236D01*
X914770Y1534351D01*
X915080Y1534504D01*
X915339Y1534734D01*
X915442Y1535041D01*
X915339Y1535348D01*
X915080Y1535578D01*
X914770Y1535731D01*
X914357Y1535846D01*
X913892Y1535884D01*
X913427Y1535846D01*
X913014Y1535731D01*
X912704Y1535578D01*
X912445Y1535348D01*
X912342Y1535041D01*
G01Y1538141D02*
X912445Y1537834D01*
X912704Y1537604D01*
X913014Y1537451D01*
X913427Y1537336D01*
X913892Y1537298D01*
X914357Y1537336D01*
X914770Y1537451D01*
X915080Y1537604D01*
X915339Y1537834D01*
X915442Y1538141D01*
X915339Y1538448D01*
X915080Y1538678D01*
X914770Y1538831D01*
X914357Y1538946D01*
X913892Y1538984D01*
X913427Y1538946D01*
X913014Y1538831D01*
X912704Y1538678D01*
X912445Y1538448D01*
X912342Y1538141D01*
G01X912859Y1540513D02*
X912549Y1540743D01*
X912394Y1541011D01*
X912342Y1541318D01*
X912445Y1541701D01*
X912704Y1541969D01*
X913014Y1542046D01*
X913324Y1542008D01*
X913582Y1541854D01*
X914099Y1541088D01*
X914460Y1540743D01*
X914977Y1540513D01*
X915442Y1540436D01*
Y1542046D01*
G01X903841Y1634473D02*
X954453D01*
G01X903841Y1648973D02*
Y1634473D01*
G01X904269Y1650723D02*
Y1653823D01*
X905725D01*
G01X905189Y1652325D02*
X904269D01*
G01X907292Y1651136D02*
X907599Y1650878D01*
X907944Y1650723D01*
X908250D01*
X908557Y1650878D01*
X908787Y1651136D01*
X908902Y1651498D01*
X908825Y1651860D01*
X908634Y1652170D01*
X908289Y1652376D01*
X907829Y1652480D01*
X907560Y1652686D01*
X907445Y1653048D01*
X907522Y1653410D01*
X907714Y1653668D01*
X907982Y1653823D01*
X908250D01*
X908519Y1653720D01*
X908749Y1653461D01*
G01X911197Y1650723D02*
Y1653823D01*
X910737Y1653203D01*
G01Y1650723D02*
X911657D01*
G01X954453Y1648973D02*
X903841D01*
G01X915872Y1682410D02*
X901688D01*
G01X934843Y151358D02*
X928462D01*
G01X934547Y151752D02*
X928867D01*
G01X928462Y246752D02*
X934843D01*
G01X928867Y246358D02*
X934547D01*
G01X927068Y268747D02*
Y262547D01*
G01D02*
X923868D01*
G01D02*
Y268747D01*
G01D02*
X927068D01*
G01X929949Y263196D02*
Y260974D01*
X930102Y260509D01*
X930409Y260199D01*
X930792Y260096D01*
X931175Y260199D01*
X931482Y260509D01*
X931635Y260974D01*
Y263196D01*
G01X934352Y260096D02*
Y263196D01*
X932934Y260974D01*
X934850D01*
G01X937452Y260096D02*
Y263196D01*
X936034Y260974D01*
X937950D01*
G01X941745Y265352D02*
X928391D01*
G01D02*
Y274210D01*
G01X917868Y276959D02*
Y270759D01*
G01X921868Y276959D02*
Y270759D01*
G01D02*
X918668D01*
G01D02*
Y276959D01*
G01D02*
X921868D01*
G01X928391Y274210D02*
X941745D01*
G01X931976Y551949D02*
X916622D01*
G01D02*
Y564627D01*
G01D02*
X931976D01*
G01X931124Y569103D02*
X924924D01*
G01D02*
Y572303D01*
G01D02*
X931124D01*
G01D02*
Y569103D01*
G01X921556Y572306D02*
Y569106D01*
G01X923172Y580211D02*
X920072D01*
G01D02*
Y592613D01*
G01X928272D02*
Y580211D01*
G01D02*
X925172D01*
G01X923272D02*
X924172Y581404D01*
G01D02*
X925172Y580211D01*
G01X923172Y594711D02*
X920072D01*
G01D02*
Y607113D01*
G01X928272D02*
Y594711D01*
G01D02*
X925172D01*
G01X923272D02*
X924172Y595904D01*
G01D02*
X925172Y594711D01*
G01X920072Y592613D02*
X928272D01*
G01X923172Y609211D02*
X920072D01*
G01D02*
Y621613D01*
G01X928272D02*
Y609211D01*
G01D02*
X925172D01*
G01X923272D02*
X924172Y610404D01*
G01D02*
X925172Y609211D01*
G01X920072Y607113D02*
X928272D01*
G01X923172Y623711D02*
X920072D01*
G01D02*
Y636113D01*
G01X928272D02*
Y623711D01*
G01D02*
X925172D01*
G01X923272D02*
X924172Y624904D01*
G01D02*
X925172Y623711D01*
G01X920072Y621613D02*
X928272D01*
G01X920072Y636113D02*
X928272D01*
G01X919028Y781005D02*
Y784105D01*
G01X920638D02*
Y781005D01*
G01Y782555D02*
X919028D01*
G01X922281Y781367D02*
X922550Y781108D01*
X922856Y781005D01*
X923163Y781108D01*
X923431Y781418D01*
X923623Y781883D01*
X923700Y782348D01*
Y782917D01*
X923623Y783382D01*
X923431Y783795D01*
X923201Y784002D01*
X922933Y784105D01*
X922626Y784002D01*
X922396Y783795D01*
X922243Y783485D01*
X922166Y783072D01*
X922243Y782710D01*
X922435Y782348D01*
X922665Y782142D01*
X922933Y782090D01*
X923240Y782193D01*
X923470Y782452D01*
X923700Y782917D01*
G01X925381Y781367D02*
X925650Y781108D01*
X925956Y781005D01*
X926263Y781108D01*
X926531Y781418D01*
X926723Y781883D01*
X926800Y782348D01*
Y782917D01*
X926723Y783382D01*
X926531Y783795D01*
X926301Y784002D01*
X926033Y784105D01*
X925726Y784002D01*
X925496Y783795D01*
X925343Y783485D01*
X925266Y783072D01*
X925343Y782710D01*
X925535Y782348D01*
X925765Y782142D01*
X926033Y782090D01*
X926340Y782193D01*
X926570Y782452D01*
X926800Y782917D01*
G01X924200Y1119200D02*
Y1113200D01*
G01Y1112200D02*
Y1106200D01*
G01Y1126200D02*
Y1120200D01*
G01X917232Y1140598D02*
Y1141069D01*
G01X920847Y1157175D02*
X924047D01*
G01X920847Y1150975D02*
Y1157175D01*
G01X924047Y1150975D02*
X920847D01*
G01X924047Y1157175D02*
Y1150975D01*
G01X917232Y1156469D02*
Y1156740D01*
G01X981701Y1168189D02*
X931307D01*
G01D02*
Y1226789D01*
G01X926847D02*
Y1168189D01*
G01X931500Y1237883D02*
X928400D01*
Y1238803D01*
X928555Y1239110D01*
X928917Y1239340D01*
X929330Y1239417D01*
X929743Y1239340D01*
X930053Y1239148D01*
X930208Y1238803D01*
Y1237883D01*
G01X928658Y1242593D02*
X928503Y1242363D01*
X928400Y1242095D01*
Y1241788D01*
X928555Y1241443D01*
X928813Y1241175D01*
X929123Y1240983D01*
X929640Y1240830D01*
X930105Y1240792D01*
X930570Y1240868D01*
X930880Y1240983D01*
X931190Y1241213D01*
X931397Y1241482D01*
X931500Y1241750D01*
Y1242018D01*
X931397Y1242287D01*
X931242Y1242517D01*
X931035Y1242708D01*
G01X930208Y1244122D02*
X929847Y1244390D01*
X929640Y1244620D01*
X929537Y1244927D01*
X929640Y1245195D01*
X929847Y1245387D01*
X930157Y1245540D01*
X930518Y1245578D01*
X930828Y1245540D01*
X931138Y1245387D01*
X931397Y1245157D01*
X931500Y1244888D01*
X931397Y1244582D01*
X931087Y1244313D01*
X930622Y1244160D01*
X930105Y1244122D01*
X929433Y1244198D01*
X929072Y1244313D01*
X928710Y1244505D01*
X928452Y1244773D01*
X928400Y1245042D01*
X928503Y1245310D01*
X928762Y1245502D01*
G01X931035Y1247107D02*
X931293Y1247337D01*
X931448Y1247605D01*
X931500Y1247950D01*
X931397Y1248295D01*
X931190Y1248563D01*
X930828Y1248755D01*
X930415Y1248793D01*
X930002Y1248717D01*
X929743Y1248525D01*
X929537Y1248257D01*
X929485Y1247988D01*
X929537Y1247720D01*
X929743Y1247375D01*
X928400Y1247490D01*
Y1248525D01*
G01X930880Y1250207D02*
X931242Y1250437D01*
X931448Y1250743D01*
X931500Y1251088D01*
X931448Y1251395D01*
X931190Y1251702D01*
X930880Y1251893D01*
X930570Y1251932D01*
X930208Y1251855D01*
X929950Y1251587D01*
X929847Y1251318D01*
Y1250973D01*
G01Y1251318D02*
X929692Y1251548D01*
X929433Y1251740D01*
X929123Y1251817D01*
X928813Y1251740D01*
X928555Y1251548D01*
X928400Y1251203D01*
X928452Y1250858D01*
X928658Y1250513D01*
G01X928917Y1253422D02*
X928607Y1253652D01*
X928452Y1253920D01*
X928400Y1254227D01*
X928503Y1254610D01*
X928762Y1254878D01*
X929072Y1254955D01*
X929382Y1254917D01*
X929640Y1254763D01*
X930157Y1253997D01*
X930518Y1253652D01*
X931035Y1253422D01*
X931500Y1253345D01*
Y1254955D01*
G01X923250Y1232593D02*
X926250Y1235593D01*
G01X919123Y1232593D02*
X923250D01*
G01X926250Y1235593D02*
Y1254247D01*
G01X931307Y1226789D02*
X981701D01*
G01X926250Y1254247D02*
X919123D01*
G01X929050Y1580633D02*
Y1583833D01*
G01X935250Y1580633D02*
X929050D01*
G01Y1576633D02*
Y1579833D01*
G01X935250Y1576633D02*
X929050D01*
G01Y1579833D02*
X935250D01*
G01X921686Y1572254D02*
Y1592472D01*
G01X929050Y1583833D02*
X935250D01*
G01X929050Y1587833D02*
X935250D01*
G01X929050Y1584633D02*
Y1587833D01*
G01X935250Y1584633D02*
X929050D01*
G01Y1591833D02*
X935250D01*
G01X929050Y1588633D02*
Y1591833D01*
G01X935250Y1588633D02*
X929050D01*
G01X934547Y197000D02*
Y151752D01*
G01X934843Y197000D02*
Y151358D01*
G01X939845Y186652D02*
X946045D01*
G01X939845Y183452D02*
Y186652D01*
G01X946045Y183452D02*
X939845D01*
G01X946045Y186652D02*
Y183452D01*
G01X939845Y190652D02*
X946045D01*
G01X939845Y187452D02*
Y190652D01*
G01X946045Y187452D02*
X939845D01*
G01X946045Y190652D02*
Y187452D01*
G01X934547Y211500D02*
Y208500D01*
G01X934843Y211500D02*
Y208500D01*
G01Y204500D02*
Y201500D01*
G01X934547Y204500D02*
Y201500D01*
G01Y226000D02*
Y222500D01*
G01X934843Y226000D02*
Y222500D01*
G01Y218500D02*
Y215500D01*
G01X934547Y218500D02*
Y215500D01*
G01Y246358D02*
Y229500D01*
G01X934843Y246752D02*
Y229500D01*
G01X941745Y274210D02*
Y265352D01*
G01X943663Y273056D02*
Y279256D01*
G01D02*
X946863D01*
G01Y273056D02*
X943663D01*
G01X931976Y564430D02*
Y551949D01*
G01X939145Y574995D02*
Y572773D01*
X939298Y572308D01*
X939605Y571998D01*
X939988Y571895D01*
X940371Y571998D01*
X940678Y572308D01*
X940831Y572773D01*
Y574995D01*
G01X943088Y571895D02*
Y574995D01*
X942628Y574375D01*
G01Y571895D02*
X943548D01*
G01X945345Y572360D02*
X945575Y572102D01*
X945843Y571947D01*
X946188Y571895D01*
X946533Y571998D01*
X946801Y572205D01*
X946993Y572567D01*
X947031Y572980D01*
X946955Y573393D01*
X946763Y573652D01*
X946495Y573858D01*
X946226Y573910D01*
X945958Y573858D01*
X945613Y573652D01*
X945728Y574995D01*
X946763D01*
G01X948445Y572515D02*
X948675Y572153D01*
X948981Y571947D01*
X949326Y571895D01*
X949633Y571947D01*
X949940Y572205D01*
X950131Y572515D01*
X950170Y572825D01*
X950093Y573187D01*
X949825Y573445D01*
X949556Y573548D01*
X949211D01*
G01X949556D02*
X949786Y573703D01*
X949978Y573962D01*
X950055Y574272D01*
X949978Y574582D01*
X949786Y574840D01*
X949441Y574995D01*
X949096Y574943D01*
X948751Y574737D01*
G01X949681Y588817D02*
X943481D01*
G01D02*
Y592017D01*
G01D02*
X949681D01*
G01X943443Y586800D02*
X949643D01*
G01Y583600D02*
X943443D01*
G01D02*
Y586800D01*
G01X942785Y599455D02*
Y597233D01*
X942938Y596768D01*
X943245Y596458D01*
X943628Y596355D01*
X944011Y596458D01*
X944318Y596768D01*
X944471Y597233D01*
Y599455D01*
G01X946728Y596355D02*
Y599455D01*
X946268Y598835D01*
G01Y596355D02*
X947188D01*
G01X948985Y596975D02*
X949215Y596613D01*
X949521Y596407D01*
X949866Y596355D01*
X950173Y596407D01*
X950480Y596665D01*
X950671Y596975D01*
X950710Y597285D01*
X950633Y597647D01*
X950365Y597905D01*
X950096Y598008D01*
X949751D01*
G01X950096D02*
X950326Y598163D01*
X950518Y598422D01*
X950595Y598732D01*
X950518Y599042D01*
X950326Y599300D01*
X949981Y599455D01*
X949636Y599403D01*
X949291Y599197D01*
G01X950331Y612550D02*
X944131D01*
G01D02*
Y615750D01*
G01X939955Y609965D02*
Y607743D01*
X940108Y607278D01*
X940415Y606968D01*
X940798Y606865D01*
X941181Y606968D01*
X941488Y607278D01*
X941641Y607743D01*
Y609965D01*
G01X943898Y606865D02*
Y609965D01*
X943438Y609345D01*
G01Y606865D02*
X944358D01*
G01X947458D02*
Y609965D01*
X946040Y607743D01*
X947956D01*
G01X944131Y615750D02*
X950331D01*
G01X949156Y627062D02*
X942956D01*
G01D02*
Y630262D01*
G01X940455Y623939D02*
Y621717D01*
X940608Y621252D01*
X940915Y620942D01*
X941298Y620839D01*
X941681Y620942D01*
X941988Y621252D01*
X942141Y621717D01*
Y623939D01*
G01X944398Y620839D02*
Y623939D01*
X943938Y623319D01*
G01Y620839D02*
X944858D01*
G01X946655Y621304D02*
X946885Y621046D01*
X947153Y620891D01*
X947498Y620839D01*
X947843Y620942D01*
X948111Y621149D01*
X948303Y621511D01*
X948341Y621924D01*
X948265Y622337D01*
X948073Y622596D01*
X947805Y622802D01*
X947536Y622854D01*
X947268Y622802D01*
X946923Y622596D01*
X947038Y623939D01*
X948073D01*
G01X951058Y620839D02*
Y623939D01*
X949640Y621717D01*
X951556D01*
G01X942956Y630262D02*
X949156D01*
G01X954000Y1113200D02*
X942000D01*
G01D02*
Y1119200D01*
G01D02*
X954000D01*
G01Y1106200D02*
X942000D01*
G01Y1112200D02*
X954000D01*
G01X942000Y1106200D02*
Y1112200D01*
G01Y1127200D02*
Y1133200D01*
X954000D01*
Y1127200D01*
X942000D01*
G01Y1120200D02*
Y1126200D01*
X954000D01*
Y1120200D01*
X942000D01*
G01X945748Y1139443D02*
Y1136243D01*
G01X939548Y1139443D02*
X945748D01*
G01X939548Y1136243D02*
Y1139443D01*
G01X945748Y1136243D02*
X939548D01*
G01X937993Y1139978D02*
X934793D01*
G01X937993Y1146178D02*
Y1139978D01*
G01X934793Y1146178D02*
X937993D01*
G01X934793Y1139978D02*
Y1146178D01*
G01X946155Y1150669D02*
Y1147469D01*
G01X939955D02*
Y1150669D01*
G01X946155Y1147469D02*
X939955D01*
G01X941993Y1139978D02*
X938793D01*
G01X941993Y1146178D02*
Y1139978D01*
G01X938793Y1146178D02*
X941993D01*
G01X938793Y1139978D02*
Y1146178D01*
G01X946060Y1139976D02*
X942860Y1139980D01*
G01X946066Y1146176D02*
X946060Y1139976D01*
G01X942866Y1146180D02*
X946066Y1146176D01*
G01X942860Y1139980D02*
X942866Y1146180D01*
G01X939955Y1150669D02*
X946155D01*
G01X944019Y1158231D02*
X940819D01*
G01X944019Y1164431D02*
Y1158231D01*
G01X940819D02*
Y1164431D01*
G01X946155Y1155097D02*
Y1151897D01*
G01X939955Y1155097D02*
X946155D01*
G01X939955Y1151897D02*
Y1155097D01*
G01X946155Y1151897D02*
X939955D01*
G01X944819Y1161431D02*
X951019D01*
G01X944819Y1158231D02*
Y1161431D01*
G01X951019Y1158231D02*
X944819D01*
G01X940819Y1164431D02*
X944019D01*
G01X942580Y1232593D02*
X946707D01*
G01X939580Y1235593D02*
X942580Y1232593D01*
G01X939580Y1254247D02*
Y1235593D01*
G01X937507Y1240820D02*
X934307D01*
G01X937507Y1247020D02*
Y1240820D01*
G01X934307Y1247020D02*
X937507D01*
G01X934307Y1240820D02*
Y1247020D01*
G01X946707Y1254247D02*
X939580D01*
G01X939271Y1461699D02*
Y1489579D01*
G01X959271Y1461699D02*
X939271D01*
G01X937504Y1478318D02*
X934404D01*
Y1479238D01*
X934559Y1479545D01*
X934921Y1479775D01*
X935334Y1479852D01*
X935747Y1479775D01*
X936057Y1479583D01*
X936212Y1479238D01*
Y1478318D01*
G01X937504Y1481342D02*
X934404D01*
Y1482108D01*
X934559Y1482415D01*
X934766Y1482645D01*
X935076Y1482837D01*
X935437Y1482990D01*
X935954Y1483028D01*
X936471Y1482990D01*
X936832Y1482837D01*
X937142Y1482645D01*
X937349Y1482415D01*
X937504Y1482108D01*
Y1481342D01*
G01Y1485285D02*
X934404D01*
X935024Y1484825D01*
G01X937504D02*
Y1485745D01*
G01Y1488308D02*
X936832Y1488385D01*
X936264Y1488500D01*
X935747Y1488653D01*
X935179Y1488845D01*
X934404Y1489152D01*
Y1487618D01*
G01X939271Y1489579D02*
X959271D01*
G01X939247Y1509621D02*
X936147D01*
Y1510541D01*
X936302Y1510848D01*
X936664Y1511078D01*
X937077Y1511155D01*
X937490Y1511078D01*
X937800Y1510886D01*
X937955Y1510541D01*
Y1509621D01*
G01X939247Y1512721D02*
X936147D01*
Y1513641D01*
X936302Y1513948D01*
X936664Y1514178D01*
X937077Y1514255D01*
X937490Y1514178D01*
X937800Y1513986D01*
X937955Y1513641D01*
Y1512721D01*
G01X939247Y1516588D02*
X939195Y1516281D01*
X938989Y1516013D01*
X938679Y1515783D01*
X938317Y1515630D01*
X937904Y1515553D01*
X937490D01*
X937077Y1515630D01*
X936715Y1515783D01*
X936405Y1516013D01*
X936199Y1516281D01*
X936147Y1516588D01*
X936199Y1516895D01*
X936405Y1517163D01*
X936715Y1517393D01*
X937077Y1517546D01*
X937490Y1517623D01*
X937904D01*
X938317Y1517546D01*
X938679Y1517393D01*
X938989Y1517163D01*
X939195Y1516895D01*
X939247Y1516588D01*
G01X938420Y1516895D02*
X939247Y1517355D01*
G01Y1519688D02*
X936147D01*
X936767Y1519228D01*
G01X939247D02*
Y1520148D01*
G01X940969Y1507588D02*
Y1526092D01*
G01X941802Y1507588D02*
X940969D01*
G01Y1526092D02*
X941602D01*
G01X935250Y1583833D02*
Y1580633D01*
G01Y1579833D02*
Y1576633D01*
G01X948037Y1569019D02*
X944937D01*
Y1569939D01*
X945092Y1570246D01*
X945454Y1570476D01*
X945867Y1570553D01*
X946280Y1570476D01*
X946590Y1570284D01*
X946745Y1569939D01*
Y1569019D01*
G01X948037Y1572119D02*
X944937D01*
Y1573078D01*
X945092Y1573384D01*
X945299Y1573576D01*
X945712Y1573653D01*
X946125Y1573576D01*
X946384Y1573346D01*
X946539Y1573078D01*
Y1572119D01*
G01Y1573078D02*
X948037Y1573653D01*
G01X946745Y1575258D02*
X946384Y1575526D01*
X946177Y1575756D01*
X946074Y1576063D01*
X946177Y1576331D01*
X946384Y1576523D01*
X946694Y1576676D01*
X947055Y1576714D01*
X947365Y1576676D01*
X947675Y1576523D01*
X947934Y1576293D01*
X948037Y1576024D01*
X947934Y1575718D01*
X947624Y1575449D01*
X947159Y1575296D01*
X946642Y1575258D01*
X945970Y1575334D01*
X945609Y1575449D01*
X945247Y1575641D01*
X944989Y1575909D01*
X944937Y1576178D01*
X945040Y1576446D01*
X945299Y1576638D01*
G01X944937Y1579086D02*
X945040Y1578779D01*
X945299Y1578549D01*
X945609Y1578396D01*
X946022Y1578281D01*
X946487Y1578243D01*
X946952Y1578281D01*
X947365Y1578396D01*
X947675Y1578549D01*
X947934Y1578779D01*
X948037Y1579086D01*
X947934Y1579393D01*
X947675Y1579623D01*
X947365Y1579776D01*
X946952Y1579891D01*
X946487Y1579929D01*
X946022Y1579891D01*
X945609Y1579776D01*
X945299Y1579623D01*
X945040Y1579393D01*
X944937Y1579086D01*
G01Y1582186D02*
X945040Y1581879D01*
X945299Y1581649D01*
X945609Y1581496D01*
X946022Y1581381D01*
X946487Y1581343D01*
X946952Y1581381D01*
X947365Y1581496D01*
X947675Y1581649D01*
X947934Y1581879D01*
X948037Y1582186D01*
X947934Y1582493D01*
X947675Y1582723D01*
X947365Y1582876D01*
X946952Y1582991D01*
X946487Y1583029D01*
X946022Y1582991D01*
X945609Y1582876D01*
X945299Y1582723D01*
X945040Y1582493D01*
X944937Y1582186D01*
G01X948037Y1585286D02*
X944937D01*
X945557Y1584826D01*
G01X948037D02*
Y1585746D01*
G01X935250Y1587833D02*
Y1584633D01*
G01Y1591833D02*
Y1588633D01*
G01X955872Y1682410D02*
X941688D01*
G01X955452Y159603D02*
Y171603D01*
G01X961452Y159603D02*
X955452D01*
G01Y171603D02*
X961452D01*
G01X950942Y178917D02*
X962942D01*
G01X950942Y172917D02*
Y178917D01*
G01X962942Y172917D02*
X950942D01*
G01X947443Y180471D02*
X978447D01*
G01X947443Y195271D02*
Y180471D01*
G01X978447Y195271D02*
X947443D01*
G01X960025Y203696D02*
X966225D01*
G01X960025Y200496D02*
Y203696D01*
G01X966225Y200496D02*
X960025D01*
G01X956525Y196571D02*
Y199771D01*
G01X962725Y196571D02*
X956525D01*
G01Y199771D02*
X962725D01*
G01X946863Y279256D02*
Y273056D01*
G01X950863Y279256D02*
Y273056D01*
G01D02*
X947663D01*
G01D02*
Y279256D01*
G01D02*
X950863D01*
G01X949681Y592017D02*
Y588817D01*
G01X949643Y586800D02*
Y583600D01*
G01X950331Y615750D02*
Y612550D01*
G01X949156Y630262D02*
Y627062D01*
G01X955883Y1054000D02*
Y1057100D01*
X956803D01*
X957110Y1056945D01*
X957340Y1056583D01*
X957417Y1056170D01*
X957340Y1055757D01*
X957148Y1055447D01*
X956803Y1055292D01*
X955883D01*
G01X958983Y1057100D02*
Y1054000D01*
X960517D01*
G01X962122Y1055292D02*
X962390Y1055653D01*
X962620Y1055860D01*
X962927Y1055963D01*
X963195Y1055860D01*
X963387Y1055653D01*
X963540Y1055343D01*
X963578Y1054982D01*
X963540Y1054672D01*
X963387Y1054362D01*
X963157Y1054103D01*
X962888Y1054000D01*
X962582Y1054103D01*
X962313Y1054413D01*
X962160Y1054878D01*
X962122Y1055395D01*
X962198Y1056067D01*
X962313Y1056428D01*
X962505Y1056790D01*
X962773Y1057048D01*
X963042Y1057100D01*
X963310Y1056997D01*
X963502Y1056738D01*
G01X965107Y1054465D02*
X965337Y1054207D01*
X965605Y1054052D01*
X965950Y1054000D01*
X966295Y1054103D01*
X966563Y1054310D01*
X966755Y1054672D01*
X966793Y1055085D01*
X966717Y1055498D01*
X966525Y1055757D01*
X966257Y1055963D01*
X965988Y1056015D01*
X965720Y1055963D01*
X965375Y1055757D01*
X965490Y1057100D01*
X966525D01*
G01X969050D02*
X968743Y1056997D01*
X968513Y1056738D01*
X968360Y1056428D01*
X968245Y1056015D01*
X968207Y1055550D01*
X968245Y1055085D01*
X968360Y1054672D01*
X968513Y1054362D01*
X968743Y1054103D01*
X969050Y1054000D01*
X969357Y1054103D01*
X969587Y1054362D01*
X969740Y1054672D01*
X969855Y1055085D01*
X969893Y1055550D01*
X969855Y1056015D01*
X969740Y1056428D01*
X969587Y1056738D01*
X969357Y1056997D01*
X969050Y1057100D01*
G01X972150D02*
X971843Y1056997D01*
X971613Y1056738D01*
X971460Y1056428D01*
X971345Y1056015D01*
X971307Y1055550D01*
X971345Y1055085D01*
X971460Y1054672D01*
X971613Y1054362D01*
X971843Y1054103D01*
X972150Y1054000D01*
X972457Y1054103D01*
X972687Y1054362D01*
X972840Y1054672D01*
X972955Y1055085D01*
X972993Y1055550D01*
X972955Y1056015D01*
X972840Y1056428D01*
X972687Y1056738D01*
X972457Y1056997D01*
X972150Y1057100D01*
G01X955919Y1114534D02*
Y1120534D01*
G01X967919Y1114534D02*
X955919D01*
G01Y1113534D02*
X967919D01*
G01X955919Y1107534D02*
Y1113534D01*
G01X967919Y1107534D02*
X955919D01*
G01X954000Y1119200D02*
Y1113200D01*
G01Y1112200D02*
Y1106200D01*
G01X955919Y1127534D02*
X967919D01*
G01X955919Y1121534D02*
Y1127534D01*
G01X967919Y1121534D02*
X955919D01*
G01Y1120534D02*
X967919D01*
G01X967800Y1134403D02*
Y1128403D01*
X955800D01*
Y1134403D01*
X967800D01*
G01X952053Y1140598D02*
X955855D01*
G01X952053Y1140869D02*
Y1140598D01*
G01X958155D02*
X964257D01*
G01X958173Y1162769D02*
Y1159569D01*
G01X951973Y1162769D02*
X958173D01*
G01X951973Y1159569D02*
Y1162769D01*
G01X958173Y1159569D02*
X951973D01*
G01X951019Y1161431D02*
Y1158231D01*
G01X961634Y1161854D02*
Y1164954D01*
X962554D01*
X962861Y1164799D01*
X963091Y1164437D01*
X963168Y1164024D01*
X963091Y1163611D01*
X962899Y1163301D01*
X962554Y1163146D01*
X961634D01*
G01X964658Y1164954D02*
Y1162732D01*
X964811Y1162267D01*
X965118Y1161957D01*
X965501Y1161854D01*
X965884Y1161957D01*
X966191Y1162267D01*
X966344Y1162732D01*
Y1164954D01*
G01X967873Y1163146D02*
X968141Y1163507D01*
X968371Y1163714D01*
X968678Y1163817D01*
X968946Y1163714D01*
X969138Y1163507D01*
X969291Y1163197D01*
X969329Y1162836D01*
X969291Y1162526D01*
X969138Y1162216D01*
X968908Y1161957D01*
X968639Y1161854D01*
X968333Y1161957D01*
X968064Y1162267D01*
X967911Y1162732D01*
X967873Y1163249D01*
X967949Y1163921D01*
X968064Y1164282D01*
X968256Y1164644D01*
X968524Y1164902D01*
X968793Y1164954D01*
X969061Y1164851D01*
X969253Y1164592D01*
G01X970858Y1162319D02*
X971088Y1162061D01*
X971356Y1161906D01*
X971701Y1161854D01*
X972046Y1161957D01*
X972314Y1162164D01*
X972506Y1162526D01*
X972544Y1162939D01*
X972468Y1163352D01*
X972276Y1163611D01*
X972008Y1163817D01*
X971739Y1163869D01*
X971471Y1163817D01*
X971126Y1163611D01*
X971241Y1164954D01*
X972276D01*
G01X974801D02*
X974494Y1164851D01*
X974264Y1164592D01*
X974111Y1164282D01*
X973996Y1163869D01*
X973958Y1163404D01*
X973996Y1162939D01*
X974111Y1162526D01*
X974264Y1162216D01*
X974494Y1161957D01*
X974801Y1161854D01*
X975108Y1161957D01*
X975338Y1162216D01*
X975491Y1162526D01*
X975606Y1162939D01*
X975644Y1163404D01*
X975606Y1163869D01*
X975491Y1164282D01*
X975338Y1164592D01*
X975108Y1164851D01*
X974801Y1164954D01*
G01X977901D02*
X977594Y1164851D01*
X977364Y1164592D01*
X977211Y1164282D01*
X977096Y1163869D01*
X977058Y1163404D01*
X977096Y1162939D01*
X977211Y1162526D01*
X977364Y1162216D01*
X977594Y1161957D01*
X977901Y1161854D01*
X978208Y1161957D01*
X978438Y1162216D01*
X978591Y1162526D01*
X978706Y1162939D01*
X978744Y1163404D01*
X978706Y1163869D01*
X978591Y1164282D01*
X978438Y1164592D01*
X978208Y1164851D01*
X977901Y1164954D01*
G01X952053Y1156740D02*
Y1156469D01*
G01X955855Y1156740D02*
X952053D01*
G01X964257D02*
X960455D01*
G01X961234Y1235593D02*
Y1254247D01*
G01X958234Y1232593D02*
X961234Y1235593D01*
G01X954107Y1232593D02*
X958234D01*
G01X961234Y1254247D02*
X954107D01*
G01X959271Y1489579D02*
Y1461699D01*
G01X957377Y1497095D02*
Y1500295D01*
G01X963577Y1497095D02*
X957377D01*
G01Y1500295D02*
X963577D01*
G01X961835Y1507588D02*
X960902D01*
G01X961202Y1526092D02*
X961835D01*
G01X946984Y1535124D02*
Y1566524D01*
G01X975184Y1535124D02*
X946984D01*
G01Y1566524D02*
X975184D01*
G01X956446Y1624836D02*
X980934D01*
G01X956446Y1627460D02*
Y1624836D01*
G01X980934Y1626417D02*
X956446D01*
G01X980934Y1626017D02*
X956446D01*
G01X980934Y1625617D02*
X956446D01*
G01X980934Y1625417D02*
X956446D01*
G01X980934Y1625217D02*
X956446D01*
G01X954453Y1634473D02*
Y1648973D01*
G01X956446Y1627360D02*
Y1664500D01*
G01X956739Y1627573D02*
X956939Y1627586D01*
G01X980934Y1627217D02*
X956446D01*
G01X980934Y1627611D02*
X956446D01*
G01X980934Y1627650D02*
X956446D01*
G01Y1629773D02*
Y1629667D01*
G01X980934Y1627611D02*
X956446D01*
G01Y1627460D02*
Y1627986D01*
G01Y1627260D02*
Y1632140D01*
G01X980934Y1627611D02*
X956446D01*
G01X980934Y1626717D02*
X956446D01*
G01X955759Y1652039D02*
X952659D01*
Y1652959D01*
X952814Y1653266D01*
X953176Y1653496D01*
X953589Y1653573D01*
X954002Y1653496D01*
X954312Y1653304D01*
X954467Y1652959D01*
Y1652039D01*
G01X955759Y1655063D02*
X952659D01*
Y1655829D01*
X952814Y1656136D01*
X953021Y1656366D01*
X953331Y1656558D01*
X953692Y1656711D01*
X954209Y1656749D01*
X954726Y1656711D01*
X955087Y1656558D01*
X955397Y1656366D01*
X955604Y1656136D01*
X955759Y1655829D01*
Y1655063D01*
G01Y1659006D02*
X952659D01*
X953279Y1658546D01*
G01X955759D02*
Y1659466D01*
G01X955294Y1661263D02*
X955552Y1661493D01*
X955707Y1661761D01*
X955759Y1662106D01*
X955656Y1662451D01*
X955449Y1662719D01*
X955087Y1662911D01*
X954674Y1662949D01*
X954261Y1662873D01*
X954002Y1662681D01*
X953796Y1662413D01*
X953744Y1662144D01*
X953796Y1661876D01*
X954002Y1661531D01*
X952659Y1661646D01*
Y1662681D01*
G01X956446Y1664500D02*
X980934D01*
G01X966551Y147946D02*
X963451D01*
Y148866D01*
X963606Y149173D01*
X963968Y149403D01*
X964381Y149480D01*
X964794Y149403D01*
X965104Y149211D01*
X965259Y148866D01*
Y147946D01*
G01X966551Y150970D02*
X963451D01*
Y151736D01*
X963606Y152043D01*
X963813Y152273D01*
X964123Y152465D01*
X964484Y152618D01*
X965001Y152656D01*
X965518Y152618D01*
X965879Y152465D01*
X966189Y152273D01*
X966396Y152043D01*
X966551Y151736D01*
Y150970D01*
G01Y154913D02*
X963451D01*
X964071Y154453D01*
G01X966551D02*
Y155373D01*
G01Y158013D02*
X963451D01*
X964071Y157553D01*
G01X966551D02*
Y158473D01*
G01X963968Y160385D02*
X963658Y160615D01*
X963503Y160883D01*
X963451Y161190D01*
X963554Y161573D01*
X963813Y161841D01*
X964123Y161918D01*
X964433Y161880D01*
X964691Y161726D01*
X965208Y160960D01*
X965569Y160615D01*
X966086Y160385D01*
X966551Y160308D01*
Y161918D01*
G01X974808Y144009D02*
Y146249D01*
G01X973183Y145036D02*
X976433D01*
G01X968660Y147650D02*
Y177209D01*
G01X980156Y147650D02*
X968660D01*
G01X963842Y163285D02*
Y169485D01*
G01X967042D02*
Y163285D01*
G01D02*
X963842D01*
G01X961452Y171603D02*
Y159603D01*
G01X963842Y169485D02*
X967042D01*
G01Y170285D02*
X963842D01*
G01X967042Y176485D02*
Y170285D01*
G01X963842D02*
Y176485D01*
G01D02*
X967042D01*
G01X962942Y178917D02*
Y172917D01*
G01X976693Y180102D02*
Y177676D01*
G01X968660Y177209D02*
X980156D01*
G01X966225Y203696D02*
Y200496D01*
G01X978795Y206323D02*
X975595D01*
G01D02*
Y212523D01*
G01X969725Y199771D02*
Y196571D01*
G01X963525Y199771D02*
X969725D01*
G01X963525Y196571D02*
Y199771D01*
G01X969725Y196571D02*
X963525D01*
G01X962725Y199771D02*
Y196571D01*
G01X972390Y218589D02*
Y206589D01*
G01D02*
X966390D01*
G01D02*
Y218589D01*
G01X968383Y201500D02*
Y204600D01*
X969342D01*
X969648Y204445D01*
X969840Y204238D01*
X969917Y203825D01*
X969840Y203412D01*
X969610Y203153D01*
X969342Y202998D01*
X968383D01*
G01X969342D02*
X969917Y201500D01*
G01X972250D02*
Y204600D01*
X971790Y203980D01*
G01Y201500D02*
X972710D01*
G01X974507Y202120D02*
X974737Y201758D01*
X975043Y201552D01*
X975388Y201500D01*
X975695Y201552D01*
X976002Y201810D01*
X976193Y202120D01*
X976232Y202430D01*
X976155Y202792D01*
X975887Y203050D01*
X975618Y203153D01*
X975273D01*
G01X975618D02*
X975848Y203308D01*
X976040Y203567D01*
X976117Y203877D01*
X976040Y204187D01*
X975848Y204445D01*
X975503Y204600D01*
X975158Y204548D01*
X974813Y204342D01*
G01X977722Y204083D02*
X977952Y204393D01*
X978220Y204548D01*
X978527Y204600D01*
X978910Y204497D01*
X979178Y204238D01*
X979255Y203928D01*
X979217Y203618D01*
X979063Y203360D01*
X978297Y202843D01*
X977952Y202482D01*
X977722Y201965D01*
X977645Y201500D01*
X979255D01*
G01X980707Y202120D02*
X980937Y201758D01*
X981243Y201552D01*
X981588Y201500D01*
X981895Y201552D01*
X982202Y201810D01*
X982393Y202120D01*
X982432Y202430D01*
X982355Y202792D01*
X982087Y203050D01*
X981818Y203153D01*
X981473D01*
G01X981818D02*
X982048Y203308D01*
X982240Y203567D01*
X982317Y203877D01*
X982240Y204187D01*
X982048Y204445D01*
X981703Y204600D01*
X981358Y204548D01*
X981013Y204342D01*
G01X975595Y212523D02*
X978795D01*
G01X966390Y218589D02*
X972390D01*
G01X979677Y231041D02*
Y228507D01*
X974677D01*
Y231041D01*
G01X977094Y230027D02*
Y228507D01*
G01X979677Y234874D02*
X974677D01*
X975677Y234114D01*
G01X979677D02*
Y235634D01*
G01X979844Y239974D02*
X979760Y239847D01*
X979594D01*
X979510Y239974D01*
X979594Y240101D01*
X979760D01*
X979844Y239974D01*
G01X979010Y243744D02*
X979427Y244251D01*
X979677Y244821D01*
Y245327D01*
X979427Y245834D01*
X979010Y246214D01*
X978427Y246404D01*
X977844Y246277D01*
X977344Y245961D01*
X977010Y245391D01*
X976844Y244631D01*
X976510Y244187D01*
X975927Y243997D01*
X975344Y244124D01*
X974927Y244441D01*
X974677Y244884D01*
Y245327D01*
X974844Y245771D01*
X975260Y246151D01*
G01X979010Y253944D02*
X979427Y254451D01*
X979677Y255021D01*
Y255527D01*
X979427Y256034D01*
X979010Y256414D01*
X978427Y256604D01*
X977844Y256477D01*
X977344Y256161D01*
X977010Y255591D01*
X976844Y254831D01*
X976510Y254387D01*
X975927Y254197D01*
X975344Y254324D01*
X974927Y254641D01*
X974677Y255084D01*
Y255527D01*
X974844Y255971D01*
X975260Y256351D01*
G01X974677Y259107D02*
X979677D01*
Y261641D01*
G01Y265474D02*
X979594Y264967D01*
X979260Y264524D01*
X978760Y264144D01*
X978177Y263891D01*
X977510Y263764D01*
X976844D01*
X976177Y263891D01*
X975594Y264144D01*
X975094Y264524D01*
X974760Y264967D01*
X974677Y265474D01*
X974760Y265981D01*
X975094Y266424D01*
X975594Y266804D01*
X976177Y267057D01*
X976844Y267184D01*
X977510D01*
X978177Y267057D01*
X978760Y266804D01*
X979260Y266424D01*
X979594Y265981D01*
X979677Y265474D01*
G01X974677Y270574D02*
X979677D01*
G01X974677Y269117D02*
Y272031D01*
G01Y280774D02*
X974844Y280267D01*
X975260Y279887D01*
X975760Y279634D01*
X976427Y279444D01*
X977177Y279381D01*
X977927Y279444D01*
X978594Y279634D01*
X979094Y279887D01*
X979510Y280267D01*
X979677Y280774D01*
X979510Y281281D01*
X979094Y281661D01*
X978594Y281914D01*
X977927Y282104D01*
X977177Y282167D01*
X976427Y282104D01*
X975760Y281914D01*
X975260Y281661D01*
X974844Y281281D01*
X974677Y280774D01*
G01X981344Y290657D02*
X980510Y290024D01*
X979677Y289707D01*
X976344D01*
X975510Y290024D01*
X974677Y290657D01*
G01X979677Y294807D02*
X974677D01*
Y296327D01*
X974927Y296834D01*
X975510Y297214D01*
X976177Y297341D01*
X976844Y297214D01*
X977344Y296897D01*
X977594Y296327D01*
Y294807D01*
G01X975094Y302567D02*
X974844Y302187D01*
X974677Y301744D01*
Y301237D01*
X974927Y300667D01*
X975344Y300224D01*
X975844Y299907D01*
X976677Y299654D01*
X977427Y299591D01*
X978177Y299717D01*
X978677Y299907D01*
X979177Y300287D01*
X979510Y300731D01*
X979677Y301174D01*
Y301617D01*
X979510Y302061D01*
X979260Y302441D01*
X978927Y302757D01*
G01X974677Y305514D02*
Y307034D01*
G01Y306274D02*
X979677D01*
G01Y305514D02*
Y307034D01*
G01X977427Y310424D02*
Y312451D01*
X976844Y312261D01*
X976510Y311944D01*
X976344Y311501D01*
X976427Y311057D01*
X976677Y310677D01*
X977260Y310424D01*
X977760Y310297D01*
X978260D01*
X978760Y310424D01*
X979260Y310741D01*
X979594Y311121D01*
X979677Y311564D01*
X979510Y312007D01*
X979010Y312451D01*
G01X976344Y320624D02*
X979677Y322524D01*
G01X976344D02*
X979677Y320624D01*
G01Y327434D02*
X974677D01*
X978260Y325091D01*
Y328257D01*
G01X981344Y332091D02*
X980510Y332724D01*
X979677Y333041D01*
X976344D01*
X975510Y332724D01*
X974677Y332091D01*
G01X975625Y1057084D02*
X981825D01*
G01X975625Y1053884D02*
Y1057084D01*
G01X981825Y1053884D02*
X975625D01*
G01X987083Y1059126D02*
X969367D01*
G01D02*
Y1062534D01*
G01Y1073434D02*
Y1076842D01*
G01D02*
X987083D01*
G01X963821Y1083809D02*
Y1088558D01*
G01X968758Y1078872D02*
X963821Y1083809D01*
G01X990593Y1078872D02*
X968758D01*
G01X963821Y1100707D02*
Y1095958D01*
G01X968758Y1105644D02*
X963821Y1100707D01*
G01X967919Y1120534D02*
Y1114534D01*
G01Y1113534D02*
Y1107534D01*
G01X973383Y1108000D02*
Y1111100D01*
X974303D01*
X974610Y1110945D01*
X974840Y1110583D01*
X974917Y1110170D01*
X974840Y1109757D01*
X974648Y1109447D01*
X974303Y1109292D01*
X973383D01*
G01X978093Y1110842D02*
X977863Y1110997D01*
X977595Y1111100D01*
X977288D01*
X976943Y1110945D01*
X976675Y1110687D01*
X976483Y1110377D01*
X976330Y1109860D01*
X976292Y1109395D01*
X976368Y1108930D01*
X976483Y1108620D01*
X976713Y1108310D01*
X976982Y1108103D01*
X977250Y1108000D01*
X977518D01*
X977787Y1108103D01*
X978017Y1108258D01*
X978208Y1108465D01*
G01X979622Y1109292D02*
X979890Y1109653D01*
X980120Y1109860D01*
X980427Y1109963D01*
X980695Y1109860D01*
X980887Y1109653D01*
X981040Y1109343D01*
X981078Y1108982D01*
X981040Y1108672D01*
X980887Y1108362D01*
X980657Y1108103D01*
X980388Y1108000D01*
X980082Y1108103D01*
X979813Y1108413D01*
X979660Y1108878D01*
X979622Y1109395D01*
X979698Y1110067D01*
X979813Y1110428D01*
X980005Y1110790D01*
X980273Y1111048D01*
X980542Y1111100D01*
X980810Y1110997D01*
X981002Y1110738D01*
G01X983450Y1108000D02*
X983718Y1108052D01*
X984025Y1108207D01*
X984217Y1108465D01*
X984293Y1108827D01*
X984217Y1109188D01*
X983987Y1109498D01*
X983642Y1109653D01*
X983258D01*
X983028Y1109757D01*
X982837Y1110015D01*
X982760Y1110377D01*
X982875Y1110738D01*
X983143Y1110997D01*
X983450Y1111100D01*
X983757Y1110997D01*
X984025Y1110738D01*
X984140Y1110377D01*
X984063Y1110015D01*
X983872Y1109757D01*
X983642Y1109653D01*
X983258D01*
X982913Y1109498D01*
X982683Y1109188D01*
X982607Y1108827D01*
X982683Y1108465D01*
X982875Y1108207D01*
X983182Y1108052D01*
X983450Y1108000D01*
G01X986550Y1111100D02*
X986243Y1110997D01*
X986013Y1110738D01*
X985860Y1110428D01*
X985745Y1110015D01*
X985707Y1109550D01*
X985745Y1109085D01*
X985860Y1108672D01*
X986013Y1108362D01*
X986243Y1108103D01*
X986550Y1108000D01*
X986857Y1108103D01*
X987087Y1108362D01*
X987240Y1108672D01*
X987355Y1109085D01*
X987393Y1109550D01*
X987355Y1110015D01*
X987240Y1110428D01*
X987087Y1110738D01*
X986857Y1110997D01*
X986550Y1111100D01*
G01X989650D02*
X989343Y1110997D01*
X989113Y1110738D01*
X988960Y1110428D01*
X988845Y1110015D01*
X988807Y1109550D01*
X988845Y1109085D01*
X988960Y1108672D01*
X989113Y1108362D01*
X989343Y1108103D01*
X989650Y1108000D01*
X989957Y1108103D01*
X990187Y1108362D01*
X990340Y1108672D01*
X990455Y1109085D01*
X990493Y1109550D01*
X990455Y1110015D01*
X990340Y1110428D01*
X990187Y1110738D01*
X989957Y1110997D01*
X989650Y1111100D01*
G01X990593Y1105644D02*
X968758D01*
G01X967919Y1127534D02*
Y1121534D01*
G01X964257Y1140598D02*
Y1141069D01*
G01X967872Y1157175D02*
X971072D01*
G01X967872Y1150975D02*
Y1157175D01*
G01X971072Y1150975D02*
X967872D01*
G01X971072Y1157175D02*
Y1150975D01*
G01X964257Y1156469D02*
Y1156740D01*
G01X966580Y1232593D02*
X970707D01*
G01X963580Y1235593D02*
X966580Y1232593D01*
G01X963580Y1254247D02*
Y1235593D01*
G01X970707Y1254247D02*
X963580D01*
G01X966683Y1486159D02*
Y1489259D01*
X967603D01*
X967910Y1489104D01*
X968140Y1488742D01*
X968217Y1488329D01*
X968140Y1487916D01*
X967948Y1487606D01*
X967603Y1487451D01*
X966683D01*
G01X969783Y1486159D02*
Y1489259D01*
X970703D01*
X971010Y1489104D01*
X971240Y1488742D01*
X971317Y1488329D01*
X971240Y1487916D01*
X971048Y1487606D01*
X970703Y1487451D01*
X969783D01*
G01X973650Y1486159D02*
X973343Y1486211D01*
X973075Y1486417D01*
X972845Y1486727D01*
X972692Y1487089D01*
X972615Y1487502D01*
Y1487916D01*
X972692Y1488329D01*
X972845Y1488691D01*
X973075Y1489001D01*
X973343Y1489207D01*
X973650Y1489259D01*
X973957Y1489207D01*
X974225Y1489001D01*
X974455Y1488691D01*
X974608Y1488329D01*
X974685Y1487916D01*
Y1487502D01*
X974608Y1487089D01*
X974455Y1486727D01*
X974225Y1486417D01*
X973957Y1486211D01*
X973650Y1486159D01*
G01X973957Y1486986D02*
X974417Y1486159D01*
G01X976022Y1488742D02*
X976252Y1489052D01*
X976520Y1489207D01*
X976827Y1489259D01*
X977210Y1489156D01*
X977478Y1488897D01*
X977555Y1488587D01*
X977517Y1488277D01*
X977363Y1488019D01*
X976597Y1487502D01*
X976252Y1487141D01*
X976022Y1486624D01*
X975945Y1486159D01*
X977555D01*
G01X963577Y1500295D02*
Y1497095D01*
G01X961835Y1526092D02*
Y1507588D01*
G01X964335D02*
Y1526092D01*
G01X965168Y1507588D02*
X964335D01*
G01Y1526092D02*
X964968D01*
G01X975184Y1566524D02*
Y1535124D01*
G01X967990Y1621567D02*
Y1623993D01*
G01X968690Y1643136D02*
Y1641336D01*
G01X963690Y1643136D02*
X973690D01*
G01X968690D02*
X964690Y1648136D01*
G01X972690D02*
X968690Y1643136D01*
G01X964690Y1648136D02*
X972690D01*
G01X968690Y1650336D02*
Y1648536D01*
G01X968590Y1666009D02*
Y1668249D01*
G01X966965Y1667036D02*
X970215D01*
G01X990872Y1682410D02*
X971688D01*
G01X980156Y177209D02*
Y147650D01*
G01X987100Y156899D02*
Y150699D01*
G01D02*
X983900D01*
G01D02*
Y156899D01*
G01D02*
X987100D01*
G01X996100Y150699D02*
X989900D01*
G01D02*
Y153899D01*
G01D02*
X996100D01*
G01X988005Y177953D02*
Y184153D01*
G01X991205Y177953D02*
X988005D01*
G01X983045Y177983D02*
X979845D01*
G01X983045Y184183D02*
Y177983D01*
G01X979845D02*
Y184183D01*
G01X983845Y177983D02*
Y184183D01*
G01X987045Y177983D02*
X983845D01*
G01X987045Y184183D02*
Y177983D01*
G01X987024Y177083D02*
Y173883D01*
G01X980824Y177083D02*
X987024D01*
G01X980824Y173883D02*
Y177083D01*
G01X987024Y173883D02*
X980824D01*
G01X988005Y184153D02*
X991205D01*
G01X980024Y187747D02*
Y190947D01*
G01X986224Y187747D02*
X980024D01*
G01X986224Y190947D02*
Y187747D01*
G01X980024Y190947D02*
X986224D01*
G01X987235Y190353D02*
Y196553D01*
G01X990435Y190353D02*
X987235D01*
G01X990435Y196553D02*
Y190353D01*
G01X979845Y184183D02*
X983045D01*
G01X983845D02*
X987045D01*
G01X990065Y186336D02*
X989815Y186496D01*
X989690Y186683D01*
X989648Y186896D01*
X989731Y187163D01*
X989940Y187350D01*
X990190Y187403D01*
X990440Y187376D01*
X990648Y187270D01*
X991065Y186736D01*
X991356Y186496D01*
X991773Y186336D01*
X992148Y186283D01*
Y187403D01*
G01X989648Y189043D02*
X989731Y188830D01*
X989940Y188670D01*
X990190Y188563D01*
X990523Y188483D01*
X990898Y188456D01*
X991273Y188483D01*
X991606Y188563D01*
X991856Y188670D01*
X992065Y188830D01*
X992148Y189043D01*
X992065Y189256D01*
X991856Y189416D01*
X991606Y189523D01*
X991273Y189603D01*
X990898Y189630D01*
X990523Y189603D01*
X990190Y189523D01*
X989940Y189416D01*
X989731Y189256D01*
X989648Y189043D01*
G01X978447Y180471D02*
Y195271D01*
G01X987235Y196553D02*
X990435D01*
G01X978795Y212523D02*
Y206323D01*
G01X985628Y219433D02*
Y209233D01*
G01D02*
X981028D01*
G01D02*
Y219433D01*
G01X985928Y209233D02*
Y219433D01*
G01X990528D02*
Y209233D01*
G01D02*
X985928D01*
G01X981028Y219433D02*
X985628D01*
G01X985928D02*
X990528D01*
G01X986598Y221223D02*
X984098D01*
X984598Y220903D01*
G01X986598D02*
Y221543D01*
G01X984515Y222916D02*
X984265Y223076D01*
X984140Y223263D01*
X984098Y223476D01*
X984181Y223743D01*
X984390Y223930D01*
X984640Y223983D01*
X984890Y223956D01*
X985098Y223850D01*
X985515Y223316D01*
X985806Y223076D01*
X986223Y222916D01*
X986598Y222863D01*
Y223983D01*
G01X991405Y224086D02*
Y221586D01*
X991725Y222086D01*
G01Y224086D02*
X991085D01*
G01X989205D02*
Y221586D01*
X989525Y222086D01*
G01Y224086D02*
X988885D01*
G01X983355Y262381D02*
X989555D01*
G01D02*
Y259181D01*
G01D02*
X983355D01*
G01D02*
Y262381D01*
G01X989555Y263181D02*
X983355D01*
G01D02*
Y266381D01*
G01D02*
X989555D01*
G01D02*
Y263181D01*
G01X983355Y273043D02*
X989555D01*
G01D02*
Y269843D01*
G01D02*
X983355D01*
G01D02*
Y273043D01*
G01X989555Y273843D02*
X983355D01*
G01D02*
Y277043D01*
G01D02*
X989555D01*
G01D02*
Y273843D01*
G01X982984Y297241D02*
X989184D01*
G01D02*
Y294041D01*
G01D02*
X982984D01*
G01D02*
Y297241D01*
G01X986860Y368136D02*
X990060D01*
G01X986860Y361936D02*
Y368136D01*
G01X990060Y361936D02*
X986860D01*
G01X990060Y368136D02*
Y361936D01*
G01X994060D02*
X990860D01*
G01Y368136D02*
X994060D01*
G01X990860Y361936D02*
Y368136D01*
G01X985586Y397381D02*
Y382665D01*
G01D02*
X1005664D01*
G01Y397381D02*
X985586D01*
G01X990578Y430728D02*
Y418524D01*
G01D02*
X1004226D01*
G01X994800Y430728D02*
X990578D01*
G01X986956Y517614D02*
X993156D01*
G01Y514414D02*
X986956D01*
G01D02*
Y517614D01*
G01Y522614D02*
X993156D01*
G01Y519414D02*
X986956D01*
G01D02*
Y522614D01*
G01Y527674D02*
X993156D01*
G01Y524474D02*
X986956D01*
G01D02*
Y527674D01*
G01Y532674D02*
X993156D01*
G01Y529474D02*
X986956D01*
G01D02*
Y532674D01*
G01X981825Y1057084D02*
Y1053884D01*
G01X987083Y1062534D02*
Y1059126D01*
G01Y1076842D02*
Y1073434D01*
G01X990593Y1088558D02*
Y1078872D01*
G01Y1095958D02*
Y1105644D01*
G01X994220Y1166075D02*
X995111D01*
X1001756Y1159430D01*
Y1159205D01*
X1001531D01*
X994756Y1165980D01*
X990920D01*
X990817Y1165877D01*
X990995D01*
X1001683Y1155189D01*
Y1155733D01*
X991436Y1165980D01*
X991944D01*
X1001605Y1156319D01*
Y1156221D01*
G01X990236Y1166220D02*
X1002047Y1154409D01*
G01Y1166220D02*
X990236D01*
G01X987000Y1168383D02*
X983900D01*
Y1169303D01*
X984055Y1169610D01*
X984417Y1169840D01*
X984830Y1169917D01*
X985243Y1169840D01*
X985553Y1169648D01*
X985708Y1169303D01*
Y1168383D01*
G01X983900Y1171483D02*
X987000D01*
Y1173017D01*
G01X985708Y1174622D02*
X985347Y1174890D01*
X985140Y1175120D01*
X985037Y1175427D01*
X985140Y1175695D01*
X985347Y1175887D01*
X985657Y1176040D01*
X986018Y1176078D01*
X986328Y1176040D01*
X986638Y1175887D01*
X986897Y1175657D01*
X987000Y1175388D01*
X986897Y1175082D01*
X986587Y1174813D01*
X986122Y1174660D01*
X985605Y1174622D01*
X984933Y1174698D01*
X984572Y1174813D01*
X984210Y1175005D01*
X983952Y1175273D01*
X983900Y1175542D01*
X984003Y1175810D01*
X984262Y1176002D01*
G01X986535Y1177607D02*
X986793Y1177837D01*
X986948Y1178105D01*
X987000Y1178450D01*
X986897Y1178795D01*
X986690Y1179063D01*
X986328Y1179255D01*
X985915Y1179293D01*
X985502Y1179217D01*
X985243Y1179025D01*
X985037Y1178757D01*
X984985Y1178488D01*
X985037Y1178220D01*
X985243Y1177875D01*
X983900Y1177990D01*
Y1179025D01*
G01Y1181550D02*
X984003Y1181243D01*
X984262Y1181013D01*
X984572Y1180860D01*
X984985Y1180745D01*
X985450Y1180707D01*
X985915Y1180745D01*
X986328Y1180860D01*
X986638Y1181013D01*
X986897Y1181243D01*
X987000Y1181550D01*
X986897Y1181857D01*
X986638Y1182087D01*
X986328Y1182240D01*
X985915Y1182355D01*
X985450Y1182393D01*
X984985Y1182355D01*
X984572Y1182240D01*
X984262Y1182087D01*
X984003Y1181857D01*
X983900Y1181550D01*
G01X987000Y1184650D02*
X983900D01*
X984520Y1184190D01*
G01X987000D02*
Y1185110D01*
G01X981701Y1226789D02*
Y1168189D01*
G01X982234Y1232593D02*
X985234Y1235593D01*
G01X978107Y1232593D02*
X982234D01*
G01X985234Y1235593D02*
Y1254247D01*
G01X991000Y1236883D02*
X987900D01*
Y1237803D01*
X988055Y1238110D01*
X988417Y1238340D01*
X988830Y1238417D01*
X989243Y1238340D01*
X989553Y1238148D01*
X989708Y1237803D01*
Y1236883D01*
G01X988158Y1241593D02*
X988003Y1241363D01*
X987900Y1241095D01*
Y1240788D01*
X988055Y1240443D01*
X988313Y1240175D01*
X988623Y1239983D01*
X989140Y1239830D01*
X989605Y1239792D01*
X990070Y1239868D01*
X990380Y1239983D01*
X990690Y1240213D01*
X990897Y1240482D01*
X991000Y1240750D01*
Y1241018D01*
X990897Y1241287D01*
X990742Y1241517D01*
X990535Y1241708D01*
G01X989708Y1243122D02*
X989347Y1243390D01*
X989140Y1243620D01*
X989037Y1243927D01*
X989140Y1244195D01*
X989347Y1244387D01*
X989657Y1244540D01*
X990018Y1244578D01*
X990328Y1244540D01*
X990638Y1244387D01*
X990897Y1244157D01*
X991000Y1243888D01*
X990897Y1243582D01*
X990587Y1243313D01*
X990122Y1243160D01*
X989605Y1243122D01*
X988933Y1243198D01*
X988572Y1243313D01*
X988210Y1243505D01*
X987952Y1243773D01*
X987900Y1244042D01*
X988003Y1244310D01*
X988262Y1244502D01*
G01X990535Y1246107D02*
X990793Y1246337D01*
X990948Y1246605D01*
X991000Y1246950D01*
X990897Y1247295D01*
X990690Y1247563D01*
X990328Y1247755D01*
X989915Y1247793D01*
X989502Y1247717D01*
X989243Y1247525D01*
X989037Y1247257D01*
X988985Y1246988D01*
X989037Y1246720D01*
X989243Y1246375D01*
X987900Y1246490D01*
Y1247525D01*
G01X991000Y1250050D02*
X987900D01*
X988520Y1249590D01*
G01X991000D02*
Y1250510D01*
G01X990380Y1252307D02*
X990742Y1252537D01*
X990948Y1252843D01*
X991000Y1253188D01*
X990948Y1253495D01*
X990690Y1253802D01*
X990380Y1253993D01*
X990070Y1254032D01*
X989708Y1253955D01*
X989450Y1253687D01*
X989347Y1253418D01*
Y1253073D01*
G01Y1253418D02*
X989192Y1253648D01*
X988933Y1253840D01*
X988623Y1253917D01*
X988313Y1253840D01*
X988055Y1253648D01*
X987900Y1253303D01*
X987952Y1252958D01*
X988158Y1252613D01*
G01X985234Y1254247D02*
X978107D01*
G01X1047736Y1420331D02*
G02I-31496J0D01*
G01X988903Y1485933D02*
Y1489033D01*
X989823D01*
X990130Y1488878D01*
X990360Y1488516D01*
X990437Y1488103D01*
X990360Y1487690D01*
X990168Y1487380D01*
X989823Y1487225D01*
X988903D01*
G01X992003Y1485933D02*
Y1489033D01*
X992923D01*
X993230Y1488878D01*
X993460Y1488516D01*
X993537Y1488103D01*
X993460Y1487690D01*
X993268Y1487380D01*
X992923Y1487225D01*
X992003D01*
G01X995870Y1485933D02*
X995563Y1485985D01*
X995295Y1486191D01*
X995065Y1486501D01*
X994912Y1486863D01*
X994835Y1487276D01*
Y1487690D01*
X994912Y1488103D01*
X995065Y1488465D01*
X995295Y1488775D01*
X995563Y1488981D01*
X995870Y1489033D01*
X996177Y1488981D01*
X996445Y1488775D01*
X996675Y1488465D01*
X996828Y1488103D01*
X996905Y1487690D01*
Y1487276D01*
X996828Y1486863D01*
X996675Y1486501D01*
X996445Y1486191D01*
X996177Y1485985D01*
X995870Y1485933D01*
G01X996177Y1486760D02*
X996637Y1485933D01*
G01X998127Y1486398D02*
X998357Y1486140D01*
X998625Y1485985D01*
X998970Y1485933D01*
X999315Y1486036D01*
X999583Y1486243D01*
X999775Y1486605D01*
X999813Y1487018D01*
X999737Y1487431D01*
X999545Y1487690D01*
X999277Y1487896D01*
X999008Y1487948D01*
X998740Y1487896D01*
X998395Y1487690D01*
X998510Y1489033D01*
X999545D01*
G01X980743Y1497095D02*
Y1500295D01*
G01X986943Y1497095D02*
X980743D01*
G01X986943Y1500295D02*
Y1497095D01*
G01X980743Y1500295D02*
X986943D01*
G01X985201Y1507588D02*
X984268D01*
G01X985201Y1526092D02*
Y1507588D01*
G01X987701D02*
Y1526092D01*
G01X988534Y1507588D02*
X987701D01*
G01X984568Y1526092D02*
X985201D01*
G01X987701D02*
X988334D01*
G01X978596Y1535140D02*
Y1566540D01*
G01X1006796Y1535140D02*
X978596D01*
G01Y1566540D02*
X1006796D01*
G01X981955Y1569113D02*
X978855D01*
Y1570033D01*
X979010Y1570340D01*
X979372Y1570570D01*
X979785Y1570647D01*
X980198Y1570570D01*
X980508Y1570378D01*
X980663Y1570033D01*
Y1569113D01*
G01X981955Y1572213D02*
X978855D01*
Y1573172D01*
X979010Y1573478D01*
X979217Y1573670D01*
X979630Y1573747D01*
X980043Y1573670D01*
X980302Y1573440D01*
X980457Y1573172D01*
Y1572213D01*
G01Y1573172D02*
X981955Y1573747D01*
G01X979372Y1575352D02*
X979062Y1575582D01*
X978907Y1575850D01*
X978855Y1576157D01*
X978958Y1576540D01*
X979217Y1576808D01*
X979527Y1576885D01*
X979837Y1576847D01*
X980095Y1576693D01*
X980612Y1575927D01*
X980973Y1575582D01*
X981490Y1575352D01*
X981955Y1575275D01*
Y1576885D01*
G01X981490Y1578337D02*
X981748Y1578567D01*
X981903Y1578835D01*
X981955Y1579180D01*
X981852Y1579525D01*
X981645Y1579793D01*
X981283Y1579985D01*
X980870Y1580023D01*
X980457Y1579947D01*
X980198Y1579755D01*
X979992Y1579487D01*
X979940Y1579218D01*
X979992Y1578950D01*
X980198Y1578605D01*
X978855Y1578720D01*
Y1579755D01*
G01X981335Y1581437D02*
X981697Y1581667D01*
X981903Y1581973D01*
X981955Y1582318D01*
X981903Y1582625D01*
X981645Y1582932D01*
X981335Y1583123D01*
X981025Y1583162D01*
X980663Y1583085D01*
X980405Y1582817D01*
X980302Y1582548D01*
Y1582203D01*
G01Y1582548D02*
X980147Y1582778D01*
X979888Y1582970D01*
X979578Y1583047D01*
X979268Y1582970D01*
X979010Y1582778D01*
X978855Y1582433D01*
X978907Y1582088D01*
X979113Y1581743D01*
G01X981335Y1584537D02*
X981697Y1584767D01*
X981903Y1585073D01*
X981955Y1585418D01*
X981903Y1585725D01*
X981645Y1586032D01*
X981335Y1586223D01*
X981025Y1586262D01*
X980663Y1586185D01*
X980405Y1585917D01*
X980302Y1585648D01*
Y1585303D01*
G01Y1585648D02*
X980147Y1585878D01*
X979888Y1586070D01*
X979578Y1586147D01*
X979268Y1586070D01*
X979010Y1585878D01*
X978855Y1585533D01*
X978907Y1585188D01*
X979113Y1584843D01*
G01X980934Y1624836D02*
Y1627305D01*
G01X995614Y1621536D02*
Y1623962D01*
G01X1008558Y1625186D02*
X984070D01*
G01X1008558Y1625386D02*
X984070D01*
G01X1008558Y1625586D02*
X984070D01*
G01X1008558Y1625986D02*
X984070D01*
G01X1008558Y1626386D02*
X984070D01*
G01Y1624805D02*
X1008558D01*
G01X984070Y1627429D02*
Y1624805D01*
G01X980934Y1664500D02*
Y1627460D01*
G01Y1629667D02*
Y1627260D01*
G01Y1628373D02*
Y1629573D01*
G01Y1627986D02*
Y1629273D01*
G01X1008558Y1626686D02*
X984070D01*
G01X1008558Y1627580D02*
X984070D01*
G01Y1627229D02*
Y1632109D01*
G01Y1627429D02*
Y1627955D01*
G01X1008558Y1627580D02*
X984070D01*
G01Y1629742D02*
Y1629636D01*
G01X1008558Y1627619D02*
X984070D01*
G01X1008558Y1627580D02*
X984070D01*
G01X1008558Y1627186D02*
X984070D01*
G01X984363Y1627542D02*
X984563Y1627555D01*
G01X984070Y1627329D02*
Y1664469D01*
G01D02*
X1008558D01*
G01X1007335Y156343D02*
X1004135D01*
G01D02*
Y162543D01*
G01D02*
X1007335D01*
G01X1003100Y150699D02*
X996900D01*
G01D02*
Y153899D01*
G01D02*
X1003100D01*
G01D02*
Y150699D01*
G01X996100Y153899D02*
Y150699D01*
G01X1003366Y165970D02*
Y169070D01*
X1004286D01*
X1004593Y168915D01*
X1004823Y168553D01*
X1004900Y168140D01*
X1004823Y167727D01*
X1004631Y167417D01*
X1004286Y167262D01*
X1003366D01*
G01X1006390Y169070D02*
Y166848D01*
X1006543Y166383D01*
X1006850Y166073D01*
X1007233Y165970D01*
X1007616Y166073D01*
X1007923Y166383D01*
X1008076Y166848D01*
Y169070D01*
G01X1009605Y168553D02*
X1009835Y168863D01*
X1010103Y169018D01*
X1010410Y169070D01*
X1010793Y168967D01*
X1011061Y168708D01*
X1011138Y168398D01*
X1011100Y168088D01*
X1010946Y167830D01*
X1010180Y167313D01*
X1009835Y166952D01*
X1009605Y166435D01*
X1009528Y165970D01*
X1011138D01*
G01X1012781Y166332D02*
X1013050Y166073D01*
X1013356Y165970D01*
X1013663Y166073D01*
X1013931Y166383D01*
X1014123Y166848D01*
X1014200Y167313D01*
Y167882D01*
X1014123Y168347D01*
X1013931Y168760D01*
X1013701Y168967D01*
X1013433Y169070D01*
X1013126Y168967D01*
X1012896Y168760D01*
X1012743Y168450D01*
X1012666Y168037D01*
X1012743Y167675D01*
X1012935Y167313D01*
X1013165Y167107D01*
X1013433Y167055D01*
X1013740Y167158D01*
X1013970Y167417D01*
X1014200Y167882D01*
G01X1016993Y165970D02*
Y169070D01*
X1015575Y166848D01*
X1017491D01*
G01X999499Y158585D02*
Y172561D01*
G01X991311D02*
Y158585D01*
G01D02*
X999499D01*
G01X1004099Y169743D02*
Y175943D01*
G01D02*
X1007299D01*
G01Y169743D02*
X1004099D01*
G01X991205Y184153D02*
Y177953D01*
G01X998315Y177473D02*
Y183673D01*
G01X1001515D02*
Y177473D01*
G01D02*
X998315D01*
G01X994815D02*
Y183673D01*
G01X998015D02*
Y177473D01*
G01D02*
X994815D01*
G01X999499Y172561D02*
X991311D01*
G01X998315Y183673D02*
X1001515D01*
G01X994815D02*
X998015D01*
G01X1003809Y182105D02*
Y185205D01*
X1004729D01*
X1005036Y185050D01*
X1005266Y184688D01*
X1005343Y184275D01*
X1005266Y183862D01*
X1005074Y183552D01*
X1004729Y183397D01*
X1003809D01*
G01X1006833Y185205D02*
Y182983D01*
X1006986Y182518D01*
X1007293Y182208D01*
X1007676Y182105D01*
X1008059Y182208D01*
X1008366Y182518D01*
X1008519Y182983D01*
Y185205D01*
G01X1010048Y184688D02*
X1010278Y184998D01*
X1010546Y185153D01*
X1010853Y185205D01*
X1011236Y185102D01*
X1011504Y184843D01*
X1011581Y184533D01*
X1011543Y184223D01*
X1011389Y183965D01*
X1010623Y183448D01*
X1010278Y183087D01*
X1010048Y182570D01*
X1009971Y182105D01*
X1011581D01*
G01X1013224Y182467D02*
X1013493Y182208D01*
X1013799Y182105D01*
X1014106Y182208D01*
X1014374Y182518D01*
X1014566Y182983D01*
X1014643Y183448D01*
Y184017D01*
X1014566Y184482D01*
X1014374Y184895D01*
X1014144Y185102D01*
X1013876Y185205D01*
X1013569Y185102D01*
X1013339Y184895D01*
X1013186Y184585D01*
X1013109Y184172D01*
X1013186Y183810D01*
X1013378Y183448D01*
X1013608Y183242D01*
X1013876Y183190D01*
X1014183Y183293D01*
X1014413Y183552D01*
X1014643Y184017D01*
G01X1016248Y184688D02*
X1016478Y184998D01*
X1016746Y185153D01*
X1017053Y185205D01*
X1017436Y185102D01*
X1017704Y184843D01*
X1017781Y184533D01*
X1017743Y184223D01*
X1017589Y183965D01*
X1016823Y183448D01*
X1016478Y183087D01*
X1016248Y182570D01*
X1016171Y182105D01*
X1017781D01*
G01X1004662Y187943D02*
X1004502Y187693D01*
X1004315Y187568D01*
X1004102Y187526D01*
X1003835Y187609D01*
X1003648Y187818D01*
X1003595Y188068D01*
X1003622Y188318D01*
X1003728Y188526D01*
X1004262Y188943D01*
X1004502Y189234D01*
X1004662Y189651D01*
X1004715Y190026D01*
X1003595D01*
G01X1001955D02*
Y187526D01*
X1002275Y188026D01*
G01Y190026D02*
X1001635D01*
G01X1000555Y190859D02*
X998955D01*
G01X998062Y187943D02*
X997902Y187693D01*
X997715Y187568D01*
X997502Y187526D01*
X997235Y187609D01*
X997048Y187818D01*
X996995Y188068D01*
X997022Y188318D01*
X997128Y188526D01*
X997662Y188943D01*
X997902Y189234D01*
X998062Y189651D01*
X998115Y190026D01*
X996995D01*
G01X995862Y187943D02*
X995702Y187693D01*
X995515Y187568D01*
X995302Y187526D01*
X995035Y187609D01*
X994848Y187818D01*
X994795Y188068D01*
X994822Y188318D01*
X994928Y188526D01*
X995462Y188943D01*
X995702Y189234D01*
X995862Y189651D01*
X995915Y190026D01*
X994795D01*
G01X993353Y192254D02*
X996494D01*
G01X1002416D02*
X1005557D01*
G01D02*
Y193427D01*
G01X993353Y193419D02*
Y192254D01*
G01X998505D02*
X1000405D01*
G01X992812Y222833D02*
X999012D01*
G01D02*
Y219633D01*
G01D02*
X992812D01*
G01D02*
Y222833D01*
G01X999012Y226833D02*
Y223633D01*
G01D02*
X992812D01*
G01D02*
Y226833D01*
G01X1002995Y223023D02*
Y216823D01*
G01D02*
X999795D01*
G01D02*
Y223023D01*
G01D02*
X1002995D01*
G01X1003795Y216823D02*
Y223023D01*
G01D02*
X1006995D01*
G01Y216823D02*
X1003795D01*
G01X999012Y215633D02*
X992812D01*
G01D02*
Y218833D01*
G01D02*
X999012D01*
G01D02*
Y215633D01*
G01X1006325Y226826D02*
Y224326D01*
X1006645Y224826D01*
G01Y226826D02*
X1006005D01*
G01X1004125Y224326D02*
X1004338Y224409D01*
X1004498Y224618D01*
X1004605Y224868D01*
X1004685Y225201D01*
X1004712Y225576D01*
X1004685Y225951D01*
X1004605Y226284D01*
X1004498Y226534D01*
X1004338Y226743D01*
X1004125Y226826D01*
X1003912Y226743D01*
X1003752Y226534D01*
X1003645Y226284D01*
X1003565Y225951D01*
X1003538Y225576D01*
X1003565Y225201D01*
X1003645Y224868D01*
X1003752Y224618D01*
X1003912Y224409D01*
X1004125Y224326D01*
G01X1005557Y211167D02*
Y212332D01*
G01D02*
X1002423D01*
G01X1000423D02*
X998487D01*
G01X996487D02*
X993353D01*
G01D02*
Y211167D01*
G01X992812Y226833D02*
X999012D01*
G01X997249Y251978D02*
X996942Y252030D01*
X996674Y252236D01*
X996444Y252546D01*
X996291Y252908D01*
X996214Y253321D01*
Y253735D01*
X996291Y254148D01*
X996444Y254510D01*
X996674Y254820D01*
X996942Y255026D01*
X997249Y255078D01*
X997556Y255026D01*
X997824Y254820D01*
X998054Y254510D01*
X998207Y254148D01*
X998284Y253735D01*
Y253321D01*
X998207Y252908D01*
X998054Y252546D01*
X997824Y252236D01*
X997556Y252030D01*
X997249Y251978D01*
G01X997556Y252805D02*
X998016Y251978D01*
G01X1000349D02*
Y255078D01*
X999889Y254458D01*
G01Y251978D02*
X1000809D01*
G01X1002721Y254561D02*
X1002951Y254871D01*
X1003219Y255026D01*
X1003526Y255078D01*
X1003909Y254975D01*
X1004177Y254716D01*
X1004254Y254406D01*
X1004216Y254096D01*
X1004062Y253838D01*
X1003296Y253321D01*
X1002951Y252960D01*
X1002721Y252443D01*
X1002644Y251978D01*
X1004254D01*
G01X1006472D02*
X1006549Y252650D01*
X1006664Y253218D01*
X1006817Y253735D01*
X1007009Y254303D01*
X1007316Y255078D01*
X1005782D01*
G01X1006676Y267112D02*
X996182D01*
G01D02*
Y275774D01*
G01Y265112D02*
X999529D01*
G01D02*
X1001429Y262912D01*
G01D02*
X1003329Y265112D01*
G01D02*
X1006676D01*
G01Y256450D02*
X996182D01*
G01D02*
Y265112D01*
G01X996979Y277010D02*
X996672Y277062D01*
X996404Y277268D01*
X996174Y277578D01*
X996021Y277940D01*
X995944Y278353D01*
Y278767D01*
X996021Y279180D01*
X996174Y279542D01*
X996404Y279852D01*
X996672Y280058D01*
X996979Y280110D01*
X997286Y280058D01*
X997554Y279852D01*
X997784Y279542D01*
X997937Y279180D01*
X998014Y278767D01*
Y278353D01*
X997937Y277940D01*
X997784Y277578D01*
X997554Y277268D01*
X997286Y277062D01*
X996979Y277010D01*
G01X997286Y277837D02*
X997746Y277010D01*
G01X1000079D02*
Y280110D01*
X999619Y279490D01*
G01Y277010D02*
X1000539D01*
G01X1002451Y279593D02*
X1002681Y279903D01*
X1002949Y280058D01*
X1003256Y280110D01*
X1003639Y280007D01*
X1003907Y279748D01*
X1003984Y279438D01*
X1003946Y279128D01*
X1003792Y278870D01*
X1003026Y278353D01*
X1002681Y277992D01*
X1002451Y277475D01*
X1002374Y277010D01*
X1003984D01*
G01X1005551Y278302D02*
X1005819Y278663D01*
X1006049Y278870D01*
X1006356Y278973D01*
X1006624Y278870D01*
X1006816Y278663D01*
X1006969Y278353D01*
X1007007Y277992D01*
X1006969Y277682D01*
X1006816Y277372D01*
X1006586Y277113D01*
X1006317Y277010D01*
X1006011Y277113D01*
X1005742Y277423D01*
X1005589Y277888D01*
X1005551Y278405D01*
X1005627Y279077D01*
X1005742Y279438D01*
X1005934Y279800D01*
X1006202Y280058D01*
X1006471Y280110D01*
X1006739Y280007D01*
X1006931Y279748D01*
G01X996182Y275774D02*
X999529D01*
G01D02*
X1001429Y273574D01*
G01D02*
X1003329Y275774D01*
G01D02*
X1006676D01*
G01X995936Y301742D02*
Y299520D01*
X996089Y299055D01*
X996396Y298745D01*
X996779Y298642D01*
X997162Y298745D01*
X997469Y299055D01*
X997622Y299520D01*
Y301742D01*
G01X999879Y298642D02*
Y301742D01*
X999419Y301122D01*
G01Y298642D02*
X1000339D01*
G01X1002136Y299262D02*
X1002366Y298900D01*
X1002672Y298694D01*
X1003017Y298642D01*
X1003324Y298694D01*
X1003631Y298952D01*
X1003822Y299262D01*
X1003861Y299572D01*
X1003784Y299934D01*
X1003516Y300192D01*
X1003247Y300295D01*
X1002902D01*
G01X1003247D02*
X1003477Y300450D01*
X1003669Y300709D01*
X1003746Y301019D01*
X1003669Y301329D01*
X1003477Y301587D01*
X1003132Y301742D01*
X1002787Y301690D01*
X1002442Y301484D01*
G01X1006539Y298642D02*
Y301742D01*
X1005121Y299520D01*
X1007037D01*
G01X1001429Y295075D02*
X999098Y297406D01*
G01D02*
X995989D01*
G01D02*
Y288744D01*
G01D02*
X1006869D01*
G01Y297406D02*
X1003760D01*
G01D02*
X1001429Y295075D01*
G01X1006060Y361936D02*
X1002860D01*
G01D02*
Y368136D01*
G01D02*
X1006060D01*
G01X1002060D02*
Y361936D01*
G01D02*
X998860D01*
G01D02*
Y368136D01*
G01D02*
X1002060D01*
G01X998060D02*
Y361936D01*
G01D02*
X994860D01*
G01D02*
Y368136D01*
G01D02*
X998060D01*
G01X994060D02*
Y361936D01*
G01X1005664Y382665D02*
Y385984D01*
G01D02*
X1001625Y390023D01*
G01D02*
X1005664Y394062D01*
G01D02*
Y397381D01*
G01X992059Y416903D02*
Y414681D01*
X992212Y414216D01*
X992519Y413906D01*
X992902Y413803D01*
X993285Y413906D01*
X993592Y414216D01*
X993745Y414681D01*
Y416903D01*
G01X995274Y416386D02*
X995504Y416696D01*
X995772Y416851D01*
X996079Y416903D01*
X996462Y416800D01*
X996730Y416541D01*
X996807Y416231D01*
X996769Y415921D01*
X996615Y415663D01*
X995849Y415146D01*
X995504Y414785D01*
X995274Y414268D01*
X995197Y413803D01*
X996807D01*
G01X999102D02*
Y416903D01*
X998642Y416283D01*
G01Y413803D02*
X999562D01*
G01X1002202D02*
X1002470Y413855D01*
X1002777Y414010D01*
X1002969Y414268D01*
X1003045Y414630D01*
X1002969Y414991D01*
X1002739Y415301D01*
X1002394Y415456D01*
X1002010D01*
X1001780Y415560D01*
X1001589Y415818D01*
X1001512Y416180D01*
X1001627Y416541D01*
X1001895Y416800D01*
X1002202Y416903D01*
X1002509Y416800D01*
X1002777Y416541D01*
X1002892Y416180D01*
X1002815Y415818D01*
X1002624Y415560D01*
X1002394Y415456D01*
X1002010D01*
X1001665Y415301D01*
X1001435Y414991D01*
X1001359Y414630D01*
X1001435Y414268D01*
X1001627Y414010D01*
X1001934Y413855D01*
X1002202Y413803D01*
G01X1004226Y418524D02*
Y430728D01*
G01X1011802Y431826D02*
X1005602D01*
G01D02*
Y435026D01*
G01X997402Y428126D02*
X994800Y430728D01*
G01X1004226D02*
X1000004D01*
G01D02*
X997402Y428126D01*
G01X1005602Y435026D02*
X1011802D01*
G01X999234Y444575D02*
Y447775D01*
G01X1005434Y444575D02*
X999234D01*
G01X1005434Y447775D02*
Y444575D01*
G01X999234Y447775D02*
X1005434D01*
G01X999234Y455575D02*
Y458775D01*
G01X1005434Y455575D02*
X999234D01*
G01X1005434Y458775D02*
Y455575D01*
G01X999234Y458775D02*
X1005434D01*
G01X999234Y450075D02*
Y453275D01*
G01X1005434Y450075D02*
X999234D01*
G01X1005434Y453275D02*
Y450075D01*
G01X999234Y453275D02*
X1005434D01*
G01X999234Y461075D02*
Y464275D01*
G01X1005434Y461075D02*
X999234D01*
G01X1005434Y464275D02*
Y461075D01*
G01X991284Y472075D02*
Y475275D01*
G01X997484Y472075D02*
X991284D01*
G01Y475275D02*
X997484D01*
G01D02*
Y472075D01*
G01X991284Y477575D02*
Y480775D01*
G01X997484Y477575D02*
X991284D01*
G01X997484Y480775D02*
Y477575D01*
G01X999234Y464275D02*
X1005434D01*
G01X999234Y466575D02*
Y469775D01*
G01X1005434Y466575D02*
X999234D01*
G01X1005434Y469775D02*
Y466575D01*
G01X999234Y469775D02*
X1005434D01*
G01X999234Y477575D02*
Y480775D01*
G01X1005434Y477575D02*
X999234D01*
G01X1005434Y480775D02*
Y477575D01*
G01X999234Y472075D02*
Y475275D01*
G01X1005434Y472075D02*
X999234D01*
G01X1005434Y475275D02*
Y472075D01*
G01X999234Y475275D02*
X1005434D01*
G01X991284Y480775D02*
X997484D01*
G01X999234Y492575D02*
Y495775D01*
G01X1005434Y492575D02*
X999234D01*
G01X1005434Y495775D02*
Y492575D01*
G01X999234Y488575D02*
Y491775D01*
G01X1005434Y488575D02*
X999234D01*
G01X1005434Y491775D02*
Y488575D01*
G01X999234Y491775D02*
X1005434D01*
G01X999234Y483075D02*
Y486275D01*
G01X1005434Y483075D02*
X999234D01*
G01X1005434Y486275D02*
Y483075D01*
G01X999234Y486275D02*
X1005434D01*
G01X999234Y480775D02*
X1005434D01*
G01X999234Y498075D02*
Y501275D01*
G01X1005434Y498075D02*
X999234D01*
G01X1005434Y501275D02*
Y498075D01*
G01X999234Y501275D02*
X1005434D01*
G01X999234Y495775D02*
X1005434D01*
G01X993156Y517614D02*
Y514414D01*
G01X1001156Y519414D02*
X994956D01*
G01D02*
Y522614D01*
G01D02*
X1001156D01*
G01D02*
Y519414D01*
G01Y514414D02*
X994956D01*
G01D02*
Y517614D01*
G01D02*
X1001156D01*
G01D02*
Y514414D01*
G01X993156Y522614D02*
Y519414D01*
G01Y527674D02*
Y524474D01*
G01X1001156D02*
X994956D01*
G01D02*
Y527674D01*
G01D02*
X1001156D01*
G01D02*
Y524474D01*
G01Y529474D02*
X994956D01*
G01D02*
Y532674D01*
G01D02*
X1001156D01*
G01D02*
Y529474D01*
G01X993156Y532674D02*
Y529474D01*
G01X1008611Y548549D02*
X1005411D01*
G01D02*
Y554749D01*
G01Y540399D02*
Y546599D01*
G01D02*
X1008611D01*
G01Y540399D02*
X1005411D01*
G01Y554749D02*
X1008611D01*
G01X999298Y1143379D02*
Y1146479D01*
G01X1000908D02*
Y1143379D01*
G01Y1144929D02*
X999298D01*
G01X1003203Y1143379D02*
Y1146479D01*
X1002743Y1145859D01*
G01Y1143379D02*
X1003663D01*
G01X1005575Y1145962D02*
X1005805Y1146272D01*
X1006073Y1146427D01*
X1006380Y1146479D01*
X1006763Y1146376D01*
X1007031Y1146117D01*
X1007108Y1145807D01*
X1007070Y1145497D01*
X1006916Y1145239D01*
X1006150Y1144722D01*
X1005805Y1144361D01*
X1005575Y1143844D01*
X1005498Y1143379D01*
X1007108D01*
G01X991944Y1165980D02*
X1001605Y1156319D01*
Y1156934D01*
X992483Y1166056D01*
Y1166112D01*
X993009D01*
X1001662Y1157459D01*
Y1157384D01*
X1001680Y1157402D01*
Y1158061D01*
X993666Y1166075D01*
X994220D01*
X1001691Y1158604D01*
X1001756D01*
Y1159205D01*
X995037Y1165924D01*
X994961D01*
X995036Y1165849D01*
X995655D01*
X1001624Y1159880D01*
Y1159562D01*
X1001718Y1159656D01*
Y1160519D01*
X996424Y1165813D01*
X996093D01*
X996111Y1165831D01*
X997012D01*
X1001817Y1161026D01*
Y1160876D01*
X1001799Y1160894D01*
Y1161702D01*
X997594Y1165907D01*
X997181D01*
X997256Y1165982D01*
X998063D01*
X1001686Y1162359D01*
Y1162171D01*
X1001705Y1162190D01*
Y1163072D01*
X998889Y1165888D01*
X998551D01*
X998663Y1166000D01*
X999321D01*
X1001667Y1163654D01*
Y1164405D01*
X1000109Y1165963D01*
X999715D01*
X999828Y1165850D01*
X1000672D01*
X1001648Y1164874D01*
Y1164855D01*
X1001573Y1164930D01*
Y1165550D01*
X1001235Y1165888D01*
X1001067D01*
X1001123Y1165944D01*
X1001554D01*
X1001742Y1165756D01*
G01X993666Y1166075D02*
Y1166054D01*
X1001659Y1158061D01*
X1001680D01*
G01X995655Y1165849D02*
X996388D01*
X1001718Y1160519D01*
Y1159974D01*
X1001624Y1159880D01*
X1000843Y1160661D01*
Y1161100D01*
X1000280Y1161663D01*
X1000093D01*
X996093Y1165663D01*
Y1165813D01*
X997546D01*
X1001799Y1161560D01*
Y1160894D01*
X1000913Y1161780D01*
Y1161808D01*
X996908Y1165813D01*
X996424D01*
G01X998889Y1165888D02*
Y1165194D01*
X1001705Y1162378D01*
X1001667D01*
X1001686Y1162359D01*
X1001705Y1162378D01*
Y1163072D01*
X998889Y1165888D01*
X998551D01*
X998626Y1165963D01*
X1000109D01*
X999996Y1165850D01*
X999828D01*
X1001273Y1164405D01*
X1001667D01*
Y1163654D01*
X1001554Y1163767D01*
G01X1002047Y1154409D02*
Y1166220D01*
G01X996500Y1236883D02*
X993400D01*
Y1237803D01*
X993555Y1238110D01*
X993917Y1238340D01*
X994330Y1238417D01*
X994743Y1238340D01*
X995053Y1238148D01*
X995208Y1237803D01*
Y1236883D01*
G01X993658Y1241593D02*
X993503Y1241363D01*
X993400Y1241095D01*
Y1240788D01*
X993555Y1240443D01*
X993813Y1240175D01*
X994123Y1239983D01*
X994640Y1239830D01*
X995105Y1239792D01*
X995570Y1239868D01*
X995880Y1239983D01*
X996190Y1240213D01*
X996397Y1240482D01*
X996500Y1240750D01*
Y1241018D01*
X996397Y1241287D01*
X996242Y1241517D01*
X996035Y1241708D01*
G01X995208Y1243122D02*
X994847Y1243390D01*
X994640Y1243620D01*
X994537Y1243927D01*
X994640Y1244195D01*
X994847Y1244387D01*
X995157Y1244540D01*
X995518Y1244578D01*
X995828Y1244540D01*
X996138Y1244387D01*
X996397Y1244157D01*
X996500Y1243888D01*
X996397Y1243582D01*
X996087Y1243313D01*
X995622Y1243160D01*
X995105Y1243122D01*
X994433Y1243198D01*
X994072Y1243313D01*
X993710Y1243505D01*
X993452Y1243773D01*
X993400Y1244042D01*
X993503Y1244310D01*
X993762Y1244502D01*
G01X996500Y1246950D02*
X996448Y1247218D01*
X996293Y1247525D01*
X996035Y1247717D01*
X995673Y1247793D01*
X995312Y1247717D01*
X995002Y1247487D01*
X994847Y1247142D01*
Y1246758D01*
X994743Y1246528D01*
X994485Y1246337D01*
X994123Y1246260D01*
X993762Y1246375D01*
X993503Y1246643D01*
X993400Y1246950D01*
X993503Y1247257D01*
X993762Y1247525D01*
X994123Y1247640D01*
X994485Y1247563D01*
X994743Y1247372D01*
X994847Y1247142D01*
Y1246758D01*
X995002Y1246413D01*
X995312Y1246183D01*
X995673Y1246107D01*
X996035Y1246183D01*
X996293Y1246375D01*
X996448Y1246682D01*
X996500Y1246950D01*
G01X993400Y1250050D02*
X993503Y1249743D01*
X993762Y1249513D01*
X994072Y1249360D01*
X994485Y1249245D01*
X994950Y1249207D01*
X995415Y1249245D01*
X995828Y1249360D01*
X996138Y1249513D01*
X996397Y1249743D01*
X996500Y1250050D01*
X996397Y1250357D01*
X996138Y1250587D01*
X995828Y1250740D01*
X995415Y1250855D01*
X994950Y1250893D01*
X994485Y1250855D01*
X994072Y1250740D01*
X993762Y1250587D01*
X993503Y1250357D01*
X993400Y1250050D01*
G01X996035Y1252307D02*
X996293Y1252537D01*
X996448Y1252805D01*
X996500Y1253150D01*
X996397Y1253495D01*
X996190Y1253763D01*
X995828Y1253955D01*
X995415Y1253993D01*
X995002Y1253917D01*
X994743Y1253725D01*
X994537Y1253457D01*
X994485Y1253188D01*
X994537Y1252920D01*
X994743Y1252575D01*
X993400Y1252690D01*
Y1253725D01*
G01X998545Y1454400D02*
Y1457500D01*
G01X1000155D02*
Y1454400D01*
G01Y1455950D02*
X998545D01*
G01X1002450Y1454400D02*
Y1457500D01*
X1001990Y1456880D01*
G01Y1454400D02*
X1002910D01*
G01X1005550D02*
Y1457500D01*
X1005090Y1456880D01*
G01Y1454400D02*
X1006010D01*
G01X1007922Y1456983D02*
X1008152Y1457293D01*
X1008420Y1457448D01*
X1008727Y1457500D01*
X1009110Y1457397D01*
X1009378Y1457138D01*
X1009455Y1456828D01*
X1009417Y1456518D01*
X1009263Y1456260D01*
X1008497Y1455743D01*
X1008152Y1455382D01*
X1007922Y1454865D01*
X1007845Y1454400D01*
X1009455D01*
G01X1004109Y1497095D02*
Y1500295D01*
G01X1010309Y1497095D02*
X1004109D01*
G01Y1500295D02*
X1010309D01*
G01X1000957Y1602206D02*
X1001337Y1602706D01*
X1001780Y1602956D01*
X1002287Y1603039D01*
X1002920Y1602872D01*
X1003363Y1602456D01*
X1003490Y1601956D01*
X1003427Y1601456D01*
X1003173Y1601039D01*
X1001907Y1600206D01*
X1001337Y1599622D01*
X1000957Y1598789D01*
X1000830Y1598039D01*
X1003490D01*
G01X1006437Y1599706D02*
X1008083D01*
G01X1010967Y1599039D02*
X1011347Y1598456D01*
X1011853Y1598122D01*
X1012423Y1598039D01*
X1012930Y1598122D01*
X1013437Y1598539D01*
X1013753Y1599039D01*
X1013817Y1599539D01*
X1013690Y1600122D01*
X1013247Y1600539D01*
X1012803Y1600706D01*
X1012233D01*
G01X1012803D02*
X1013183Y1600956D01*
X1013500Y1601372D01*
X1013627Y1601872D01*
X1013500Y1602372D01*
X1013183Y1602789D01*
X1012613Y1603039D01*
X1012043Y1602956D01*
X1011473Y1602622D01*
G01X1021167Y1598039D02*
Y1603039D01*
X1022433D01*
X1022940Y1602789D01*
X1023320Y1602456D01*
X1023637Y1601956D01*
X1023890Y1601372D01*
X1023953Y1600539D01*
X1023890Y1599706D01*
X1023637Y1599122D01*
X1023320Y1598622D01*
X1022940Y1598289D01*
X1022433Y1598039D01*
X1021167D01*
G01X1027660Y1601372D02*
Y1598039D01*
G01Y1602706D02*
X1027533Y1602789D01*
Y1602956D01*
X1027660Y1603039D01*
X1027787Y1602956D01*
Y1602789D01*
X1027660Y1602706D01*
G01X1031810Y1598622D02*
X1032127Y1598289D01*
X1032570Y1598039D01*
X1032950D01*
X1033330Y1598206D01*
X1033583Y1598456D01*
X1033710Y1598789D01*
X1033647Y1599289D01*
X1033393Y1599539D01*
X1032253Y1600039D01*
X1032000Y1600622D01*
X1032127Y1601039D01*
X1032380Y1601289D01*
X1032760Y1601372D01*
X1033140Y1601289D01*
X1033520Y1601039D01*
G01X1039000Y1598039D02*
Y1601372D01*
G01Y1600789D02*
X1038747Y1601122D01*
X1038367Y1601289D01*
X1037923Y1601372D01*
X1037480Y1601206D01*
X1037100Y1600872D01*
X1036847Y1600372D01*
X1036720Y1599706D01*
X1036847Y1599039D01*
X1037100Y1598539D01*
X1037480Y1598206D01*
X1037923Y1598039D01*
X1038367Y1598122D01*
X1038747Y1598372D01*
X1039000Y1598706D01*
G01X1041820Y1598039D02*
Y1603039D01*
G01Y1600539D02*
X1042137Y1601039D01*
X1042517Y1601289D01*
X1042897Y1601372D01*
X1043467Y1601206D01*
X1043847Y1600872D01*
X1044100Y1600289D01*
Y1599622D01*
X1043973Y1598956D01*
X1043720Y1598456D01*
X1043277Y1598122D01*
X1042897Y1598039D01*
X1042517Y1598122D01*
X1042137Y1598372D01*
X1041820Y1598789D01*
G01X1048060Y1598039D02*
Y1603039D01*
G01X1052210Y1600289D02*
X1054237D01*
X1054047Y1600872D01*
X1053730Y1601206D01*
X1053287Y1601372D01*
X1052843Y1601289D01*
X1052463Y1601039D01*
X1052210Y1600456D01*
X1052083Y1599956D01*
Y1599456D01*
X1052210Y1598956D01*
X1052527Y1598456D01*
X1052907Y1598122D01*
X1053350Y1598039D01*
X1053793Y1598206D01*
X1054237Y1598706D01*
G01X998764Y1620582D02*
Y1596082D01*
G01D02*
X1097264D01*
G01X1002160Y1605639D02*
Y1610639D01*
X1001400Y1609639D01*
G01Y1605639D02*
X1002920D01*
G01X1006437Y1607306D02*
X1008083D01*
G01X1011157Y1609806D02*
X1011537Y1610306D01*
X1011980Y1610556D01*
X1012487Y1610639D01*
X1013120Y1610472D01*
X1013563Y1610056D01*
X1013690Y1609556D01*
X1013627Y1609056D01*
X1013373Y1608639D01*
X1012107Y1607806D01*
X1011537Y1607222D01*
X1011157Y1606389D01*
X1011030Y1605639D01*
X1013690D01*
G01X1023827D02*
X1021293D01*
Y1610639D01*
X1023827D01*
G01X1022813Y1608222D02*
X1021293D01*
G01X1026583Y1605639D02*
Y1608972D01*
G01Y1608139D02*
X1026837Y1608556D01*
X1027217Y1608889D01*
X1027723Y1608972D01*
X1028167Y1608889D01*
X1028547Y1608556D01*
X1028737Y1607972D01*
Y1605639D01*
G01X1033900D02*
Y1608972D01*
G01Y1608389D02*
X1033647Y1608722D01*
X1033267Y1608889D01*
X1032823Y1608972D01*
X1032380Y1608806D01*
X1032000Y1608472D01*
X1031747Y1607972D01*
X1031620Y1607306D01*
X1031747Y1606639D01*
X1032000Y1606139D01*
X1032380Y1605806D01*
X1032823Y1605639D01*
X1033267Y1605722D01*
X1033647Y1605972D01*
X1033900Y1606306D01*
G01X1036720Y1605639D02*
Y1610639D01*
G01Y1608139D02*
X1037037Y1608639D01*
X1037417Y1608889D01*
X1037797Y1608972D01*
X1038367Y1608806D01*
X1038747Y1608472D01*
X1039000Y1607889D01*
Y1607222D01*
X1038873Y1606556D01*
X1038620Y1606056D01*
X1038177Y1605722D01*
X1037797Y1605639D01*
X1037417Y1605722D01*
X1037037Y1605972D01*
X1036720Y1606389D01*
G01X1042960Y1605639D02*
Y1610639D01*
G01X1047110Y1607889D02*
X1049137D01*
X1048947Y1608472D01*
X1048630Y1608806D01*
X1048187Y1608972D01*
X1047743Y1608889D01*
X1047363Y1608639D01*
X1047110Y1608056D01*
X1046983Y1607556D01*
Y1607056D01*
X1047110Y1606556D01*
X1047427Y1606056D01*
X1047807Y1605722D01*
X1048250Y1605639D01*
X1048693Y1605806D01*
X1049137Y1606306D01*
G01X1052843Y1603972D02*
X1052210Y1604806D01*
X1051893Y1605639D01*
Y1608972D01*
X1052210Y1609806D01*
X1052843Y1610639D01*
G01X1056867Y1605639D02*
Y1610639D01*
X1058133D01*
X1058640Y1610389D01*
X1059020Y1610056D01*
X1059337Y1609556D01*
X1059590Y1608972D01*
X1059653Y1608139D01*
X1059590Y1607306D01*
X1059337Y1606722D01*
X1059020Y1606222D01*
X1058640Y1605889D01*
X1058133Y1605639D01*
X1056867D01*
G01X1064627D02*
X1062093D01*
Y1610639D01*
X1064627D01*
G01X1063613Y1608222D02*
X1062093D01*
G01X1067257Y1605639D02*
Y1610639D01*
X1069663D01*
G01X1068777Y1608222D02*
X1067257D01*
G01X1071977Y1605639D02*
X1073560Y1610639D01*
X1075143Y1605639D01*
G01X1074573Y1607389D02*
X1072547D01*
G01X1077267Y1610639D02*
Y1607056D01*
X1077520Y1606306D01*
X1078027Y1605806D01*
X1078660Y1605639D01*
X1079293Y1605806D01*
X1079800Y1606306D01*
X1080053Y1607056D01*
Y1610639D01*
G01X1082493D02*
Y1605639D01*
X1085027D01*
G01X1088860Y1610639D02*
Y1605639D01*
G01X1087403Y1610639D02*
X1090317D01*
G01X1094277Y1603972D02*
X1094910Y1604806D01*
X1095227Y1605639D01*
Y1608972D01*
X1094910Y1609806D01*
X1094277Y1610639D01*
G01X1000830Y1613239D02*
Y1618239D01*
G01X1003490D02*
Y1613239D01*
G01Y1615739D02*
X1000830D01*
G01X1005930Y1613906D02*
X1006437Y1613489D01*
X1007007Y1613239D01*
X1007513D01*
X1008020Y1613489D01*
X1008400Y1613906D01*
X1008590Y1614489D01*
X1008463Y1615072D01*
X1008147Y1615572D01*
X1007577Y1615906D01*
X1006817Y1616072D01*
X1006373Y1616406D01*
X1006183Y1616989D01*
X1006310Y1617572D01*
X1006627Y1617989D01*
X1007070Y1618239D01*
X1007513D01*
X1007957Y1618072D01*
X1008337Y1617656D01*
G01X1013753Y1617822D02*
X1013373Y1618072D01*
X1012930Y1618239D01*
X1012423D01*
X1011853Y1617989D01*
X1011410Y1617572D01*
X1011093Y1617072D01*
X1010840Y1616239D01*
X1010777Y1615489D01*
X1010903Y1614739D01*
X1011093Y1614239D01*
X1011473Y1613739D01*
X1011917Y1613406D01*
X1012360Y1613239D01*
X1012803D01*
X1013247Y1613406D01*
X1013627Y1613656D01*
X1013943Y1613989D01*
G01X1023700Y1618239D02*
Y1613239D01*
G01Y1613989D02*
X1023447Y1613572D01*
X1023067Y1613322D01*
X1022623Y1613239D01*
X1022117Y1613406D01*
X1021737Y1613822D01*
X1021483Y1614322D01*
X1021420Y1614906D01*
X1021483Y1615489D01*
X1021737Y1615989D01*
X1022117Y1616406D01*
X1022623Y1616572D01*
X1023067Y1616489D01*
X1023383Y1616322D01*
X1023700Y1615989D01*
G01X1027660Y1616572D02*
Y1613239D01*
G01Y1617906D02*
X1027533Y1617989D01*
Y1618156D01*
X1027660Y1618239D01*
X1027787Y1618156D01*
Y1617989D01*
X1027660Y1617906D01*
G01X1031810Y1613822D02*
X1032127Y1613489D01*
X1032570Y1613239D01*
X1032950D01*
X1033330Y1613406D01*
X1033583Y1613656D01*
X1033710Y1613989D01*
X1033647Y1614489D01*
X1033393Y1614739D01*
X1032253Y1615239D01*
X1032000Y1615822D01*
X1032127Y1616239D01*
X1032380Y1616489D01*
X1032760Y1616572D01*
X1033140Y1616489D01*
X1033520Y1616239D01*
G01X1039000Y1613239D02*
Y1616572D01*
G01Y1615989D02*
X1038747Y1616322D01*
X1038367Y1616489D01*
X1037923Y1616572D01*
X1037480Y1616406D01*
X1037100Y1616072D01*
X1036847Y1615572D01*
X1036720Y1614906D01*
X1036847Y1614239D01*
X1037100Y1613739D01*
X1037480Y1613406D01*
X1037923Y1613239D01*
X1038367Y1613322D01*
X1038747Y1613572D01*
X1039000Y1613906D01*
G01X1041820Y1613239D02*
Y1618239D01*
G01Y1615739D02*
X1042137Y1616239D01*
X1042517Y1616489D01*
X1042897Y1616572D01*
X1043467Y1616406D01*
X1043847Y1616072D01*
X1044100Y1615489D01*
Y1614822D01*
X1043973Y1614156D01*
X1043720Y1613656D01*
X1043277Y1613322D01*
X1042897Y1613239D01*
X1042517Y1613322D01*
X1042137Y1613572D01*
X1041820Y1613989D01*
G01X1048060Y1613239D02*
Y1618239D01*
G01X1052210Y1615489D02*
X1054237D01*
X1054047Y1616072D01*
X1053730Y1616406D01*
X1053287Y1616572D01*
X1052843Y1616489D01*
X1052463Y1616239D01*
X1052210Y1615656D01*
X1052083Y1615156D01*
Y1614656D01*
X1052210Y1614156D01*
X1052527Y1613656D01*
X1052907Y1613322D01*
X1053350Y1613239D01*
X1053793Y1613406D01*
X1054237Y1613906D01*
G01X1097264Y1620582D02*
X998764D01*
G01X996314Y1643105D02*
Y1641305D01*
G01Y1650305D02*
Y1648505D01*
G01Y1643105D02*
X992314Y1648105D01*
G01X1000314D02*
X996314Y1643105D01*
G01X992314Y1648105D02*
X1000314D01*
G01X991314Y1643105D02*
X1001314D01*
G01X996214Y1665978D02*
Y1668218D01*
G01X994589Y1667005D02*
X997839D01*
G01X1021687Y142988D02*
Y145228D01*
G01X1020062Y144015D02*
X1023312D01*
G01X1017987Y166873D02*
Y147655D01*
G01D02*
X1025861D01*
G01X1008135Y156343D02*
Y162543D01*
G01D02*
X1011335D01*
G01D02*
Y156343D01*
G01D02*
X1008135D01*
G01X1007335Y162543D02*
Y156343D01*
G01X1008210Y155468D02*
X1014410D01*
G01D02*
Y152268D01*
G01D02*
X1008210D01*
G01D02*
Y155468D01*
G01X1023224Y155014D02*
X1020224D01*
G01D02*
X1021724Y158014D01*
G01X1020224D02*
X1023224D01*
G01X1014476Y173678D02*
X1008276D01*
G01D02*
Y176878D01*
G01D02*
X1014476D01*
G01D02*
Y173678D01*
G01X1007299Y175943D02*
Y169743D01*
G01X1014476Y169678D02*
X1008276D01*
G01D02*
Y172878D01*
G01D02*
X1014476D01*
G01D02*
Y169678D01*
G01X1021924Y167701D02*
Y170127D01*
G01X1025861Y166873D02*
X1017987D01*
G01X1018420Y192899D02*
X1012220D01*
G01D02*
Y196099D01*
G01X1018420D02*
Y192899D01*
G01X1012120Y200599D02*
X1018320D01*
G01D02*
Y197399D01*
G01D02*
X1012120D01*
G01D02*
Y200599D01*
G01X1012095Y209023D02*
X1018295D01*
G01D02*
Y205823D01*
G01D02*
X1012095D01*
G01D02*
Y209023D01*
G01X1012220Y196099D02*
X1018420D01*
G01X1012020Y204699D02*
X1018220D01*
G01D02*
Y201499D01*
G01D02*
X1012020D01*
G01D02*
Y204699D01*
G01X1010193Y210329D02*
X1010402Y210515D01*
X1010485Y210729D01*
X1010402Y210942D01*
X1010152Y211129D01*
X1009777Y211262D01*
X1009402Y211315D01*
X1008943D01*
X1008568Y211262D01*
X1008235Y211129D01*
X1008068Y210969D01*
X1007985Y210782D01*
X1008068Y210569D01*
X1008235Y210409D01*
X1008485Y210302D01*
X1008818Y210249D01*
X1009110Y210302D01*
X1009402Y210435D01*
X1009568Y210595D01*
X1009610Y210782D01*
X1009527Y210995D01*
X1009318Y211155D01*
X1008943Y211315D01*
G01X1012095Y216023D02*
X1018295D01*
G01D02*
Y212823D01*
G01D02*
X1012095D01*
G01D02*
Y216023D01*
G01X1018295Y228023D02*
Y224823D01*
G01D02*
X1012095D01*
G01D02*
Y228023D01*
G01Y224023D02*
X1018295D01*
G01D02*
Y220823D01*
G01D02*
X1012095D01*
G01D02*
Y224023D01*
G01Y220023D02*
X1018295D01*
G01D02*
Y216823D01*
G01D02*
X1012095D01*
G01D02*
Y220023D01*
G01X1006995Y223023D02*
Y216823D01*
G01X1012095Y228023D02*
X1018295D01*
G01Y228823D02*
X1012095D01*
Y232023D01*
X1018295D01*
Y228823D01*
G01X1015170Y228898D02*
Y235098D01*
X1018370D01*
Y228898D01*
X1015170D01*
G01X1013228Y269327D02*
Y275527D01*
G01X1016428D02*
Y269327D01*
G01D02*
X1013228D01*
G01Y260165D02*
Y266365D01*
G01D02*
X1016428D01*
G01D02*
Y260165D01*
G01D02*
X1013228D01*
G01X1006676Y275774D02*
Y267112D01*
G01Y265112D02*
Y256450D01*
G01X1013228Y275527D02*
X1016428D01*
G01X1013734Y289711D02*
Y295911D01*
G01D02*
X1016934D01*
G01D02*
Y289711D01*
G01D02*
X1013734D01*
G01Y288911D02*
X1019934D01*
G01D02*
Y285711D01*
G01D02*
X1013734D01*
G01D02*
Y288911D01*
G01X1019934Y299911D02*
Y296711D01*
G01D02*
X1013734D01*
G01D02*
Y299911D01*
G01X1006869Y288744D02*
Y297406D01*
G01X1013734Y299911D02*
X1019934D01*
G01X1006060Y368136D02*
Y361936D01*
G01X1026069Y377164D02*
X1019869D01*
G01D02*
Y380364D01*
G01D02*
X1026069D01*
G01Y382164D02*
X1019869D01*
G01D02*
Y385364D01*
G01D02*
X1026069D01*
G01Y387164D02*
X1019869D01*
G01D02*
Y390364D01*
G01X1007488Y382904D02*
X1009710D01*
X1010175Y383057D01*
X1010485Y383364D01*
X1010588Y383747D01*
X1010485Y384130D01*
X1010175Y384437D01*
X1009710Y384590D01*
X1007488D01*
G01X1010588Y386847D02*
X1007488D01*
X1008108Y386387D01*
G01X1010588D02*
Y387307D01*
G01X1010123Y389104D02*
X1010381Y389334D01*
X1010536Y389602D01*
X1010588Y389947D01*
X1010485Y390292D01*
X1010278Y390560D01*
X1009916Y390752D01*
X1009503Y390790D01*
X1009090Y390714D01*
X1008831Y390522D01*
X1008625Y390254D01*
X1008573Y389985D01*
X1008625Y389717D01*
X1008831Y389372D01*
X1007488Y389487D01*
Y390522D01*
G01Y393047D02*
X1007591Y392740D01*
X1007850Y392510D01*
X1008160Y392357D01*
X1008573Y392242D01*
X1009038Y392204D01*
X1009503Y392242D01*
X1009916Y392357D01*
X1010226Y392510D01*
X1010485Y392740D01*
X1010588Y393047D01*
X1010485Y393354D01*
X1010226Y393584D01*
X1009916Y393737D01*
X1009503Y393852D01*
X1009038Y393890D01*
X1008573Y393852D01*
X1008160Y393737D01*
X1007850Y393584D01*
X1007591Y393354D01*
X1007488Y393047D01*
G01X1011218Y403665D02*
Y397465D01*
G01D02*
X1008018D01*
G01D02*
Y403665D01*
G01D02*
X1011218D01*
G01X1019859Y399326D02*
X1026059D01*
G01Y396126D02*
X1019859D01*
G01D02*
Y399326D01*
G01X1019900Y403600D02*
X1026100D01*
G01X1019900Y400400D02*
Y403600D01*
G01X1026100Y400400D02*
X1019900D01*
G01X1026069Y392164D02*
X1019869D01*
G01D02*
Y395364D01*
G01D02*
X1026069D01*
G01X1019869Y390364D02*
X1026069D01*
G01X1011802Y435026D02*
Y431826D01*
G01X1012457Y422502D02*
X1018657D01*
G01D02*
Y419302D01*
G01D02*
X1012457D01*
G01D02*
Y422502D01*
G01X1018657Y424302D02*
X1012457D01*
G01D02*
Y427502D01*
G01D02*
X1018657D01*
G01D02*
Y424302D01*
G01X1009664Y461755D02*
X1015864D01*
G01D02*
Y458555D01*
G01X1009664D02*
Y461755D01*
G01X1015864Y458555D02*
X1009664D01*
G01X1015864Y457755D02*
Y454555D01*
G01X1009664Y457755D02*
X1015864D01*
G01X1009664Y454555D02*
Y457755D01*
G01X1015864Y454555D02*
X1009664D01*
G01X1015864Y453755D02*
Y450555D01*
G01X1009664Y453755D02*
X1015864D01*
G01X1009664Y450555D02*
Y453755D01*
G01X1015864Y450555D02*
X1009664D01*
G01X1015864Y465755D02*
Y462555D01*
G01X1009664D02*
Y465755D01*
G01X1015864Y462555D02*
X1009664D01*
G01Y465755D02*
X1015864D01*
G01Y469755D02*
Y466555D01*
G01X1009664Y469755D02*
X1015864D01*
G01X1009664Y466555D02*
Y469755D01*
G01X1015864Y466555D02*
X1009664D01*
G01Y477755D02*
X1015864D01*
G01D02*
Y474555D01*
G01X1009664D02*
Y477755D01*
G01X1015864Y474555D02*
X1009664D01*
G01X1015864Y473755D02*
Y470555D01*
G01X1009664Y473755D02*
X1015864D01*
G01X1009664Y470555D02*
Y473755D01*
G01X1015864Y470555D02*
X1009664D01*
G01X1015864Y495255D02*
Y492055D01*
G01X1009664D02*
Y495255D01*
G01X1015864Y492055D02*
X1009664D01*
G01X1015864Y490242D02*
Y487042D01*
G01X1009664Y490242D02*
X1015864D01*
G01X1009664Y487042D02*
Y490242D01*
G01X1015864Y487042D02*
X1009664D01*
G01X1015864Y481755D02*
Y478555D01*
G01X1009664Y481755D02*
X1015864D01*
G01X1009664Y478555D02*
Y481755D01*
G01X1015864Y478555D02*
X1009664D01*
G01Y482555D02*
Y485755D01*
G01X1015864Y482555D02*
X1009664D01*
G01X1015864Y485755D02*
Y482555D01*
G01X1009664Y485755D02*
X1015864D01*
G01X1009664Y495255D02*
X1015864D01*
G01X1015572Y511973D02*
Y509751D01*
X1015725Y509286D01*
X1016032Y508976D01*
X1016415Y508873D01*
X1016798Y508976D01*
X1017105Y509286D01*
X1017258Y509751D01*
Y511973D01*
G01X1018672Y509338D02*
X1018902Y509080D01*
X1019170Y508925D01*
X1019515Y508873D01*
X1019860Y508976D01*
X1020128Y509183D01*
X1020320Y509545D01*
X1020358Y509958D01*
X1020282Y510371D01*
X1020090Y510630D01*
X1019822Y510836D01*
X1019553Y510888D01*
X1019285Y510836D01*
X1018940Y510630D01*
X1019055Y511973D01*
X1020090D01*
G01X1021772Y509493D02*
X1022002Y509131D01*
X1022308Y508925D01*
X1022653Y508873D01*
X1022960Y508925D01*
X1023267Y509183D01*
X1023458Y509493D01*
X1023497Y509803D01*
X1023420Y510165D01*
X1023152Y510423D01*
X1022883Y510526D01*
X1022538D01*
G01X1022883D02*
X1023113Y510681D01*
X1023305Y510940D01*
X1023382Y511250D01*
X1023305Y511560D01*
X1023113Y511818D01*
X1022768Y511973D01*
X1022423Y511921D01*
X1022078Y511715D01*
G01X1007106Y511904D02*
X1013306D01*
G01D02*
Y508704D01*
G01D02*
X1007106D01*
G01D02*
Y511904D01*
G01X1019655Y517544D02*
X1023694Y513505D01*
G01X1012297Y533583D02*
Y513505D01*
G01D02*
X1015616D01*
G01D02*
X1019655Y517544D01*
G01X1021802Y536676D02*
X1018602D01*
G01D02*
Y542876D01*
G01X1027013Y533583D02*
X1012297D01*
G01X1018602Y542876D02*
X1021802D01*
G01X1008611Y554749D02*
Y548549D01*
G01Y546599D02*
Y540399D01*
G01X1016886Y548474D02*
X1010686D01*
G01D02*
Y551674D01*
G01D02*
X1016886D01*
G01D02*
Y548474D01*
G01Y543474D02*
X1010686D01*
G01D02*
Y546674D01*
G01D02*
X1016886D01*
G01D02*
Y543474D01*
G01X1017600Y562100D02*
Y558900D01*
G01X1011400Y562100D02*
X1017600D01*
G01Y558900D02*
X1011400D01*
G01D02*
Y562100D01*
G01X1019900Y567600D02*
X1026100D01*
G01Y564400D02*
X1019900D01*
G01D02*
Y567600D01*
G01X1018361Y555832D02*
Y562032D01*
G01D02*
X1021561D01*
G01Y555832D02*
X1018361D01*
G01X1012463Y1485967D02*
Y1489067D01*
X1013383D01*
X1013690Y1488912D01*
X1013920Y1488550D01*
X1013997Y1488137D01*
X1013920Y1487724D01*
X1013728Y1487414D01*
X1013383Y1487259D01*
X1012463D01*
G01X1015563Y1485967D02*
Y1489067D01*
X1016483D01*
X1016790Y1488912D01*
X1017020Y1488550D01*
X1017097Y1488137D01*
X1017020Y1487724D01*
X1016828Y1487414D01*
X1016483Y1487259D01*
X1015563D01*
G01X1019430Y1485967D02*
X1019123Y1486019D01*
X1018855Y1486225D01*
X1018625Y1486535D01*
X1018472Y1486897D01*
X1018395Y1487310D01*
Y1487724D01*
X1018472Y1488137D01*
X1018625Y1488499D01*
X1018855Y1488809D01*
X1019123Y1489015D01*
X1019430Y1489067D01*
X1019737Y1489015D01*
X1020005Y1488809D01*
X1020235Y1488499D01*
X1020388Y1488137D01*
X1020465Y1487724D01*
Y1487310D01*
X1020388Y1486897D01*
X1020235Y1486535D01*
X1020005Y1486225D01*
X1019737Y1486019D01*
X1019430Y1485967D01*
G01X1019737Y1486794D02*
X1020197Y1485967D01*
G01X1021802Y1487259D02*
X1022070Y1487620D01*
X1022300Y1487827D01*
X1022607Y1487930D01*
X1022875Y1487827D01*
X1023067Y1487620D01*
X1023220Y1487310D01*
X1023258Y1486949D01*
X1023220Y1486639D01*
X1023067Y1486329D01*
X1022837Y1486070D01*
X1022568Y1485967D01*
X1022262Y1486070D01*
X1021993Y1486380D01*
X1021840Y1486845D01*
X1021802Y1487362D01*
X1021878Y1488034D01*
X1021993Y1488395D01*
X1022185Y1488757D01*
X1022453Y1489015D01*
X1022722Y1489067D01*
X1022990Y1488964D01*
X1023182Y1488705D01*
G01X1010309Y1500295D02*
Y1497095D01*
G01X1008567Y1507588D02*
X1007634D01*
G01X1008567Y1526092D02*
Y1507588D01*
G01X1011067D02*
Y1526092D01*
G01X1011900Y1507588D02*
X1011067D01*
G01X1007934Y1526092D02*
X1008567D01*
G01X1011067D02*
X1011700D01*
G01X1006796Y1566540D02*
Y1535140D01*
G01X1010196D02*
Y1566540D01*
G01X1038396Y1535140D02*
X1010196D01*
G01Y1566540D02*
X1038396D01*
G01X1013545Y1569503D02*
X1010445D01*
Y1570423D01*
X1010600Y1570730D01*
X1010962Y1570960D01*
X1011375Y1571037D01*
X1011788Y1570960D01*
X1012098Y1570768D01*
X1012253Y1570423D01*
Y1569503D01*
G01X1013545Y1572603D02*
X1010445D01*
Y1573562D01*
X1010600Y1573868D01*
X1010807Y1574060D01*
X1011220Y1574137D01*
X1011633Y1574060D01*
X1011892Y1573830D01*
X1012047Y1573562D01*
Y1572603D01*
G01Y1573562D02*
X1013545Y1574137D01*
G01X1010962Y1575742D02*
X1010652Y1575972D01*
X1010497Y1576240D01*
X1010445Y1576547D01*
X1010548Y1576930D01*
X1010807Y1577198D01*
X1011117Y1577275D01*
X1011427Y1577237D01*
X1011685Y1577083D01*
X1012202Y1576317D01*
X1012563Y1575972D01*
X1013080Y1575742D01*
X1013545Y1575665D01*
Y1577275D01*
G01X1013080Y1578727D02*
X1013338Y1578957D01*
X1013493Y1579225D01*
X1013545Y1579570D01*
X1013442Y1579915D01*
X1013235Y1580183D01*
X1012873Y1580375D01*
X1012460Y1580413D01*
X1012047Y1580337D01*
X1011788Y1580145D01*
X1011582Y1579877D01*
X1011530Y1579608D01*
X1011582Y1579340D01*
X1011788Y1578995D01*
X1010445Y1579110D01*
Y1580145D01*
G01X1012925Y1581827D02*
X1013287Y1582057D01*
X1013493Y1582363D01*
X1013545Y1582708D01*
X1013493Y1583015D01*
X1013235Y1583322D01*
X1012925Y1583513D01*
X1012615Y1583552D01*
X1012253Y1583475D01*
X1011995Y1583207D01*
X1011892Y1582938D01*
Y1582593D01*
G01Y1582938D02*
X1011737Y1583168D01*
X1011478Y1583360D01*
X1011168Y1583437D01*
X1010858Y1583360D01*
X1010600Y1583168D01*
X1010445Y1582823D01*
X1010497Y1582478D01*
X1010703Y1582133D01*
G01X1013545Y1586230D02*
X1010445D01*
X1012667Y1584812D01*
Y1586728D01*
G01X1008558Y1624805D02*
Y1627274D01*
G01Y1627955D02*
Y1629242D01*
G01Y1628342D02*
Y1629542D01*
G01Y1629636D02*
Y1627229D01*
G01Y1664469D02*
Y1627429D01*
G01X1013419Y1653178D02*
X1010319D01*
Y1654098D01*
X1010474Y1654405D01*
X1010836Y1654635D01*
X1011249Y1654712D01*
X1011662Y1654635D01*
X1011972Y1654443D01*
X1012127Y1654098D01*
Y1653178D01*
G01X1013419Y1656202D02*
X1010319D01*
Y1656968D01*
X1010474Y1657275D01*
X1010681Y1657505D01*
X1010991Y1657697D01*
X1011352Y1657850D01*
X1011869Y1657888D01*
X1012386Y1657850D01*
X1012747Y1657697D01*
X1013057Y1657505D01*
X1013264Y1657275D01*
X1013419Y1656968D01*
Y1656202D01*
G01Y1660145D02*
X1010319D01*
X1010939Y1659685D01*
G01X1013419D02*
Y1660605D01*
G01X1012799Y1662402D02*
X1013161Y1662632D01*
X1013367Y1662938D01*
X1013419Y1663283D01*
X1013367Y1663590D01*
X1013109Y1663897D01*
X1012799Y1664088D01*
X1012489Y1664127D01*
X1012127Y1664050D01*
X1011869Y1663782D01*
X1011766Y1663513D01*
Y1663168D01*
G01Y1663513D02*
X1011611Y1663743D01*
X1011352Y1663935D01*
X1011042Y1664012D01*
X1010732Y1663935D01*
X1010474Y1663743D01*
X1010319Y1663398D01*
X1010371Y1663053D01*
X1010577Y1662708D01*
G01X1025872Y1682410D02*
X1006688D01*
G01X1026843Y109911D02*
Y113011D01*
G01X1028453D02*
Y109911D01*
G01Y111461D02*
X1026843D01*
G01X1030748Y109911D02*
X1031016Y109963D01*
X1031323Y110118D01*
X1031515Y110376D01*
X1031591Y110738D01*
X1031515Y111099D01*
X1031285Y111409D01*
X1030940Y111564D01*
X1030556D01*
X1030326Y111668D01*
X1030135Y111926D01*
X1030058Y112288D01*
X1030173Y112649D01*
X1030441Y112908D01*
X1030748Y113011D01*
X1031055Y112908D01*
X1031323Y112649D01*
X1031438Y112288D01*
X1031361Y111926D01*
X1031170Y111668D01*
X1030940Y111564D01*
X1030556D01*
X1030211Y111409D01*
X1029981Y111099D01*
X1029905Y110738D01*
X1029981Y110376D01*
X1030173Y110118D01*
X1030480Y109963D01*
X1030748Y109911D01*
G01X1033120Y111203D02*
X1033388Y111564D01*
X1033618Y111771D01*
X1033925Y111874D01*
X1034193Y111771D01*
X1034385Y111564D01*
X1034538Y111254D01*
X1034576Y110893D01*
X1034538Y110583D01*
X1034385Y110273D01*
X1034155Y110014D01*
X1033886Y109911D01*
X1033580Y110014D01*
X1033311Y110324D01*
X1033158Y110789D01*
X1033120Y111306D01*
X1033196Y111978D01*
X1033311Y112339D01*
X1033503Y112701D01*
X1033771Y112959D01*
X1034040Y113011D01*
X1034308Y112908D01*
X1034500Y112649D01*
G01X1030597Y146817D02*
X1027497D01*
Y147737D01*
X1027652Y148044D01*
X1028014Y148274D01*
X1028427Y148351D01*
X1028840Y148274D01*
X1029150Y148082D01*
X1029305Y147737D01*
Y146817D01*
G01X1030597Y149841D02*
X1027497D01*
Y150607D01*
X1027652Y150914D01*
X1027859Y151144D01*
X1028169Y151336D01*
X1028530Y151489D01*
X1029047Y151527D01*
X1029564Y151489D01*
X1029925Y151336D01*
X1030235Y151144D01*
X1030442Y150914D01*
X1030597Y150607D01*
Y149841D01*
G01Y153784D02*
X1027497D01*
X1028117Y153324D01*
G01X1030597D02*
Y154244D01*
G01Y156884D02*
X1027497D01*
X1028117Y156424D01*
G01X1030597D02*
Y157344D01*
G01Y160444D02*
X1027497D01*
X1029719Y159026D01*
Y160942D01*
G01X1025861Y147655D02*
Y166873D01*
G01X1021724Y155014D02*
Y153914D01*
G01Y158014D02*
X1023224Y155014D01*
G01X1021724Y158014D02*
Y159014D01*
G01X1021620Y184499D02*
Y190699D01*
G01D02*
X1024820D01*
G01D02*
Y184499D01*
G01D02*
X1021620D01*
G01X1089155Y204724D02*
G02I-31496J0D01*
G01X1026114Y230314D02*
Y233414D01*
G01X1027724D02*
Y230314D01*
G01Y231864D02*
X1026114D01*
G01X1030019Y230314D02*
Y233414D01*
X1029559Y232794D01*
G01Y230314D02*
X1030479D01*
G01X1033119D02*
Y233414D01*
X1032659Y232794D01*
G01Y230314D02*
X1033579D01*
G01X1036679D02*
Y233414D01*
X1035261Y231192D01*
X1037177D01*
G01X1032504Y285711D02*
X1026304D01*
G01D02*
Y288911D01*
G01D02*
X1032504D01*
G01D02*
Y285711D01*
G01Y296711D02*
X1026304D01*
G01D02*
Y299911D01*
G01X1032504D02*
Y296711D01*
G01X1026304Y299911D02*
X1032504D01*
G01X1026069Y380364D02*
Y377164D01*
G01Y385364D02*
Y382164D01*
G01Y390364D02*
Y387164D01*
G01X1026059Y399326D02*
Y396126D01*
G01X1026100Y403600D02*
Y400400D01*
G01X1026069Y395364D02*
Y392164D01*
G01X1032759Y484870D02*
Y453768D01*
G01D02*
X1047359D01*
G01X1030593Y491448D02*
Y489226D01*
X1030746Y488761D01*
X1031053Y488451D01*
X1031436Y488348D01*
X1031819Y488451D01*
X1032126Y488761D01*
X1032279Y489226D01*
Y491448D01*
G01X1033693Y488968D02*
X1033923Y488606D01*
X1034229Y488400D01*
X1034574Y488348D01*
X1034881Y488400D01*
X1035188Y488658D01*
X1035379Y488968D01*
X1035418Y489278D01*
X1035341Y489640D01*
X1035073Y489898D01*
X1034804Y490001D01*
X1034459D01*
G01X1034804D02*
X1035034Y490156D01*
X1035226Y490415D01*
X1035303Y490725D01*
X1035226Y491035D01*
X1035034Y491293D01*
X1034689Y491448D01*
X1034344Y491396D01*
X1033999Y491190D01*
G01X1036984Y488710D02*
X1037253Y488451D01*
X1037559Y488348D01*
X1037866Y488451D01*
X1038134Y488761D01*
X1038326Y489226D01*
X1038403Y489691D01*
Y490260D01*
X1038326Y490725D01*
X1038134Y491138D01*
X1037904Y491345D01*
X1037636Y491448D01*
X1037329Y491345D01*
X1037099Y491138D01*
X1036946Y490828D01*
X1036869Y490415D01*
X1036946Y490053D01*
X1037138Y489691D01*
X1037368Y489485D01*
X1037636Y489433D01*
X1037943Y489536D01*
X1038173Y489795D01*
X1038403Y490260D01*
G01X1040059Y479819D02*
X1035008Y484870D01*
G01D02*
X1032759D01*
G01X1023694Y513505D02*
X1027013D01*
G01D02*
Y533583D01*
G01X1023877Y537538D02*
Y535316D01*
X1024030Y534851D01*
X1024337Y534541D01*
X1024720Y534438D01*
X1025103Y534541D01*
X1025410Y534851D01*
X1025563Y535316D01*
Y537538D01*
G01X1026977Y534903D02*
X1027207Y534645D01*
X1027475Y534490D01*
X1027820Y534438D01*
X1028165Y534541D01*
X1028433Y534748D01*
X1028625Y535110D01*
X1028663Y535523D01*
X1028587Y535936D01*
X1028395Y536195D01*
X1028127Y536401D01*
X1027858Y536453D01*
X1027590Y536401D01*
X1027245Y536195D01*
X1027360Y537538D01*
X1028395D01*
G01X1031380Y534438D02*
Y537538D01*
X1029962Y535316D01*
X1031878D01*
G01X1036438Y536676D02*
X1033238D01*
G01D02*
Y542876D01*
G01X1021802D02*
Y536676D01*
G01X1032029Y541549D02*
Y551749D01*
G01D02*
X1023011D01*
G01D02*
Y541549D01*
G01D02*
X1032029D01*
G01X1033238Y542876D02*
X1036438D01*
G01X1026100Y567600D02*
Y564400D01*
G01X1033100D02*
X1026900D01*
G01D02*
Y567600D01*
G01D02*
X1033100D01*
G01D02*
Y564400D01*
G01X1021561Y562032D02*
Y555832D01*
G01X1023361D02*
Y562032D01*
G01D02*
X1026561D01*
G01D02*
Y555832D01*
G01D02*
X1023361D01*
G01X1028400Y562100D02*
X1031600D01*
G01X1028400Y555900D02*
Y562100D01*
G01X1031600Y555900D02*
X1028400D01*
G01X1031600Y562100D02*
Y555900D01*
G01X1033900Y562100D02*
X1037100D01*
G01X1033900Y555900D02*
Y562100D01*
G01X1037100Y555900D02*
X1033900D01*
G01X1030435Y1312649D02*
Y1309549D01*
G01X1029553Y1312649D02*
X1031317D01*
G01X1032768Y1309549D02*
Y1312649D01*
X1033688D01*
X1033995Y1312494D01*
X1034225Y1312132D01*
X1034302Y1311719D01*
X1034225Y1311306D01*
X1034033Y1310996D01*
X1033688Y1310841D01*
X1032768D01*
G01X1035907Y1312132D02*
X1036137Y1312442D01*
X1036405Y1312597D01*
X1036712Y1312649D01*
X1037095Y1312546D01*
X1037363Y1312287D01*
X1037440Y1311977D01*
X1037402Y1311667D01*
X1037248Y1311409D01*
X1036482Y1310892D01*
X1036137Y1310531D01*
X1035907Y1310014D01*
X1035830Y1309549D01*
X1037440D01*
G01X1030435Y1308649D02*
Y1305549D01*
G01X1029553Y1308649D02*
X1031317D01*
G01X1032768Y1305549D02*
Y1308649D01*
X1033688D01*
X1033995Y1308494D01*
X1034225Y1308132D01*
X1034302Y1307719D01*
X1034225Y1307306D01*
X1034033Y1306996D01*
X1033688Y1306841D01*
X1032768D01*
G01X1035792Y1306014D02*
X1036022Y1305756D01*
X1036290Y1305601D01*
X1036635Y1305549D01*
X1036980Y1305652D01*
X1037248Y1305859D01*
X1037440Y1306221D01*
X1037478Y1306634D01*
X1037402Y1307047D01*
X1037210Y1307306D01*
X1036942Y1307512D01*
X1036673Y1307564D01*
X1036405Y1307512D01*
X1036060Y1307306D01*
X1036175Y1308649D01*
X1037210D01*
G01X1027475Y1497095D02*
Y1500295D01*
G01X1033675Y1497095D02*
X1027475D01*
G01X1033675Y1500295D02*
Y1497095D01*
G01X1027475Y1500295D02*
X1033675D01*
G01X1031933Y1507588D02*
X1031000D01*
G01X1031933Y1526092D02*
Y1507588D01*
G01X1034433D02*
Y1526092D01*
G01X1035266Y1507588D02*
X1034433D01*
G01X1031300Y1526092D02*
X1031933D01*
G01X1034433D02*
X1035066D01*
G01X1034894Y1655146D02*
Y1661146D01*
X1046894D01*
Y1655146D01*
X1034894D01*
G01X1043938Y373503D02*
Y371281D01*
X1044091Y370816D01*
X1044398Y370506D01*
X1044781Y370403D01*
X1045164Y370506D01*
X1045471Y370816D01*
X1045624Y371281D01*
Y373503D01*
G01X1047881Y370403D02*
Y373503D01*
X1047421Y372883D01*
G01Y370403D02*
X1048341D01*
G01X1051441D02*
Y373503D01*
X1050023Y371281D01*
X1051939D01*
G01X1053429Y370765D02*
X1053698Y370506D01*
X1054004Y370403D01*
X1054311Y370506D01*
X1054579Y370816D01*
X1054771Y371281D01*
X1054848Y371746D01*
Y372315D01*
X1054771Y372780D01*
X1054579Y373193D01*
X1054349Y373400D01*
X1054081Y373503D01*
X1053774Y373400D01*
X1053544Y373193D01*
X1053391Y372883D01*
X1053314Y372470D01*
X1053391Y372108D01*
X1053583Y371746D01*
X1053813Y371540D01*
X1054081Y371488D01*
X1054388Y371591D01*
X1054618Y371850D01*
X1054848Y372315D01*
G01X1043711Y395003D02*
Y374925D01*
G01D02*
X1047030D01*
G01D02*
X1051069Y378964D01*
G01X1058427Y395003D02*
X1043711D01*
G01X1048345Y404986D02*
X1042145D01*
G01D02*
Y408186D01*
G01D02*
X1048345D01*
G01D02*
Y404986D01*
G01X1044091Y430700D02*
Y410622D01*
G01D02*
X1047410D01*
G01D02*
X1051449Y414661D01*
G01X1044318Y436526D02*
Y434304D01*
X1044471Y433839D01*
X1044778Y433529D01*
X1045161Y433426D01*
X1045544Y433529D01*
X1045851Y433839D01*
X1046004Y434304D01*
Y436526D01*
G01X1048261Y433426D02*
Y436526D01*
X1047801Y435906D01*
G01Y433426D02*
X1048721D01*
G01X1051821D02*
Y436526D01*
X1050403Y434304D01*
X1052319D01*
G01X1054461Y433426D02*
X1054729Y433478D01*
X1055036Y433633D01*
X1055228Y433891D01*
X1055304Y434253D01*
X1055228Y434614D01*
X1054998Y434924D01*
X1054653Y435079D01*
X1054269D01*
X1054039Y435183D01*
X1053848Y435441D01*
X1053771Y435803D01*
X1053886Y436164D01*
X1054154Y436423D01*
X1054461Y436526D01*
X1054768Y436423D01*
X1055036Y436164D01*
X1055151Y435803D01*
X1055074Y435441D01*
X1054883Y435183D01*
X1054653Y435079D01*
X1054269D01*
X1053924Y434924D01*
X1053694Y434614D01*
X1053618Y434253D01*
X1053694Y433891D01*
X1053886Y433633D01*
X1054193Y433478D01*
X1054461Y433426D01*
G01X1058807Y430700D02*
X1044091D01*
G01X1047359Y453768D02*
Y484870D01*
G01D02*
X1045110D01*
G01D02*
X1040059Y479819D01*
G01X1044354Y514414D02*
X1038154D01*
G01D02*
Y517614D01*
G01D02*
X1044354D01*
G01D02*
Y514414D01*
G01Y519474D02*
X1038154D01*
G01D02*
Y522674D01*
G01D02*
X1044354D01*
G01D02*
Y519474D01*
G01X1036438Y542876D02*
Y536676D01*
G01X1044354Y524474D02*
X1038154D01*
G01D02*
Y527674D01*
G01D02*
X1044354D01*
G01D02*
Y524474D01*
G01Y532474D02*
X1038154D01*
G01D02*
Y535674D01*
G01D02*
X1044354D01*
G01D02*
Y532474D01*
G01X1047100Y539600D02*
Y536400D01*
G01X1040900D02*
Y539600D01*
G01X1047100Y536400D02*
X1040900D01*
G01X1046354Y542974D02*
X1040154D01*
G01D02*
Y546174D01*
G01D02*
X1046354D01*
G01D02*
Y542974D01*
G01Y547974D02*
X1040154D01*
G01D02*
Y551174D01*
G01D02*
X1046354D01*
G01D02*
Y547974D01*
G01X1046431Y555241D02*
Y552041D01*
G01X1040231D02*
Y555241D01*
G01X1046431Y552041D02*
X1040231D01*
G01X1040900Y539600D02*
X1047100D01*
G01X1037400Y555900D02*
Y562100D01*
G01D02*
X1040600D01*
G01D02*
Y555900D01*
G01D02*
X1037400D01*
G01X1037100Y562100D02*
Y555900D01*
G01X1040231Y555241D02*
X1046431D01*
G01X1040741Y687244D02*
Y1325040D01*
G01X1066331Y687244D02*
X1040741D01*
G01X1066331Y720709D02*
X1040741D01*
G01X1066331Y1291575D02*
X1040741D01*
G01X1040445Y1322890D02*
X1037345D01*
Y1323810D01*
X1037500Y1324117D01*
X1037862Y1324347D01*
X1038275Y1324424D01*
X1038688Y1324347D01*
X1038998Y1324155D01*
X1039153Y1323810D01*
Y1322890D01*
G01X1037345Y1325990D02*
X1040445D01*
Y1327524D01*
G01Y1329857D02*
X1037345D01*
X1037965Y1329397D01*
G01X1040445D02*
Y1330317D01*
G01X1039153Y1332229D02*
X1038792Y1332497D01*
X1038585Y1332727D01*
X1038482Y1333034D01*
X1038585Y1333302D01*
X1038792Y1333494D01*
X1039102Y1333647D01*
X1039463Y1333685D01*
X1039773Y1333647D01*
X1040083Y1333494D01*
X1040342Y1333264D01*
X1040445Y1332995D01*
X1040342Y1332689D01*
X1040032Y1332420D01*
X1039567Y1332267D01*
X1039050Y1332229D01*
X1038378Y1332305D01*
X1038017Y1332420D01*
X1037655Y1332612D01*
X1037397Y1332880D01*
X1037345Y1333149D01*
X1037448Y1333417D01*
X1037707Y1333609D01*
G01X1041917Y1322712D02*
Y1348302D01*
G01X1045912Y1322712D02*
X1041917D01*
G01Y1348302D02*
X1045912D01*
G01X1046405Y1385050D02*
Y1388150D01*
G01X1048015D02*
Y1385050D01*
G01Y1386600D02*
X1046405D01*
G01X1049467Y1385515D02*
X1049697Y1385257D01*
X1049965Y1385102D01*
X1050310Y1385050D01*
X1050655Y1385153D01*
X1050923Y1385360D01*
X1051115Y1385722D01*
X1051153Y1386135D01*
X1051077Y1386548D01*
X1050885Y1386807D01*
X1050617Y1387013D01*
X1050348Y1387065D01*
X1050080Y1387013D01*
X1049735Y1386807D01*
X1049850Y1388150D01*
X1050885D01*
G01X1053410D02*
X1053103Y1388047D01*
X1052873Y1387788D01*
X1052720Y1387478D01*
X1052605Y1387065D01*
X1052567Y1386600D01*
X1052605Y1386135D01*
X1052720Y1385722D01*
X1052873Y1385412D01*
X1053103Y1385153D01*
X1053410Y1385050D01*
X1053717Y1385153D01*
X1053947Y1385412D01*
X1054100Y1385722D01*
X1054215Y1386135D01*
X1054253Y1386600D01*
X1054215Y1387065D01*
X1054100Y1387478D01*
X1053947Y1387788D01*
X1053717Y1388047D01*
X1053410Y1388150D01*
G01X1036743Y1485511D02*
Y1488611D01*
X1037663D01*
X1037970Y1488456D01*
X1038200Y1488094D01*
X1038277Y1487681D01*
X1038200Y1487268D01*
X1038008Y1486958D01*
X1037663Y1486803D01*
X1036743D01*
G01X1039843Y1485511D02*
Y1488611D01*
X1040763D01*
X1041070Y1488456D01*
X1041300Y1488094D01*
X1041377Y1487681D01*
X1041300Y1487268D01*
X1041108Y1486958D01*
X1040763Y1486803D01*
X1039843D01*
G01X1043710Y1485511D02*
X1043403Y1485563D01*
X1043135Y1485769D01*
X1042905Y1486079D01*
X1042752Y1486441D01*
X1042675Y1486854D01*
Y1487268D01*
X1042752Y1487681D01*
X1042905Y1488043D01*
X1043135Y1488353D01*
X1043403Y1488559D01*
X1043710Y1488611D01*
X1044017Y1488559D01*
X1044285Y1488353D01*
X1044515Y1488043D01*
X1044668Y1487681D01*
X1044745Y1487268D01*
Y1486854D01*
X1044668Y1486441D01*
X1044515Y1486079D01*
X1044285Y1485769D01*
X1044017Y1485563D01*
X1043710Y1485511D01*
G01X1044017Y1486338D02*
X1044477Y1485511D01*
G01X1046733D02*
X1046810Y1486183D01*
X1046925Y1486751D01*
X1047078Y1487268D01*
X1047270Y1487836D01*
X1047577Y1488611D01*
X1046043D01*
G01X1038396Y1566540D02*
Y1535140D01*
G01X1041796D02*
Y1566540D01*
G01X1069996Y1535140D02*
X1041796D01*
G01Y1566540D02*
X1069996D01*
G01X1045565Y1569233D02*
X1042465D01*
Y1570153D01*
X1042620Y1570460D01*
X1042982Y1570690D01*
X1043395Y1570767D01*
X1043808Y1570690D01*
X1044118Y1570498D01*
X1044273Y1570153D01*
Y1569233D01*
G01X1045565Y1572333D02*
X1042465D01*
Y1573292D01*
X1042620Y1573598D01*
X1042827Y1573790D01*
X1043240Y1573867D01*
X1043653Y1573790D01*
X1043912Y1573560D01*
X1044067Y1573292D01*
Y1572333D01*
G01Y1573292D02*
X1045565Y1573867D01*
G01X1042982Y1575472D02*
X1042672Y1575702D01*
X1042517Y1575970D01*
X1042465Y1576277D01*
X1042568Y1576660D01*
X1042827Y1576928D01*
X1043137Y1577005D01*
X1043447Y1576967D01*
X1043705Y1576813D01*
X1044222Y1576047D01*
X1044583Y1575702D01*
X1045100Y1575472D01*
X1045565Y1575395D01*
Y1577005D01*
G01X1045100Y1578457D02*
X1045358Y1578687D01*
X1045513Y1578955D01*
X1045565Y1579300D01*
X1045462Y1579645D01*
X1045255Y1579913D01*
X1044893Y1580105D01*
X1044480Y1580143D01*
X1044067Y1580067D01*
X1043808Y1579875D01*
X1043602Y1579607D01*
X1043550Y1579338D01*
X1043602Y1579070D01*
X1043808Y1578725D01*
X1042465Y1578840D01*
Y1579875D01*
G01X1044945Y1581557D02*
X1045307Y1581787D01*
X1045513Y1582093D01*
X1045565Y1582438D01*
X1045513Y1582745D01*
X1045255Y1583052D01*
X1044945Y1583243D01*
X1044635Y1583282D01*
X1044273Y1583205D01*
X1044015Y1582937D01*
X1043912Y1582668D01*
Y1582323D01*
G01Y1582668D02*
X1043757Y1582898D01*
X1043498Y1583090D01*
X1043188Y1583167D01*
X1042878Y1583090D01*
X1042620Y1582898D01*
X1042465Y1582553D01*
X1042517Y1582208D01*
X1042723Y1581863D01*
G01X1042982Y1584772D02*
X1042672Y1585002D01*
X1042517Y1585270D01*
X1042465Y1585577D01*
X1042568Y1585960D01*
X1042827Y1586228D01*
X1043137Y1586305D01*
X1043447Y1586267D01*
X1043705Y1586113D01*
X1044222Y1585347D01*
X1044583Y1585002D01*
X1045100Y1584772D01*
X1045565Y1584695D01*
Y1586305D01*
G01X1049466Y1640892D02*
Y1638670D01*
X1049619Y1638205D01*
X1049926Y1637895D01*
X1050309Y1637792D01*
X1050692Y1637895D01*
X1050999Y1638205D01*
X1051152Y1638670D01*
Y1640892D01*
G01X1052681Y1640375D02*
X1052911Y1640685D01*
X1053179Y1640840D01*
X1053486Y1640892D01*
X1053869Y1640789D01*
X1054137Y1640530D01*
X1054214Y1640220D01*
X1054176Y1639910D01*
X1054022Y1639652D01*
X1053256Y1639135D01*
X1052911Y1638774D01*
X1052681Y1638257D01*
X1052604Y1637792D01*
X1054214D01*
G01X1055857Y1638154D02*
X1056126Y1637895D01*
X1056432Y1637792D01*
X1056739Y1637895D01*
X1057007Y1638205D01*
X1057199Y1638670D01*
X1057276Y1639135D01*
Y1639704D01*
X1057199Y1640169D01*
X1057007Y1640582D01*
X1056777Y1640789D01*
X1056509Y1640892D01*
X1056202Y1640789D01*
X1055972Y1640582D01*
X1055819Y1640272D01*
X1055742Y1639859D01*
X1055819Y1639497D01*
X1056011Y1639135D01*
X1056241Y1638929D01*
X1056509Y1638877D01*
X1056816Y1638980D01*
X1057046Y1639239D01*
X1057276Y1639704D01*
G01X1059609Y1640892D02*
X1059302Y1640789D01*
X1059072Y1640530D01*
X1058919Y1640220D01*
X1058804Y1639807D01*
X1058766Y1639342D01*
X1058804Y1638877D01*
X1058919Y1638464D01*
X1059072Y1638154D01*
X1059302Y1637895D01*
X1059609Y1637792D01*
X1059916Y1637895D01*
X1060146Y1638154D01*
X1060299Y1638464D01*
X1060414Y1638877D01*
X1060452Y1639342D01*
X1060414Y1639807D01*
X1060299Y1640220D01*
X1060146Y1640530D01*
X1059916Y1640789D01*
X1059609Y1640892D01*
G01X1047202Y1644605D02*
X1041002D01*
G01X1047202Y1647805D02*
Y1644605D01*
G01X1041002Y1647805D02*
X1047202D01*
G01X1041002Y1644605D02*
Y1647805D01*
G01X1040870Y1650482D02*
Y1653682D01*
G01X1047070Y1650482D02*
X1040870D01*
G01Y1653682D02*
X1047070D01*
G01D02*
Y1650482D01*
G01X1048700Y1645847D02*
Y1658471D01*
G01X1060512Y1645847D02*
X1048700D01*
G01X1051704Y1666984D02*
Y1660784D01*
X1048504D01*
Y1666984D01*
X1051704D01*
G01X1048700Y1658471D02*
X1060512D01*
G01X1074272Y1682410D02*
X1041688D01*
G01X1051069Y378964D02*
X1055108Y374925D01*
G01D02*
X1058427D01*
G01D02*
Y395003D01*
G01X1053417Y408160D02*
X1059617D01*
G01D02*
Y404960D01*
G01D02*
X1053417D01*
G01D02*
Y408160D01*
G01X1051449Y414661D02*
X1055488Y410622D01*
G01D02*
X1058807D01*
G01D02*
Y430700D01*
G01X1064164Y448055D02*
Y451255D01*
G01X1070364Y448055D02*
X1064164D01*
G01X1064146Y447099D02*
X1070346D01*
G01X1064146Y443899D02*
Y447099D01*
G01X1070346Y443899D02*
X1064146D01*
G01X1064196Y459559D02*
X1070396D01*
G01X1064196Y456359D02*
Y459559D01*
G01X1070396Y456359D02*
X1064196D01*
G01X1064164Y452055D02*
Y455255D01*
G01X1070364Y452055D02*
X1064164D01*
G01Y455255D02*
X1070364D01*
G01X1064164Y451255D02*
X1070364D01*
G01X1070394Y460925D02*
X1064194D01*
G01D02*
Y464125D01*
G01X1064164Y478055D02*
Y481255D01*
G01X1070364Y478055D02*
X1064164D01*
G01X1064194Y477125D02*
X1070394D01*
G01X1064194Y473925D02*
Y477125D01*
G01X1070394Y473925D02*
X1064194D01*
G01Y464125D02*
X1070394D01*
G01X1064194Y465400D02*
Y468600D01*
G01X1070394Y465400D02*
X1064194D01*
G01Y468600D02*
X1070394D01*
G01X1064194Y469900D02*
Y473100D01*
G01X1070394Y469900D02*
X1064194D01*
G01Y473100D02*
X1070394D01*
G01X1060580Y491637D02*
Y488437D01*
G01X1054380D02*
Y491637D01*
G01X1060580Y488437D02*
X1054380D01*
G01Y491637D02*
X1060580D01*
G01X1064164Y485255D02*
X1070364D01*
G01X1064164Y482055D02*
Y485255D01*
G01X1070364Y482055D02*
X1064164D01*
G01Y489255D02*
X1070364D01*
G01X1064164Y486055D02*
Y489255D01*
G01X1070364Y486055D02*
X1064164D01*
G01Y481255D02*
X1070364D01*
G01X1058369Y682595D02*
X1058561Y682285D01*
X1058791Y682078D01*
X1059059Y681975D01*
X1059366Y682078D01*
X1059596Y682285D01*
X1059826Y682595D01*
X1059903Y683008D01*
Y685075D01*
G01X1061508Y684558D02*
X1061738Y684868D01*
X1062006Y685023D01*
X1062313Y685075D01*
X1062696Y684972D01*
X1062964Y684713D01*
X1063041Y684403D01*
X1063003Y684093D01*
X1062849Y683835D01*
X1062083Y683318D01*
X1061738Y682957D01*
X1061508Y682440D01*
X1061431Y681975D01*
X1063041D01*
G01X1064493Y682595D02*
X1064723Y682233D01*
X1065029Y682027D01*
X1065374Y681975D01*
X1065681Y682027D01*
X1065988Y682285D01*
X1066179Y682595D01*
X1066218Y682905D01*
X1066141Y683267D01*
X1065873Y683525D01*
X1065604Y683628D01*
X1065259D01*
G01X1065604D02*
X1065834Y683783D01*
X1066026Y684042D01*
X1066103Y684352D01*
X1066026Y684662D01*
X1065834Y684920D01*
X1065489Y685075D01*
X1065144Y685023D01*
X1064799Y684817D01*
G01X1066515Y1306388D02*
X1063315D01*
G01Y1312588D02*
X1066515D01*
G01X1063315Y1306388D02*
Y1312588D01*
G01X1056046Y1309603D02*
Y1312803D01*
G01X1062246Y1309603D02*
X1056046D01*
G01X1062246Y1312803D02*
Y1309603D01*
G01X1056046Y1312803D02*
X1062246D01*
G01X1056046Y1305603D02*
Y1308803D01*
G01X1062246Y1305603D02*
X1056046D01*
G01X1062246Y1308803D02*
Y1305603D01*
G01X1056046Y1308803D02*
X1062246D01*
G01X1067507Y1322712D02*
X1063512D01*
G01Y1348302D02*
X1067507D01*
G01X1067963Y1380950D02*
X1064763D01*
G01Y1387150D02*
X1067963D01*
G01X1064763Y1380950D02*
Y1387150D01*
G01X1064005Y1380918D02*
X1060805D01*
G01X1064005Y1387118D02*
Y1380918D01*
G01X1060805Y1387118D02*
X1064005D01*
G01X1060805Y1380918D02*
Y1387118D01*
G01X1065020Y1408196D02*
X1065250Y1407834D01*
X1065556Y1407628D01*
X1065901Y1407576D01*
X1066208Y1407628D01*
X1066515Y1407886D01*
X1066706Y1408196D01*
X1066745Y1408506D01*
X1066668Y1408868D01*
X1066400Y1409126D01*
X1066131Y1409229D01*
X1065786D01*
G01X1066131D02*
X1066361Y1409384D01*
X1066553Y1409643D01*
X1066630Y1409953D01*
X1066553Y1410263D01*
X1066361Y1410521D01*
X1066016Y1410676D01*
X1065671Y1410624D01*
X1065326Y1410418D01*
G01X1060233Y1485825D02*
Y1488925D01*
X1061153D01*
X1061460Y1488770D01*
X1061690Y1488408D01*
X1061767Y1487995D01*
X1061690Y1487582D01*
X1061498Y1487272D01*
X1061153Y1487117D01*
X1060233D01*
G01X1063333Y1485825D02*
Y1488925D01*
X1064253D01*
X1064560Y1488770D01*
X1064790Y1488408D01*
X1064867Y1487995D01*
X1064790Y1487582D01*
X1064598Y1487272D01*
X1064253Y1487117D01*
X1063333D01*
G01X1067200Y1485825D02*
X1066893Y1485877D01*
X1066625Y1486083D01*
X1066395Y1486393D01*
X1066242Y1486755D01*
X1066165Y1487168D01*
Y1487582D01*
X1066242Y1487995D01*
X1066395Y1488357D01*
X1066625Y1488667D01*
X1066893Y1488873D01*
X1067200Y1488925D01*
X1067507Y1488873D01*
X1067775Y1488667D01*
X1068005Y1488357D01*
X1068158Y1487995D01*
X1068235Y1487582D01*
Y1487168D01*
X1068158Y1486755D01*
X1068005Y1486393D01*
X1067775Y1486083D01*
X1067507Y1485877D01*
X1067200Y1485825D01*
G01X1067507Y1486652D02*
X1067967Y1485825D01*
G01X1070300D02*
X1070568Y1485877D01*
X1070875Y1486032D01*
X1071067Y1486290D01*
X1071143Y1486652D01*
X1071067Y1487013D01*
X1070837Y1487323D01*
X1070492Y1487478D01*
X1070108D01*
X1069878Y1487582D01*
X1069687Y1487840D01*
X1069610Y1488202D01*
X1069725Y1488563D01*
X1069993Y1488822D01*
X1070300Y1488925D01*
X1070607Y1488822D01*
X1070875Y1488563D01*
X1070990Y1488202D01*
X1070913Y1487840D01*
X1070722Y1487582D01*
X1070492Y1487478D01*
X1070108D01*
X1069763Y1487323D01*
X1069533Y1487013D01*
X1069457Y1486652D01*
X1069533Y1486290D01*
X1069725Y1486032D01*
X1070032Y1485877D01*
X1070300Y1485825D01*
G01X1050841Y1497095D02*
Y1500295D01*
G01X1057041Y1497095D02*
X1050841D01*
G01X1057041Y1500295D02*
Y1497095D01*
G01X1050841Y1500295D02*
X1057041D01*
G01X1057799Y1507588D02*
Y1526092D01*
G01X1058632Y1507588D02*
X1057799D01*
G01X1055299D02*
X1054366D01*
G01X1055299Y1526092D02*
Y1507588D01*
G01X1057799Y1526092D02*
X1058432D01*
G01X1054666D02*
X1055299D01*
G01X1065821Y1655320D02*
X1062621D01*
G01D02*
Y1661520D01*
G01X1065351Y1646394D02*
X1062151D01*
G01X1065351Y1652594D02*
Y1646394D01*
G01X1062151Y1652594D02*
X1065351D01*
G01X1062151Y1646394D02*
Y1652594D01*
G01X1060512Y1658471D02*
Y1645847D01*
G01X1062621Y1661520D02*
X1065821D01*
G01X1149262Y118905D02*
G02X1066535Y119432I-41270J14961D01*
G01X1066614Y118068D02*
G03X1149537Y118512I41378J15798D01*
G01X1066535Y119432D02*
Y148300D01*
G01X1066614Y119204D02*
Y118068D01*
G01X1066535Y148300D02*
G02X1149262Y148827I41457J-14434D01*
G01X1149537Y149220D02*
G03X1066614Y149664I-41545J-15354D01*
G01D02*
Y148528D01*
G01X1073181Y368192D02*
X1066981D01*
G01D02*
Y371392D01*
G01D02*
X1073181D01*
G01D02*
Y368192D01*
G01X1086335Y385626D02*
X1080135D01*
G01D02*
Y388826D01*
G01D02*
X1086335D01*
G01X1080135Y380826D02*
X1086335D01*
G01X1080135Y377626D02*
Y380826D01*
G01X1086335Y377626D02*
X1080135D01*
G01X1086335Y381626D02*
X1080135D01*
G01Y384826D02*
X1086335D01*
G01X1080135Y381626D02*
Y384826D01*
G01X1070836Y398557D02*
Y392357D01*
G01D02*
X1067636D01*
G01D02*
Y398557D01*
G01D02*
X1070836D01*
G01X1067722Y399448D02*
Y405648D01*
G01X1070922D02*
Y399448D01*
G01D02*
X1067722D01*
G01X1086335Y389626D02*
X1080135D01*
G01D02*
Y392826D01*
G01D02*
X1086335D01*
G01X1067722Y405648D02*
X1070922D01*
G01X1077126Y429064D02*
Y422864D01*
G01D02*
X1073926D01*
G01D02*
Y429064D01*
G01D02*
X1077126D01*
G01X1070364Y451255D02*
Y448055D01*
G01X1070346Y447099D02*
Y443899D01*
G01X1070396Y459559D02*
Y456359D01*
G01X1070364Y455255D02*
Y452055D01*
G01X1070394Y464125D02*
Y460925D01*
G01X1073110Y459559D02*
X1079310D01*
G01D02*
Y456359D01*
G01D02*
X1073110D01*
G01D02*
Y459559D01*
G01X1070364Y481255D02*
Y478055D01*
G01X1070394Y477125D02*
Y473925D01*
G01Y468600D02*
Y465400D01*
G01X1079394Y473100D02*
Y469900D01*
G01X1073194Y473100D02*
X1079394D01*
G01X1073194Y469900D02*
Y473100D01*
G01X1079394Y469900D02*
X1073194D01*
G01X1070394Y473100D02*
Y469900D01*
G01X1079394Y465400D02*
X1073194D01*
Y468600D01*
X1079394D01*
Y465400D01*
G01X1073110Y485382D02*
X1079310D01*
G01D02*
Y482182D01*
G01X1073110D02*
Y485382D01*
G01X1079310Y482182D02*
X1073110D01*
G01X1079310Y489382D02*
Y486182D01*
G01X1073110Y489382D02*
X1079310D01*
G01X1073110Y486182D02*
Y489382D01*
G01X1079310Y486182D02*
X1073110D01*
G01X1070364Y485255D02*
Y482055D01*
G01Y489255D02*
Y486055D01*
G01X1116976Y605378D02*
G02I-22900J0D01*
G01X1070442Y687244D02*
Y1303900D01*
G01X1096032Y687244D02*
X1070442D01*
G01X1066331Y1304730D02*
Y687244D01*
G01X1096032Y720709D02*
X1070442D01*
G01X1096032Y1291575D02*
X1070442D01*
G01X1066515Y1312588D02*
Y1306388D01*
G01X1070039Y1306689D02*
Y1349997D01*
G01X1075380Y1306689D02*
X1070039D01*
G01X1067507Y1348302D02*
Y1322712D01*
G01X1066331Y1321020D02*
Y1313920D01*
G01X1072896Y1354797D02*
Y1351597D01*
G01X1066696Y1354797D02*
X1072896D01*
G01X1066696Y1351597D02*
Y1354797D01*
G01X1072896Y1351597D02*
X1066696D01*
G01X1071462Y1361297D02*
Y1355097D01*
G01D02*
X1068262D01*
G01D02*
Y1361297D01*
G01X1074496Y1353214D02*
Y1355814D01*
G01X1075289Y1353214D02*
X1074496D01*
G01X1070039Y1349997D02*
X1075380D01*
G01X1071439Y1372418D02*
X1068239D01*
G01D02*
Y1378618D01*
G01X1071439Y1374500D02*
Y1372418D01*
G01Y1368118D02*
Y1361918D01*
G01X1068239Y1368118D02*
X1071439D01*
G01X1068239Y1361918D02*
Y1368118D01*
G01X1071439Y1361918D02*
X1068239D01*
G01X1068262Y1361297D02*
X1071462D01*
G01X1074496Y1362425D02*
Y1364123D01*
G01X1075333Y1381049D02*
X1072133D01*
G01X1075333Y1387249D02*
Y1381049D01*
G01X1072133Y1387249D02*
X1075333D01*
G01X1072133Y1381049D02*
Y1387249D01*
G01X1071439Y1378618D02*
Y1377500D01*
G01X1068239Y1378618D02*
X1071439D01*
G01X1076103Y1383943D02*
Y1387143D01*
G01X1082303Y1383943D02*
X1076103D01*
G01Y1387143D02*
X1082303D01*
G01X1067963Y1387150D02*
Y1380950D01*
G01X1074496Y1376836D02*
X1075504D01*
G01X1074496Y1374982D02*
Y1376836D01*
G01X1077883Y1393500D02*
Y1396600D01*
X1078803D01*
X1079110Y1396445D01*
X1079340Y1396083D01*
X1079417Y1395670D01*
X1079340Y1395257D01*
X1079148Y1394947D01*
X1078803Y1394792D01*
X1077883D01*
G01X1080907Y1396600D02*
Y1394378D01*
X1081060Y1393913D01*
X1081367Y1393603D01*
X1081750Y1393500D01*
X1082133Y1393603D01*
X1082440Y1393913D01*
X1082593Y1394378D01*
Y1396600D01*
G01X1084122Y1396083D02*
X1084352Y1396393D01*
X1084620Y1396548D01*
X1084927Y1396600D01*
X1085310Y1396497D01*
X1085578Y1396238D01*
X1085655Y1395928D01*
X1085617Y1395618D01*
X1085463Y1395360D01*
X1084697Y1394843D01*
X1084352Y1394482D01*
X1084122Y1393965D01*
X1084045Y1393500D01*
X1085655D01*
G01X1087950Y1396600D02*
X1087643Y1396497D01*
X1087413Y1396238D01*
X1087260Y1395928D01*
X1087145Y1395515D01*
X1087107Y1395050D01*
X1087145Y1394585D01*
X1087260Y1394172D01*
X1087413Y1393862D01*
X1087643Y1393603D01*
X1087950Y1393500D01*
X1088257Y1393603D01*
X1088487Y1393862D01*
X1088640Y1394172D01*
X1088755Y1394585D01*
X1088793Y1395050D01*
X1088755Y1395515D01*
X1088640Y1395928D01*
X1088487Y1396238D01*
X1088257Y1396497D01*
X1087950Y1396600D01*
G01X1077883Y1389500D02*
Y1392600D01*
X1078803D01*
X1079110Y1392445D01*
X1079340Y1392083D01*
X1079417Y1391670D01*
X1079340Y1391257D01*
X1079148Y1390947D01*
X1078803Y1390792D01*
X1077883D01*
G01X1080983Y1392600D02*
Y1389500D01*
X1082517D01*
G01X1084122Y1392083D02*
X1084352Y1392393D01*
X1084620Y1392548D01*
X1084927Y1392600D01*
X1085310Y1392497D01*
X1085578Y1392238D01*
X1085655Y1391928D01*
X1085617Y1391618D01*
X1085463Y1391360D01*
X1084697Y1390843D01*
X1084352Y1390482D01*
X1084122Y1389965D01*
X1084045Y1389500D01*
X1085655D01*
G01X1087950Y1392600D02*
X1087643Y1392497D01*
X1087413Y1392238D01*
X1087260Y1391928D01*
X1087145Y1391515D01*
X1087107Y1391050D01*
X1087145Y1390585D01*
X1087260Y1390172D01*
X1087413Y1389862D01*
X1087643Y1389603D01*
X1087950Y1389500D01*
X1088257Y1389603D01*
X1088487Y1389862D01*
X1088640Y1390172D01*
X1088755Y1390585D01*
X1088793Y1391050D01*
X1088755Y1391515D01*
X1088640Y1391928D01*
X1088487Y1392238D01*
X1088257Y1392497D01*
X1087950Y1392600D01*
G01X1067942Y1403979D02*
Y1434373D01*
G01X1077784Y1403979D02*
X1067942D01*
G01X1077784Y1434373D02*
Y1403979D01*
G01X1067696Y1436313D02*
X1067888Y1436003D01*
X1068118Y1435796D01*
X1068386Y1435693D01*
X1068693Y1435796D01*
X1068923Y1436003D01*
X1069153Y1436313D01*
X1069230Y1436726D01*
Y1438793D01*
G01X1070796Y1435693D02*
Y1438793D01*
X1071716D01*
X1072023Y1438638D01*
X1072253Y1438276D01*
X1072330Y1437863D01*
X1072253Y1437450D01*
X1072061Y1437140D01*
X1071716Y1436985D01*
X1070796D01*
G01X1073935D02*
X1074203Y1437346D01*
X1074433Y1437553D01*
X1074740Y1437656D01*
X1075008Y1437553D01*
X1075200Y1437346D01*
X1075353Y1437036D01*
X1075391Y1436675D01*
X1075353Y1436365D01*
X1075200Y1436055D01*
X1074970Y1435796D01*
X1074701Y1435693D01*
X1074395Y1435796D01*
X1074126Y1436106D01*
X1073973Y1436571D01*
X1073935Y1437088D01*
X1074011Y1437760D01*
X1074126Y1438121D01*
X1074318Y1438483D01*
X1074586Y1438741D01*
X1074855Y1438793D01*
X1075123Y1438690D01*
X1075315Y1438431D01*
G01X1076920Y1436158D02*
X1077150Y1435900D01*
X1077418Y1435745D01*
X1077763Y1435693D01*
X1078108Y1435796D01*
X1078376Y1436003D01*
X1078568Y1436365D01*
X1078606Y1436778D01*
X1078530Y1437191D01*
X1078338Y1437450D01*
X1078070Y1437656D01*
X1077801Y1437708D01*
X1077533Y1437656D01*
X1077188Y1437450D01*
X1077303Y1438793D01*
X1078338D01*
G01X1080863D02*
X1080556Y1438690D01*
X1080326Y1438431D01*
X1080173Y1438121D01*
X1080058Y1437708D01*
X1080020Y1437243D01*
X1080058Y1436778D01*
X1080173Y1436365D01*
X1080326Y1436055D01*
X1080556Y1435796D01*
X1080863Y1435693D01*
X1081170Y1435796D01*
X1081400Y1436055D01*
X1081553Y1436365D01*
X1081668Y1436778D01*
X1081706Y1437243D01*
X1081668Y1437708D01*
X1081553Y1438121D01*
X1081400Y1438431D01*
X1081170Y1438690D01*
X1080863Y1438793D01*
G01X1083963D02*
X1083656Y1438690D01*
X1083426Y1438431D01*
X1083273Y1438121D01*
X1083158Y1437708D01*
X1083120Y1437243D01*
X1083158Y1436778D01*
X1083273Y1436365D01*
X1083426Y1436055D01*
X1083656Y1435796D01*
X1083963Y1435693D01*
X1084270Y1435796D01*
X1084500Y1436055D01*
X1084653Y1436365D01*
X1084768Y1436778D01*
X1084806Y1437243D01*
X1084768Y1437708D01*
X1084653Y1438121D01*
X1084500Y1438431D01*
X1084270Y1438690D01*
X1083963Y1438793D01*
G01X1067942Y1434373D02*
X1077784D01*
G01X1074207Y1497095D02*
Y1500295D01*
G01X1080407Y1497095D02*
X1074207D01*
G01X1080407Y1500295D02*
Y1497095D01*
G01X1074207Y1500295D02*
X1080407D01*
G01X1078665Y1507588D02*
X1077732D01*
G01X1078665Y1526092D02*
Y1507588D01*
G01X1078032Y1526092D02*
X1078665D01*
G01X1069996Y1566540D02*
Y1535140D01*
G01X1073842Y1639917D02*
X1074204Y1640147D01*
X1074410Y1640453D01*
X1074462Y1640798D01*
X1074410Y1641105D01*
X1074152Y1641412D01*
X1073842Y1641603D01*
X1073532Y1641642D01*
X1073170Y1641565D01*
X1072912Y1641297D01*
X1072809Y1641028D01*
Y1640683D01*
G01Y1641028D02*
X1072654Y1641258D01*
X1072395Y1641450D01*
X1072085Y1641527D01*
X1071775Y1641450D01*
X1071517Y1641258D01*
X1071362Y1640913D01*
X1071414Y1640568D01*
X1071620Y1640223D01*
G01X1068195Y1626889D02*
X1068505Y1627081D01*
X1068712Y1627311D01*
X1068815Y1627579D01*
X1068712Y1627886D01*
X1068505Y1628116D01*
X1068195Y1628346D01*
X1067782Y1628423D01*
X1065715D01*
G01X1068815Y1629989D02*
X1065715D01*
Y1630909D01*
X1065870Y1631216D01*
X1066232Y1631446D01*
X1066645Y1631523D01*
X1067058Y1631446D01*
X1067368Y1631254D01*
X1067523Y1630909D01*
Y1629989D01*
G01X1068815Y1634316D02*
X1065715D01*
X1067937Y1632898D01*
Y1634814D01*
G01X1065715Y1636956D02*
X1065818Y1636649D01*
X1066077Y1636419D01*
X1066387Y1636266D01*
X1066800Y1636151D01*
X1067265Y1636113D01*
X1067730Y1636151D01*
X1068143Y1636266D01*
X1068453Y1636419D01*
X1068712Y1636649D01*
X1068815Y1636956D01*
X1068712Y1637263D01*
X1068453Y1637493D01*
X1068143Y1637646D01*
X1067730Y1637761D01*
X1067265Y1637799D01*
X1066800Y1637761D01*
X1066387Y1637646D01*
X1066077Y1637493D01*
X1065818Y1637263D01*
X1065715Y1636956D01*
G01Y1640056D02*
X1065818Y1639749D01*
X1066077Y1639519D01*
X1066387Y1639366D01*
X1066800Y1639251D01*
X1067265Y1639213D01*
X1067730Y1639251D01*
X1068143Y1639366D01*
X1068453Y1639519D01*
X1068712Y1639749D01*
X1068815Y1640056D01*
X1068712Y1640363D01*
X1068453Y1640593D01*
X1068143Y1640746D01*
X1067730Y1640861D01*
X1067265Y1640899D01*
X1066800Y1640861D01*
X1066387Y1640746D01*
X1066077Y1640593D01*
X1065818Y1640363D01*
X1065715Y1640056D01*
G01X1068195Y1642313D02*
X1068557Y1642543D01*
X1068763Y1642849D01*
X1068815Y1643194D01*
X1068763Y1643501D01*
X1068505Y1643808D01*
X1068195Y1643999D01*
X1067885Y1644038D01*
X1067523Y1643961D01*
X1067265Y1643693D01*
X1067162Y1643424D01*
Y1643079D01*
G01Y1643424D02*
X1067007Y1643654D01*
X1066748Y1643846D01*
X1066438Y1643923D01*
X1066128Y1643846D01*
X1065870Y1643654D01*
X1065715Y1643309D01*
X1065767Y1642964D01*
X1065973Y1642619D01*
G01X1076049Y1635761D02*
Y1666155D01*
G01X1085891Y1635761D02*
X1076049D01*
G01X1065821Y1661520D02*
Y1655320D01*
G01X1069694Y1646395D02*
X1066494D01*
G01X1069694Y1652595D02*
Y1646395D01*
G01X1066494Y1652595D02*
X1069694D01*
G01X1066494Y1646395D02*
Y1652595D01*
G01X1069821Y1655320D02*
X1066621D01*
G01X1069821Y1661520D02*
Y1655320D01*
G01X1066621D02*
Y1661520D01*
G01D02*
X1069821D01*
G01X1076049Y1666155D02*
X1085891D01*
G01X1074272Y1692083D02*
Y1682410D01*
G01Y1775402D02*
Y1717697D01*
G01X1087043Y82957D02*
X1087416Y83332D01*
X1087696Y83957D01*
X1087883Y84832D01*
X1087696Y85582D01*
X1087323Y86082D01*
X1086669Y86457D01*
X1084149D01*
Y78957D01*
X1087229D01*
X1087883Y79457D01*
X1088256Y80207D01*
X1088443Y81082D01*
X1088256Y81957D01*
X1087696Y82707D01*
X1087043Y82957D01*
X1084149D01*
G01X1095476Y78957D02*
Y83957D01*
G01Y83082D02*
X1095103Y83582D01*
X1094543Y83832D01*
X1093889Y83957D01*
X1093236Y83707D01*
X1092676Y83207D01*
X1092303Y82457D01*
X1092116Y81457D01*
X1092303Y80457D01*
X1092676Y79707D01*
X1093236Y79207D01*
X1093889Y78957D01*
X1094543Y79082D01*
X1095103Y79457D01*
X1095476Y79957D01*
G01X1101296Y86457D02*
Y78957D01*
G01X1099989Y83957D02*
X1102603D01*
G01X1108796Y86457D02*
Y78957D01*
G01X1107489Y83957D02*
X1110103D01*
G01X1114896Y82332D02*
X1117883D01*
X1117603Y83207D01*
X1117136Y83707D01*
X1116483Y83957D01*
X1115829Y83832D01*
X1115269Y83457D01*
X1114896Y82582D01*
X1114709Y81832D01*
Y81082D01*
X1114896Y80332D01*
X1115363Y79582D01*
X1115923Y79082D01*
X1116576Y78957D01*
X1117229Y79207D01*
X1117883Y79957D01*
G01X1122489Y78957D02*
Y83957D01*
G01Y82957D02*
X1122956Y83457D01*
X1123423Y83832D01*
X1124076Y83957D01*
X1124543Y83832D01*
X1125103Y83457D01*
G01X1129336Y76707D02*
X1129896Y76457D01*
X1130643Y76707D01*
X1131109Y77207D01*
X1131483Y77832D01*
X1132043Y79832D01*
X1133256Y83957D01*
G01X1130269D02*
X1132043Y79832D01*
G01X1085411Y371587D02*
Y374787D01*
G01X1091611Y371587D02*
X1085411D01*
G01X1091611Y374787D02*
Y371587D01*
G01X1094872Y373041D02*
Y370819D01*
X1095025Y370354D01*
X1095332Y370044D01*
X1095715Y369941D01*
X1096098Y370044D01*
X1096405Y370354D01*
X1096558Y370819D01*
Y373041D01*
G01X1098815Y369941D02*
Y373041D01*
X1098355Y372421D01*
G01Y369941D02*
X1099275D01*
G01X1101072Y370406D02*
X1101302Y370148D01*
X1101570Y369993D01*
X1101915Y369941D01*
X1102260Y370044D01*
X1102528Y370251D01*
X1102720Y370613D01*
X1102758Y371026D01*
X1102682Y371439D01*
X1102490Y371698D01*
X1102222Y371904D01*
X1101953Y371956D01*
X1101685Y371904D01*
X1101340Y371698D01*
X1101455Y373041D01*
X1102490D01*
G01X1105015Y369941D02*
Y373041D01*
X1104555Y372421D01*
G01Y369941D02*
X1105475D01*
G01X1085411Y374787D02*
X1091611D01*
G01X1086335Y388826D02*
Y385626D01*
G01Y380826D02*
Y377626D01*
G01Y384826D02*
Y381626D01*
G01Y392826D02*
Y389626D01*
G01X1095038Y447705D02*
Y444505D01*
G01X1088838D02*
Y447705D01*
G01X1095038Y444505D02*
X1088838D01*
G01Y447705D02*
X1095038D01*
G01Y442205D02*
Y439005D01*
G01X1088838D02*
Y442205D01*
G01X1095038Y439005D02*
X1088838D01*
G01Y442205D02*
X1095038D01*
G01Y464205D02*
Y461005D01*
G01X1088838D02*
Y464205D01*
G01X1095038Y461005D02*
X1088838D01*
G01X1095038Y458705D02*
Y455505D01*
G01X1088838D02*
Y458705D01*
G01X1095038Y455505D02*
X1088838D01*
G01Y458705D02*
X1095038D01*
G01Y453205D02*
Y450005D01*
G01X1088838Y453205D02*
X1095038D01*
G01X1088838Y450005D02*
Y453205D01*
G01X1095038Y450005D02*
X1088838D01*
G01X1095038Y469705D02*
Y466505D01*
G01X1088838Y469705D02*
X1095038D01*
G01X1088838Y466505D02*
Y469705D01*
G01X1095038Y466505D02*
X1088838D01*
G01Y464205D02*
X1095038D01*
G01Y470505D02*
X1088838D01*
G01D02*
Y473705D01*
G01D02*
X1095038D01*
G01D02*
Y470505D01*
G01X1081838Y473705D02*
X1088038D01*
G01D02*
Y470505D01*
G01D02*
X1081838D01*
G01D02*
Y473705D01*
G01X1094548Y480955D02*
Y474755D01*
G01D02*
X1091348D01*
G01D02*
Y480955D01*
G01X1088838Y491241D02*
X1095038D01*
G01D02*
Y488041D01*
G01D02*
X1088838D01*
G01D02*
Y491241D01*
G01X1095038Y496241D02*
Y493041D01*
G01D02*
X1088838D01*
G01D02*
Y496241D01*
G01X1095038Y486205D02*
Y483005D01*
G01X1088838Y486205D02*
X1095038D01*
G01X1088838Y483005D02*
Y486205D01*
G01X1095038Y483005D02*
X1088838D01*
G01X1091348Y480955D02*
X1094548D01*
G01X1088838Y496241D02*
X1095038D01*
G01X1088070Y682595D02*
X1088262Y682285D01*
X1088492Y682078D01*
X1088760Y681975D01*
X1089067Y682078D01*
X1089297Y682285D01*
X1089527Y682595D01*
X1089604Y683008D01*
Y685075D01*
G01X1091209Y684558D02*
X1091439Y684868D01*
X1091707Y685023D01*
X1092014Y685075D01*
X1092397Y684972D01*
X1092665Y684713D01*
X1092742Y684403D01*
X1092704Y684093D01*
X1092550Y683835D01*
X1091784Y683318D01*
X1091439Y682957D01*
X1091209Y682440D01*
X1091132Y681975D01*
X1092742D01*
G01X1095037D02*
Y685075D01*
X1094577Y684455D01*
G01Y681975D02*
X1095497D01*
G01X1094226Y1306689D02*
X1099567D01*
G01X1094182Y1353214D02*
X1093389D01*
G01X1094182Y1355814D02*
Y1353214D01*
G01X1099567Y1349997D02*
X1094226D01*
G01X1089770Y1386439D02*
X1092970D01*
G01X1089770Y1380239D02*
Y1386439D01*
G01X1092970Y1380239D02*
X1089770D01*
G01X1092970Y1386439D02*
Y1380239D01*
G01X1088928D02*
X1085728D01*
G01X1088928Y1386439D02*
Y1380239D01*
G01X1085728Y1386439D02*
X1088928D01*
G01X1085728Y1380239D02*
Y1386439D01*
G01X1082303Y1387143D02*
Y1383943D01*
G01X1094182Y1376836D02*
Y1374645D01*
G01X1093449Y1376836D02*
X1094182D01*
G01X1085591Y1425527D02*
Y1428627D01*
X1086550D01*
X1086856Y1428472D01*
X1087048Y1428265D01*
X1087125Y1427852D01*
X1087048Y1427439D01*
X1086818Y1427180D01*
X1086550Y1427025D01*
X1085591D01*
G01X1086550D02*
X1087125Y1425527D01*
G01X1089458Y1428627D02*
Y1425527D01*
G01X1088576Y1428627D02*
X1090340D01*
G01X1091408Y1424494D02*
X1093708D01*
G01X1094853Y1425940D02*
X1095160Y1425682D01*
X1095505Y1425527D01*
X1095811D01*
X1096118Y1425682D01*
X1096348Y1425940D01*
X1096463Y1426302D01*
X1096386Y1426664D01*
X1096195Y1426974D01*
X1095850Y1427180D01*
X1095390Y1427284D01*
X1095121Y1427490D01*
X1095006Y1427852D01*
X1095083Y1428214D01*
X1095275Y1428472D01*
X1095543Y1428627D01*
X1095811D01*
X1096080Y1428524D01*
X1096310Y1428265D01*
G01X1097761Y1425527D02*
Y1428627D01*
X1098758Y1426044D01*
X1099755Y1428627D01*
Y1425527D01*
G01X1102165Y1427180D02*
X1102318Y1427335D01*
X1102433Y1427594D01*
X1102510Y1427955D01*
X1102433Y1428265D01*
X1102280Y1428472D01*
X1102011Y1428627D01*
X1100976D01*
Y1425527D01*
X1102241D01*
X1102510Y1425734D01*
X1102663Y1426044D01*
X1102740Y1426405D01*
X1102663Y1426767D01*
X1102433Y1427077D01*
X1102165Y1427180D01*
X1100976D01*
G01X1104115Y1428627D02*
Y1426405D01*
X1104268Y1425940D01*
X1104575Y1425630D01*
X1104958Y1425527D01*
X1105341Y1425630D01*
X1105648Y1425940D01*
X1105801Y1426405D01*
Y1428627D01*
G01X1107253Y1425940D02*
X1107560Y1425682D01*
X1107905Y1425527D01*
X1108211D01*
X1108518Y1425682D01*
X1108748Y1425940D01*
X1108863Y1426302D01*
X1108786Y1426664D01*
X1108595Y1426974D01*
X1108250Y1427180D01*
X1107790Y1427284D01*
X1107521Y1427490D01*
X1107406Y1427852D01*
X1107483Y1428214D01*
X1107675Y1428472D01*
X1107943Y1428627D01*
X1108211D01*
X1108480Y1428524D01*
X1108710Y1428265D01*
G01X1083053Y1485849D02*
Y1488949D01*
X1083973D01*
X1084280Y1488794D01*
X1084510Y1488432D01*
X1084587Y1488019D01*
X1084510Y1487606D01*
X1084318Y1487296D01*
X1083973Y1487141D01*
X1083053D01*
G01X1086153Y1485849D02*
Y1488949D01*
X1087073D01*
X1087380Y1488794D01*
X1087610Y1488432D01*
X1087687Y1488019D01*
X1087610Y1487606D01*
X1087418Y1487296D01*
X1087073Y1487141D01*
X1086153D01*
G01X1090020Y1485849D02*
X1089713Y1485901D01*
X1089445Y1486107D01*
X1089215Y1486417D01*
X1089062Y1486779D01*
X1088985Y1487192D01*
Y1487606D01*
X1089062Y1488019D01*
X1089215Y1488381D01*
X1089445Y1488691D01*
X1089713Y1488897D01*
X1090020Y1488949D01*
X1090327Y1488897D01*
X1090595Y1488691D01*
X1090825Y1488381D01*
X1090978Y1488019D01*
X1091055Y1487606D01*
Y1487192D01*
X1090978Y1486779D01*
X1090825Y1486417D01*
X1090595Y1486107D01*
X1090327Y1485901D01*
X1090020Y1485849D01*
G01X1090327Y1486676D02*
X1090787Y1485849D01*
G01X1092468Y1486211D02*
X1092737Y1485952D01*
X1093043Y1485849D01*
X1093350Y1485952D01*
X1093618Y1486262D01*
X1093810Y1486727D01*
X1093887Y1487192D01*
Y1487761D01*
X1093810Y1488226D01*
X1093618Y1488639D01*
X1093388Y1488846D01*
X1093120Y1488949D01*
X1092813Y1488846D01*
X1092583Y1488639D01*
X1092430Y1488329D01*
X1092353Y1487916D01*
X1092430Y1487554D01*
X1092622Y1487192D01*
X1092852Y1486986D01*
X1093120Y1486934D01*
X1093427Y1487037D01*
X1093657Y1487296D01*
X1093887Y1487761D01*
G01X1081165Y1507588D02*
Y1526092D01*
G01X1081998Y1507588D02*
X1081165D01*
G01Y1526092D02*
X1081798D01*
G01X1083034Y1534514D02*
X1099834D01*
G01X1083034Y1567054D02*
Y1534514D01*
G01X1099834Y1567054D02*
X1083034D01*
G01X1089739Y1632126D02*
Y1635326D01*
G01X1095939Y1632126D02*
X1089739D01*
G01Y1635326D02*
X1095939D01*
G01X1089781Y1628345D02*
Y1631545D01*
G01X1095981Y1628345D02*
X1089781D01*
G01Y1631545D02*
X1095981D01*
G01X1085891Y1666155D02*
Y1635761D01*
G01X1089383Y1669620D02*
X1089575Y1669310D01*
X1089805Y1669103D01*
X1090073Y1669000D01*
X1090380Y1669103D01*
X1090610Y1669310D01*
X1090840Y1669620D01*
X1090917Y1670033D01*
Y1672100D01*
G01X1093710Y1669000D02*
Y1672100D01*
X1092292Y1669878D01*
X1094208D01*
G01X1095507Y1669465D02*
X1095737Y1669207D01*
X1096005Y1669052D01*
X1096350Y1669000D01*
X1096695Y1669103D01*
X1096963Y1669310D01*
X1097155Y1669672D01*
X1097193Y1670085D01*
X1097117Y1670498D01*
X1096925Y1670757D01*
X1096657Y1670963D01*
X1096388Y1671015D01*
X1096120Y1670963D01*
X1095775Y1670757D01*
X1095890Y1672100D01*
X1096925D01*
G01X1086083Y1787213D02*
Y1668906D01*
G01X1096214Y1685629D02*
X1090014D01*
G01D02*
Y1688829D01*
G01X1093889Y1700704D02*
X1097089D01*
G01X1093889Y1694504D02*
Y1700704D01*
G01X1097089Y1694504D02*
X1093889D01*
G01X1090014Y1688829D02*
X1096214D01*
G01Y1689629D02*
X1090014D01*
G01D02*
Y1692829D01*
G01D02*
X1096214D01*
G01X1092914Y1714316D02*
Y1720516D01*
G01X1096114Y1714316D02*
X1092914D01*
G01X1099820Y1712944D02*
X1091158D01*
G01D02*
Y1702064D01*
G01D02*
X1099820D01*
G01X1092914Y1720516D02*
X1096114D01*
G01X1092914Y1721316D02*
Y1727516D01*
G01D02*
X1096114D01*
G01Y1721316D02*
X1092914D01*
G01X1108135Y378426D02*
X1112174Y374387D01*
G01X1100777Y394465D02*
Y374387D01*
G01D02*
X1104096D01*
G01D02*
X1108135Y378426D01*
G01X1115493Y394465D02*
X1100777D01*
G01X1103548Y448955D02*
Y445755D01*
G01X1097348D02*
Y448955D01*
G01X1103548Y445755D02*
X1097348D01*
G01X1103548Y464955D02*
Y461755D01*
G01X1097348D02*
Y464955D01*
G01X1103548Y461755D02*
X1097348D01*
G01X1103548Y460955D02*
Y457755D01*
G01X1097348Y460955D02*
X1103548D01*
G01X1097348Y457755D02*
Y460955D01*
G01X1103548Y457755D02*
X1097348D01*
G01X1103548Y456955D02*
Y453755D01*
G01X1097348Y456955D02*
X1103548D01*
G01X1097348Y453755D02*
Y456955D01*
G01X1103548Y453755D02*
X1097348D01*
G01Y452955D02*
X1103548D01*
G01D02*
Y449755D01*
G01X1097348D02*
Y452955D01*
G01X1103548Y449755D02*
X1097348D01*
G01Y448955D02*
X1103548D01*
G01X1097348Y477755D02*
Y480955D01*
G01X1103548Y477755D02*
X1097348D01*
G01X1103548Y480955D02*
Y477755D01*
G01X1097348Y468955D02*
X1103548D01*
G01D02*
Y465755D01*
G01X1097348D02*
Y468955D01*
G01X1103548Y465755D02*
X1097348D01*
G01Y464955D02*
X1103548D01*
G01Y473755D02*
X1097348D01*
G01D02*
Y476955D01*
G01D02*
X1103548D01*
G01D02*
Y473755D01*
G01Y482791D02*
X1097348D01*
G01D02*
Y485991D01*
G01D02*
X1103548D01*
G01D02*
Y482791D01*
G01Y490991D02*
Y487791D01*
G01X1097348Y490991D02*
X1103548D01*
G01X1097348Y487791D02*
Y490991D01*
G01X1103548Y487791D02*
X1097348D01*
G01Y480955D02*
X1103548D01*
G01X1100142Y687244D02*
Y1303900D01*
G01X1125732Y687244D02*
X1100142D01*
G01X1096032Y1303900D02*
Y687244D01*
G01X1125732Y720709D02*
X1100142D01*
G01X1125732Y1291575D02*
X1100142D01*
G01X1102639Y1306689D02*
Y1349997D01*
G01X1107980Y1306689D02*
X1102639D01*
G01X1099567D02*
Y1349997D01*
G01X1105496Y1354797D02*
Y1351597D01*
G01X1099296Y1354797D02*
X1105496D01*
G01X1099296Y1351597D02*
Y1354797D01*
G01X1105496Y1351597D02*
X1099296D01*
G01X1104062Y1355097D02*
X1100862D01*
G01X1104062Y1361297D02*
Y1355097D01*
G01X1100862D02*
Y1361297D01*
G01X1107096Y1353214D02*
Y1355814D01*
G01X1107889Y1353214D02*
X1107096D01*
G01X1102639Y1349997D02*
X1107980D01*
G01X1104039Y1372418D02*
X1100839D01*
G01D02*
Y1378618D01*
G01X1104039Y1374500D02*
Y1372418D01*
G01X1100839Y1368118D02*
X1104039D01*
G01X1100839Y1361918D02*
Y1368118D01*
G01X1104039Y1361918D02*
X1100839D01*
G01X1104039Y1368118D02*
Y1361918D01*
G01X1100248Y1368716D02*
Y1362516D01*
G01X1097048Y1368716D02*
X1100248D01*
G01X1097048Y1362516D02*
Y1368716D01*
G01X1100248Y1362516D02*
X1097048D01*
G01X1100862Y1361297D02*
X1104062D01*
G01X1107096Y1362425D02*
Y1364123D01*
G01X1104039Y1378618D02*
Y1377300D01*
G01X1100839Y1378618D02*
X1104039D01*
G01X1107933Y1381049D02*
X1104733D01*
G01X1107933Y1387249D02*
Y1381049D01*
G01X1104733Y1387249D02*
X1107933D01*
G01X1104733Y1381049D02*
Y1387249D01*
G01X1103755Y1383886D02*
Y1380686D01*
G01X1097555D02*
Y1383886D01*
G01X1103755Y1380686D02*
X1097555D01*
G01Y1383886D02*
X1103755D01*
G01X1108703Y1383943D02*
Y1387143D01*
G01X1114903Y1383943D02*
X1108703D01*
G01Y1387143D02*
X1114903D01*
G01X1107096Y1376836D02*
X1108104D01*
G01X1107096Y1374982D02*
Y1376836D01*
G01X1107383Y1394500D02*
Y1397600D01*
X1108303D01*
X1108610Y1397445D01*
X1108840Y1397083D01*
X1108917Y1396670D01*
X1108840Y1396257D01*
X1108648Y1395947D01*
X1108303Y1395792D01*
X1107383D01*
G01X1110407Y1397600D02*
Y1395378D01*
X1110560Y1394913D01*
X1110867Y1394603D01*
X1111250Y1394500D01*
X1111633Y1394603D01*
X1111940Y1394913D01*
X1112093Y1395378D01*
Y1397600D01*
G01X1114350Y1394500D02*
Y1397600D01*
X1113890Y1396980D01*
G01Y1394500D02*
X1114810D01*
G01X1116798Y1394862D02*
X1117067Y1394603D01*
X1117373Y1394500D01*
X1117680Y1394603D01*
X1117948Y1394913D01*
X1118140Y1395378D01*
X1118217Y1395843D01*
Y1396412D01*
X1118140Y1396877D01*
X1117948Y1397290D01*
X1117718Y1397497D01*
X1117450Y1397600D01*
X1117143Y1397497D01*
X1116913Y1397290D01*
X1116760Y1396980D01*
X1116683Y1396567D01*
X1116760Y1396205D01*
X1116952Y1395843D01*
X1117182Y1395637D01*
X1117450Y1395585D01*
X1117757Y1395688D01*
X1117987Y1395947D01*
X1118217Y1396412D01*
G01X1107522Y1389997D02*
Y1393097D01*
X1108442D01*
X1108749Y1392942D01*
X1108979Y1392580D01*
X1109056Y1392167D01*
X1108979Y1391754D01*
X1108787Y1391444D01*
X1108442Y1391289D01*
X1107522D01*
G01X1110622Y1393097D02*
Y1389997D01*
X1112156D01*
G01X1113761Y1392580D02*
X1113991Y1392890D01*
X1114259Y1393045D01*
X1114566Y1393097D01*
X1114949Y1392994D01*
X1115217Y1392735D01*
X1115294Y1392425D01*
X1115256Y1392115D01*
X1115102Y1391857D01*
X1114336Y1391340D01*
X1113991Y1390979D01*
X1113761Y1390462D01*
X1113684Y1389997D01*
X1115294D01*
G01X1117589D02*
Y1393097D01*
X1117129Y1392477D01*
G01Y1389997D02*
X1118049D01*
G01X1097573Y1497095D02*
Y1500295D01*
G01X1103773Y1497095D02*
X1097573D01*
G01X1103773Y1500295D02*
Y1497095D01*
G01X1097573Y1500295D02*
X1103773D01*
G01X1102031Y1507588D02*
X1101098D01*
G01X1102031Y1526092D02*
Y1507588D01*
G01X1110347Y1527280D02*
X1107147D01*
G01X1110347Y1533480D02*
Y1527280D01*
G01X1107147Y1533480D02*
X1110347D01*
G01X1107147Y1527280D02*
Y1533480D01*
G01X1110347Y1534280D02*
X1107147D01*
G01D02*
Y1540480D01*
G01X1110347D02*
Y1534280D01*
G01X1101398Y1526092D02*
X1102031D01*
G01X1099834Y1534514D02*
Y1567054D01*
G01X1107147Y1540480D02*
X1110347D01*
G01X1111122Y1549833D02*
X1107922D01*
G01D02*
Y1556033D01*
G01X1111158Y1542986D02*
X1107958D01*
G01Y1549186D02*
X1111158D01*
G01X1107958Y1542986D02*
Y1549186D01*
G01X1104599Y1549399D02*
X1101499D01*
Y1550319D01*
X1101654Y1550626D01*
X1102016Y1550856D01*
X1102429Y1550933D01*
X1102842Y1550856D01*
X1103152Y1550664D01*
X1103307Y1550319D01*
Y1549399D01*
G01X1104599Y1552499D02*
X1101499D01*
Y1553458D01*
X1101654Y1553764D01*
X1101861Y1553956D01*
X1102274Y1554033D01*
X1102687Y1553956D01*
X1102946Y1553726D01*
X1103101Y1553458D01*
Y1552499D01*
G01Y1553458D02*
X1104599Y1554033D01*
G01X1103307Y1555638D02*
X1102946Y1555906D01*
X1102739Y1556136D01*
X1102636Y1556443D01*
X1102739Y1556711D01*
X1102946Y1556903D01*
X1103256Y1557056D01*
X1103617Y1557094D01*
X1103927Y1557056D01*
X1104237Y1556903D01*
X1104496Y1556673D01*
X1104599Y1556404D01*
X1104496Y1556098D01*
X1104186Y1555829D01*
X1103721Y1555676D01*
X1103204Y1555638D01*
X1102532Y1555714D01*
X1102171Y1555829D01*
X1101809Y1556021D01*
X1101551Y1556289D01*
X1101499Y1556558D01*
X1101602Y1556826D01*
X1101861Y1557018D01*
G01X1101499Y1559466D02*
X1101602Y1559159D01*
X1101861Y1558929D01*
X1102171Y1558776D01*
X1102584Y1558661D01*
X1103049Y1558623D01*
X1103514Y1558661D01*
X1103927Y1558776D01*
X1104237Y1558929D01*
X1104496Y1559159D01*
X1104599Y1559466D01*
X1104496Y1559773D01*
X1104237Y1560003D01*
X1103927Y1560156D01*
X1103514Y1560271D01*
X1103049Y1560309D01*
X1102584Y1560271D01*
X1102171Y1560156D01*
X1101861Y1560003D01*
X1101602Y1559773D01*
X1101499Y1559466D01*
G01Y1562566D02*
X1101602Y1562259D01*
X1101861Y1562029D01*
X1102171Y1561876D01*
X1102584Y1561761D01*
X1103049Y1561723D01*
X1103514Y1561761D01*
X1103927Y1561876D01*
X1104237Y1562029D01*
X1104496Y1562259D01*
X1104599Y1562566D01*
X1104496Y1562873D01*
X1104237Y1563103D01*
X1103927Y1563256D01*
X1103514Y1563371D01*
X1103049Y1563409D01*
X1102584Y1563371D01*
X1102171Y1563256D01*
X1101861Y1563103D01*
X1101602Y1562873D01*
X1101499Y1562566D01*
G01X1102016Y1564938D02*
X1101706Y1565168D01*
X1101551Y1565436D01*
X1101499Y1565743D01*
X1101602Y1566126D01*
X1101861Y1566394D01*
X1102171Y1566471D01*
X1102481Y1566433D01*
X1102739Y1566279D01*
X1103256Y1565513D01*
X1103617Y1565168D01*
X1104134Y1564938D01*
X1104599Y1564861D01*
Y1566471D01*
G01X1107922Y1556033D02*
X1111122D01*
G01X1097264Y1596082D02*
Y1620582D01*
G01X1105694Y1617387D02*
X1112094D01*
G01X1105694D02*
Y1630267D01*
G01X1097923Y1632800D02*
Y1636000D01*
G01X1104123Y1632800D02*
X1097923D01*
G01Y1636000D02*
X1104123D01*
G01D02*
Y1632800D01*
G01X1098116Y1628523D02*
Y1631723D01*
G01X1104316Y1628523D02*
X1098116D01*
G01Y1631723D02*
X1104316D01*
G01D02*
Y1628523D01*
G01X1095939Y1635326D02*
Y1632126D01*
G01X1095981Y1631545D02*
Y1628345D01*
G01X1097400Y1637400D02*
Y1640600D01*
G01X1103600Y1637400D02*
X1097400D01*
G01Y1640600D02*
X1103600D01*
G01D02*
Y1637400D01*
G01X1097400Y1640900D02*
Y1644100D01*
G01X1103600Y1640900D02*
X1097400D01*
G01X1103600Y1644100D02*
Y1640900D01*
G01X1105694Y1630267D02*
X1112094D01*
G01X1097400Y1644100D02*
X1103600D01*
G01X1107400Y1670100D02*
X1110600D01*
G01X1107400Y1663900D02*
Y1670100D01*
G01X1110600Y1663900D02*
X1107400D01*
G01X1106600Y1674900D02*
X1103400D01*
G01X1106600Y1681100D02*
Y1674900D01*
G01X1103400Y1681100D02*
X1106600D01*
G01X1103400Y1674900D02*
Y1681100D01*
G01X1096214Y1688829D02*
Y1685629D01*
G01X1107700Y1683100D02*
X1112300D01*
G01X1107700Y1672900D02*
Y1683100D01*
G01X1112300Y1672900D02*
X1107700D01*
G01X1097089Y1700704D02*
Y1694504D01*
G01X1097964Y1694429D02*
Y1697629D01*
G01D02*
X1104164D01*
G01D02*
Y1694429D01*
G01D02*
X1097964D01*
G01X1096214Y1692829D02*
Y1689629D01*
G01X1113200Y1699440D02*
X1106800D01*
G01X1113200Y1686560D02*
X1106800D01*
G01D02*
Y1699440D01*
G01X1096114Y1720516D02*
Y1714316D01*
G01X1096914D02*
Y1720516D01*
G01X1100114D02*
Y1714316D01*
G01D02*
X1096914D01*
G01X1112964Y1709644D02*
X1106764D01*
G01D02*
Y1712844D01*
G01D02*
X1112964D01*
G01X1103684Y1706293D02*
Y1704071D01*
X1103837Y1703606D01*
X1104144Y1703296D01*
X1104527Y1703193D01*
X1104910Y1703296D01*
X1105217Y1703606D01*
X1105370Y1704071D01*
Y1706293D01*
G01X1106784Y1703813D02*
X1107014Y1703451D01*
X1107320Y1703245D01*
X1107665Y1703193D01*
X1107972Y1703245D01*
X1108279Y1703503D01*
X1108470Y1703813D01*
X1108509Y1704123D01*
X1108432Y1704485D01*
X1108164Y1704743D01*
X1107895Y1704846D01*
X1107550D01*
G01X1107895D02*
X1108125Y1705001D01*
X1108317Y1705260D01*
X1108394Y1705570D01*
X1108317Y1705880D01*
X1108125Y1706138D01*
X1107780Y1706293D01*
X1107435Y1706241D01*
X1107090Y1706035D01*
G01X1110727Y1706293D02*
X1110420Y1706190D01*
X1110190Y1705931D01*
X1110037Y1705621D01*
X1109922Y1705208D01*
X1109884Y1704743D01*
X1109922Y1704278D01*
X1110037Y1703865D01*
X1110190Y1703555D01*
X1110420Y1703296D01*
X1110727Y1703193D01*
X1111034Y1703296D01*
X1111264Y1703555D01*
X1111417Y1703865D01*
X1111532Y1704278D01*
X1111570Y1704743D01*
X1111532Y1705208D01*
X1111417Y1705621D01*
X1111264Y1705931D01*
X1111034Y1706190D01*
X1110727Y1706293D01*
G01X1113827Y1703193D02*
X1114095Y1703245D01*
X1114402Y1703400D01*
X1114594Y1703658D01*
X1114670Y1704020D01*
X1114594Y1704381D01*
X1114364Y1704691D01*
X1114019Y1704846D01*
X1113635D01*
X1113405Y1704950D01*
X1113214Y1705208D01*
X1113137Y1705570D01*
X1113252Y1705931D01*
X1113520Y1706190D01*
X1113827Y1706293D01*
X1114134Y1706190D01*
X1114402Y1705931D01*
X1114517Y1705570D01*
X1114440Y1705208D01*
X1114249Y1704950D01*
X1114019Y1704846D01*
X1113635D01*
X1113290Y1704691D01*
X1113060Y1704381D01*
X1112984Y1704020D01*
X1113060Y1703658D01*
X1113252Y1703400D01*
X1113559Y1703245D01*
X1113827Y1703193D01*
G01X1097489Y1707504D02*
X1099820Y1709835D01*
G01D02*
Y1712944D01*
G01Y1702064D02*
Y1705173D01*
G01D02*
X1097489Y1707504D01*
G01X1096914Y1720516D02*
X1100114D01*
G01Y1727516D02*
Y1721316D01*
G01D02*
X1096914D01*
G01D02*
Y1727516D01*
G01D02*
X1100114D01*
G01X1096114D02*
Y1721316D01*
G01X1106311Y1727117D02*
X1106004Y1727169D01*
X1105736Y1727375D01*
X1105506Y1727685D01*
X1105353Y1728047D01*
X1105276Y1728460D01*
Y1728874D01*
X1105353Y1729287D01*
X1105506Y1729649D01*
X1105736Y1729959D01*
X1106004Y1730165D01*
X1106311Y1730217D01*
X1106618Y1730165D01*
X1106886Y1729959D01*
X1107116Y1729649D01*
X1107269Y1729287D01*
X1107346Y1728874D01*
Y1728460D01*
X1107269Y1728047D01*
X1107116Y1727685D01*
X1106886Y1727375D01*
X1106618Y1727169D01*
X1106311Y1727117D01*
G01X1106618Y1727944D02*
X1107078Y1727117D01*
G01X1109411D02*
Y1730217D01*
X1108951Y1729597D01*
G01Y1727117D02*
X1109871D01*
G01X1112971D02*
Y1730217D01*
X1111553Y1727995D01*
X1113469D01*
G01X1114768Y1727582D02*
X1114998Y1727324D01*
X1115266Y1727169D01*
X1115611Y1727117D01*
X1115956Y1727220D01*
X1116224Y1727427D01*
X1116416Y1727789D01*
X1116454Y1728202D01*
X1116378Y1728615D01*
X1116186Y1728874D01*
X1115918Y1729080D01*
X1115649Y1729132D01*
X1115381Y1729080D01*
X1115036Y1728874D01*
X1115151Y1730217D01*
X1116186D01*
G01X1105514Y1725881D02*
X1108861D01*
G01D02*
X1110761Y1723681D01*
G01X1116008Y1717219D02*
X1105514D01*
G01D02*
Y1725881D01*
G01X1125133Y51051D02*
Y54251D01*
G01X1131333Y51051D02*
X1125133D01*
G01Y54251D02*
X1131333D01*
G01X1112174Y374387D02*
X1115493D01*
G01D02*
Y394465D01*
G01X1122809Y399620D02*
X1129009D01*
G01Y396420D02*
X1122809D01*
G01D02*
Y399620D01*
G01X1122338Y484870D02*
Y453768D01*
G01D02*
X1136938D01*
G01X1121345Y489086D02*
Y486864D01*
X1121498Y486399D01*
X1121805Y486089D01*
X1122188Y485986D01*
X1122571Y486089D01*
X1122878Y486399D01*
X1123031Y486864D01*
Y489086D01*
G01X1124445Y486606D02*
X1124675Y486244D01*
X1124981Y486038D01*
X1125326Y485986D01*
X1125633Y486038D01*
X1125940Y486296D01*
X1126131Y486606D01*
X1126170Y486916D01*
X1126093Y487278D01*
X1125825Y487536D01*
X1125556Y487639D01*
X1125211D01*
G01X1125556D02*
X1125786Y487794D01*
X1125978Y488053D01*
X1126055Y488363D01*
X1125978Y488673D01*
X1125786Y488931D01*
X1125441Y489086D01*
X1125096Y489034D01*
X1124751Y488828D01*
G01X1127660Y487278D02*
X1127928Y487639D01*
X1128158Y487846D01*
X1128465Y487949D01*
X1128733Y487846D01*
X1128925Y487639D01*
X1129078Y487329D01*
X1129116Y486968D01*
X1129078Y486658D01*
X1128925Y486348D01*
X1128695Y486089D01*
X1128426Y485986D01*
X1128120Y486089D01*
X1127851Y486399D01*
X1127698Y486864D01*
X1127660Y487381D01*
X1127736Y488053D01*
X1127851Y488414D01*
X1128043Y488776D01*
X1128311Y489034D01*
X1128580Y489086D01*
X1128848Y488983D01*
X1129040Y488724D01*
G01X1129638Y479819D02*
X1124587Y484870D01*
G01D02*
X1122338D01*
G01X1114121Y584178D02*
Y587278D01*
G01X1115731D02*
Y584178D01*
G01Y585728D02*
X1114121D01*
G01X1118026Y584178D02*
Y587278D01*
X1117566Y586658D01*
G01Y584178D02*
X1118486D01*
G01X1120398Y586761D02*
X1120628Y587071D01*
X1120896Y587226D01*
X1121203Y587278D01*
X1121586Y587175D01*
X1121854Y586916D01*
X1121931Y586606D01*
X1121893Y586296D01*
X1121739Y586038D01*
X1120973Y585521D01*
X1120628Y585160D01*
X1120398Y584643D01*
X1120321Y584178D01*
X1121931D01*
G01X1123383Y584643D02*
X1123613Y584385D01*
X1123881Y584230D01*
X1124226Y584178D01*
X1124571Y584281D01*
X1124839Y584488D01*
X1125031Y584850D01*
X1125069Y585263D01*
X1124993Y585676D01*
X1124801Y585935D01*
X1124533Y586141D01*
X1124264Y586193D01*
X1123996Y586141D01*
X1123651Y585935D01*
X1123766Y587278D01*
X1124801D01*
G01X1117770Y682595D02*
X1117962Y682285D01*
X1118192Y682078D01*
X1118460Y681975D01*
X1118767Y682078D01*
X1118997Y682285D01*
X1119227Y682595D01*
X1119304Y683008D01*
Y685075D01*
G01X1121637Y681975D02*
Y685075D01*
X1121177Y684455D01*
G01Y681975D02*
X1122097D01*
G01X1124085Y682337D02*
X1124354Y682078D01*
X1124660Y681975D01*
X1124967Y682078D01*
X1125235Y682388D01*
X1125427Y682853D01*
X1125504Y683318D01*
Y683887D01*
X1125427Y684352D01*
X1125235Y684765D01*
X1125005Y684972D01*
X1124737Y685075D01*
X1124430Y684972D01*
X1124200Y684765D01*
X1124047Y684455D01*
X1123970Y684042D01*
X1124047Y683680D01*
X1124239Y683318D01*
X1124469Y683112D01*
X1124737Y683060D01*
X1125044Y683163D01*
X1125274Y683422D01*
X1125504Y683887D01*
G01X1122370Y1386439D02*
X1125570D01*
G01X1122370Y1380239D02*
Y1386439D01*
G01X1125570Y1380239D02*
X1122370D01*
G01X1121528D02*
X1118328D01*
G01X1121528Y1386439D02*
Y1380239D01*
G01X1118328Y1386439D02*
X1121528D01*
G01X1118328Y1380239D02*
Y1386439D01*
G01X1114903Y1387143D02*
Y1383943D01*
G01X1119698Y1407260D02*
X1116598D01*
Y1408180D01*
X1116753Y1408487D01*
X1117115Y1408717D01*
X1117528Y1408794D01*
X1117941Y1408717D01*
X1118251Y1408525D01*
X1118406Y1408180D01*
Y1407260D01*
G01X1116598Y1410360D02*
X1119698D01*
Y1411894D01*
G01Y1414227D02*
X1116598D01*
X1117218Y1413767D01*
G01X1119698D02*
Y1414687D01*
G01X1119336Y1416675D02*
X1119595Y1416944D01*
X1119698Y1417250D01*
X1119595Y1417557D01*
X1119285Y1417825D01*
X1118820Y1418017D01*
X1118355Y1418094D01*
X1117786D01*
X1117321Y1418017D01*
X1116908Y1417825D01*
X1116701Y1417595D01*
X1116598Y1417327D01*
X1116701Y1417020D01*
X1116908Y1416790D01*
X1117218Y1416637D01*
X1117631Y1416560D01*
X1117993Y1416637D01*
X1118355Y1416829D01*
X1118561Y1417059D01*
X1118613Y1417327D01*
X1118510Y1417634D01*
X1118251Y1417864D01*
X1117786Y1418094D01*
G01X1121754Y1406969D02*
X1127865D01*
G01X1121754Y1430985D02*
Y1406969D01*
G01X1127865Y1430985D02*
X1121754D01*
G01X1116217Y1527280D02*
X1113017D01*
G01X1116217Y1533480D02*
Y1527280D01*
G01X1113017Y1533480D02*
X1116217D01*
G01X1113017Y1527280D02*
Y1533480D01*
G01X1115717Y1534280D02*
X1112517D01*
G01D02*
Y1540480D01*
G01X1115717D02*
Y1534280D01*
G01X1111122Y1556033D02*
Y1549833D01*
G01X1112517Y1540480D02*
X1115717D01*
G01X1111158Y1549186D02*
Y1542986D01*
G01X1116804Y1550283D02*
Y1561687D01*
G01X1129008Y1550283D02*
X1116804D01*
G01X1125008Y1555985D02*
X1129008Y1552934D01*
G01Y1559036D02*
X1125008Y1555985D01*
G01X1116804Y1561687D02*
X1129008D01*
G01X1116605Y1577951D02*
X1113405D01*
G01X1116605Y1584151D02*
Y1577951D01*
G01X1113405D02*
Y1584151D01*
G01X1117910Y1577998D02*
Y1582598D01*
G01X1128110Y1577998D02*
X1117910D01*
G01X1122610Y1587298D02*
X1119410D01*
G01X1122610Y1593498D02*
Y1587298D01*
G01X1119410Y1593498D02*
X1122610D01*
G01X1119410Y1587298D02*
Y1593498D01*
G01X1126610Y1587298D02*
X1123410D01*
G01Y1593498D02*
X1126610D01*
G01X1123410Y1587298D02*
Y1593498D01*
G01X1113405Y1584151D02*
X1116605D01*
G01X1113427Y1591651D02*
Y1597851D01*
G01X1116627Y1591651D02*
X1113427D01*
G01X1116627Y1597851D02*
Y1591651D01*
G01X1117910Y1582598D02*
X1128110D01*
G01X1113427Y1597851D02*
X1116627D01*
G01X1132750Y1603827D02*
X1119750D01*
G01D02*
Y1618827D01*
G01X1113794Y1621227D02*
Y1627427D01*
G01X1116994Y1621227D02*
X1113794D01*
G01X1116994Y1627427D02*
Y1621227D01*
G01X1112094Y1630267D02*
Y1617387D01*
G01X1119750Y1618827D02*
X1132750D01*
G01X1113794Y1627427D02*
X1116994D01*
G01X1118658Y1633834D02*
Y1631612D01*
X1118811Y1631147D01*
X1119118Y1630837D01*
X1119501Y1630734D01*
X1119884Y1630837D01*
X1120191Y1631147D01*
X1120344Y1631612D01*
Y1633834D01*
G01X1121758Y1631354D02*
X1121988Y1630992D01*
X1122294Y1630786D01*
X1122639Y1630734D01*
X1122946Y1630786D01*
X1123253Y1631044D01*
X1123444Y1631354D01*
X1123483Y1631664D01*
X1123406Y1632026D01*
X1123138Y1632284D01*
X1122869Y1632387D01*
X1122524D01*
G01X1122869D02*
X1123099Y1632542D01*
X1123291Y1632801D01*
X1123368Y1633111D01*
X1123291Y1633421D01*
X1123099Y1633679D01*
X1122754Y1633834D01*
X1122409Y1633782D01*
X1122064Y1633576D01*
G01X1125701Y1630734D02*
Y1633834D01*
X1125241Y1633214D01*
G01Y1630734D02*
X1126161D01*
G01X1129261D02*
Y1633834D01*
X1127843Y1631612D01*
X1129759D01*
G01X1115673Y1637098D02*
X1117576D01*
G01X1115673Y1639001D02*
Y1637098D01*
G01Y1656784D02*
Y1654881D01*
G01X1110600Y1670100D02*
Y1663900D01*
G01X1110900Y1670100D02*
X1114100D01*
G01X1110900Y1663900D02*
Y1670100D01*
G01X1114100Y1663900D02*
X1110900D01*
G01X1114100Y1670100D02*
Y1663900D01*
G01X1117600D02*
X1114400D01*
G01X1117600Y1670100D02*
Y1663900D01*
G01X1114400Y1670100D02*
X1117600D01*
G01X1114400Y1663900D02*
Y1670100D01*
G01X1117576Y1656784D02*
X1115673D01*
G01X1121903Y1674835D02*
X1118703D01*
G01X1121903Y1681035D02*
Y1674835D01*
G01X1118703Y1681035D02*
X1121903D01*
G01X1118703Y1674835D02*
Y1681035D01*
G01X1112917Y1683075D02*
X1117517D01*
G01X1112917Y1672875D02*
Y1683075D01*
G01X1117517Y1672875D02*
X1112917D01*
G01X1117517Y1683075D02*
Y1672875D01*
G01X1112300Y1683100D02*
Y1672900D01*
G01X1113200Y1699440D02*
Y1686560D01*
G01X1117761Y1714634D02*
Y1720834D01*
G01X1120961D02*
Y1714634D01*
G01D02*
X1117761D01*
G01X1112964Y1712844D02*
Y1709644D01*
G01X1117761Y1720834D02*
X1120961D01*
G01X1110761Y1723681D02*
X1112661Y1725881D01*
G01D02*
X1116008D01*
G01D02*
Y1717219D01*
G01X1131333Y54251D02*
Y51051D01*
G01X1132306Y50999D02*
Y54199D01*
G01X1138506Y50999D02*
X1132306D01*
G01X1138506Y54199D02*
Y50999D01*
G01X1132306Y54199D02*
X1138506D01*
G01X1131538Y54912D02*
Y58112D01*
G01X1137738Y54912D02*
X1131538D01*
G01X1137738Y58112D02*
Y54912D01*
G01X1131538Y58112D02*
X1137738D01*
G01X1131805Y382133D02*
X1138005D01*
G01D02*
Y378933D01*
G01D02*
X1131805D01*
G01D02*
Y382133D01*
G01Y387298D02*
X1138005D01*
G01D02*
Y384098D01*
G01D02*
X1131805D01*
G01D02*
Y387298D01*
G01X1129009Y399620D02*
Y396420D01*
G01X1136938Y453768D02*
Y484870D01*
G01D02*
X1134689D01*
G01D02*
X1129638Y479819D01*
G01X1129843Y687244D02*
Y1303880D01*
G01X1155433Y687244D02*
X1129843D01*
G01X1125732Y1304040D02*
Y687244D01*
G01X1155433Y720709D02*
X1129843D01*
G01X1155433Y1291575D02*
X1129843D01*
G01X1135339Y1306689D02*
Y1349997D01*
G01X1140680Y1306689D02*
X1135339D01*
G01X1132167D02*
Y1349997D01*
G01X1126826Y1306689D02*
X1132167D01*
G01X1138196Y1354797D02*
Y1351597D01*
G01X1131996Y1354797D02*
X1138196D01*
G01X1131996Y1351597D02*
Y1354797D01*
G01X1138196Y1351597D02*
X1131996D01*
G01X1136762Y1355097D02*
X1133562D01*
G01X1136762Y1361297D02*
Y1355097D01*
G01X1133562D02*
Y1361297D01*
G01X1139796Y1353214D02*
Y1355814D01*
G01X1140589Y1353214D02*
X1139796D01*
G01X1126782D02*
X1125989D01*
G01X1126782Y1355814D02*
Y1353214D01*
G01X1135339Y1349997D02*
X1140680D01*
G01X1132167D02*
X1126826D01*
G01X1136739Y1372418D02*
X1133539D01*
G01D02*
Y1378618D01*
G01X1136739Y1374500D02*
Y1372418D01*
G01X1133539Y1368118D02*
X1136739D01*
G01X1133539Y1361918D02*
Y1368118D01*
G01X1136739Y1361918D02*
X1133539D01*
G01X1136739Y1368118D02*
Y1361918D01*
G01X1129648Y1368716D02*
X1132848D01*
G01X1129648Y1362516D02*
Y1368716D01*
G01X1132848Y1362516D02*
X1129648D01*
G01X1132848Y1368716D02*
Y1362516D01*
G01X1133562Y1361297D02*
X1136762D01*
G01X1139796Y1362425D02*
Y1364123D01*
G01X1136739Y1378618D02*
Y1377000D01*
G01X1133539Y1378618D02*
X1136739D01*
G01X1140633Y1381049D02*
X1137433D01*
G01Y1387249D02*
X1140633D01*
G01X1137433Y1381049D02*
Y1387249D01*
G01X1130255Y1380686D02*
Y1383886D01*
G01X1136455Y1380686D02*
X1130255D01*
G01X1136455Y1383886D02*
Y1380686D01*
G01X1130255Y1383886D02*
X1136455D01*
G01X1125570Y1386439D02*
Y1380239D01*
G01X1139796Y1376836D02*
X1140804D01*
G01X1139796Y1374982D02*
Y1376836D01*
G01X1126782D02*
Y1374645D01*
G01X1126049Y1376836D02*
X1126782D01*
G01X1139265Y1406969D02*
X1145376D01*
G01Y1430985D02*
X1139265D01*
G01X1136246Y1461048D02*
X1139446D01*
G01X1136246Y1454848D02*
Y1461048D01*
G01X1139446Y1454848D02*
X1136246D01*
G01X1139446Y1461048D02*
Y1454848D01*
G01X1131446D02*
X1128246D01*
G01X1131446Y1461048D02*
Y1454848D01*
G01X1128246Y1461048D02*
X1131446D01*
G01X1128246Y1454848D02*
Y1461048D01*
G01X1132246D02*
X1135446D01*
G01X1132246Y1454848D02*
Y1461048D01*
G01X1135446Y1454848D02*
X1132246D01*
G01X1135446Y1461048D02*
Y1454848D01*
G01X1130106Y1546727D02*
X1132328D01*
X1132793Y1546880D01*
X1133103Y1547187D01*
X1133206Y1547570D01*
X1133103Y1547953D01*
X1132793Y1548260D01*
X1132328Y1548413D01*
X1130106D01*
G01X1133206Y1550670D02*
X1130106D01*
X1130726Y1550210D01*
G01X1133206D02*
Y1551130D01*
G01Y1554230D02*
X1130106D01*
X1132328Y1552812D01*
Y1554728D01*
G01X1132586Y1556027D02*
X1132948Y1556257D01*
X1133154Y1556563D01*
X1133206Y1556908D01*
X1133154Y1557215D01*
X1132896Y1557522D01*
X1132586Y1557713D01*
X1132276Y1557752D01*
X1131914Y1557675D01*
X1131656Y1557407D01*
X1131553Y1557138D01*
Y1556793D01*
G01Y1557138D02*
X1131398Y1557368D01*
X1131139Y1557560D01*
X1130829Y1557637D01*
X1130519Y1557560D01*
X1130261Y1557368D01*
X1130106Y1557023D01*
X1130158Y1556678D01*
X1130364Y1556333D01*
G01X1129008Y1552934D02*
Y1550283D01*
G01Y1561687D02*
Y1559036D01*
G01X1132856Y1567427D02*
X1129656D01*
G01X1132856Y1573627D02*
Y1567427D01*
G01X1129656Y1573627D02*
X1132856D01*
G01X1129656Y1567427D02*
Y1573627D01*
G01X1128110Y1582598D02*
Y1577998D01*
G01X1136106Y1577110D02*
X1150506D01*
G01X1136106Y1596796D02*
Y1577110D01*
G01X1126610Y1593498D02*
Y1587298D01*
G01X1143306Y1592553D02*
X1139063Y1596796D01*
G01D02*
X1136106D01*
G01X1136700Y1605148D02*
X1136648Y1604841D01*
X1136442Y1604573D01*
X1136132Y1604343D01*
X1135770Y1604190D01*
X1135357Y1604113D01*
X1134943D01*
X1134530Y1604190D01*
X1134168Y1604343D01*
X1133858Y1604573D01*
X1133652Y1604841D01*
X1133600Y1605148D01*
X1133652Y1605455D01*
X1133858Y1605723D01*
X1134168Y1605953D01*
X1134530Y1606106D01*
X1134943Y1606183D01*
X1135357D01*
X1135770Y1606106D01*
X1136132Y1605953D01*
X1136442Y1605723D01*
X1136648Y1605455D01*
X1136700Y1605148D01*
G01X1135873Y1605455D02*
X1136700Y1605915D01*
G01X1135408Y1607520D02*
X1135047Y1607788D01*
X1134840Y1608018D01*
X1134737Y1608325D01*
X1134840Y1608593D01*
X1135047Y1608785D01*
X1135357Y1608938D01*
X1135718Y1608976D01*
X1136028Y1608938D01*
X1136338Y1608785D01*
X1136597Y1608555D01*
X1136700Y1608286D01*
X1136597Y1607980D01*
X1136287Y1607711D01*
X1135822Y1607558D01*
X1135305Y1607520D01*
X1134633Y1607596D01*
X1134272Y1607711D01*
X1133910Y1607903D01*
X1133652Y1608171D01*
X1133600Y1608440D01*
X1133703Y1608708D01*
X1133962Y1608900D01*
G01X1133600Y1611348D02*
X1133703Y1611041D01*
X1133962Y1610811D01*
X1134272Y1610658D01*
X1134685Y1610543D01*
X1135150Y1610505D01*
X1135615Y1610543D01*
X1136028Y1610658D01*
X1136338Y1610811D01*
X1136597Y1611041D01*
X1136700Y1611348D01*
X1136597Y1611655D01*
X1136338Y1611885D01*
X1136028Y1612038D01*
X1135615Y1612153D01*
X1135150Y1612191D01*
X1134685Y1612153D01*
X1134272Y1612038D01*
X1133962Y1611885D01*
X1133703Y1611655D01*
X1133600Y1611348D01*
G01Y1614448D02*
X1133703Y1614141D01*
X1133962Y1613911D01*
X1134272Y1613758D01*
X1134685Y1613643D01*
X1135150Y1613605D01*
X1135615Y1613643D01*
X1136028Y1613758D01*
X1136338Y1613911D01*
X1136597Y1614141D01*
X1136700Y1614448D01*
X1136597Y1614755D01*
X1136338Y1614985D01*
X1136028Y1615138D01*
X1135615Y1615253D01*
X1135150Y1615291D01*
X1134685Y1615253D01*
X1134272Y1615138D01*
X1133962Y1614985D01*
X1133703Y1614755D01*
X1133600Y1614448D01*
G01X1136700Y1617548D02*
X1133600D01*
X1134220Y1617088D01*
G01X1136700D02*
Y1618008D01*
G01X1132750Y1618827D02*
Y1603827D01*
G01X1130568Y1621865D02*
Y1628065D01*
G01X1133768Y1621865D02*
X1130568D01*
G01X1133768Y1628065D02*
Y1621865D01*
G01X1134497Y1621868D02*
Y1628068D01*
G01X1137697Y1621868D02*
X1134497D01*
G01X1137697Y1628068D02*
Y1621868D01*
G01X1130568Y1628065D02*
X1133768D01*
G01X1134497Y1628068D02*
X1137697D01*
G01X1135359Y1637098D02*
Y1639001D01*
G01X1133456Y1637098D02*
X1135359D01*
G01Y1654881D02*
Y1656784D01*
G01X1141717Y1664052D02*
X1138517D01*
G01Y1670252D02*
X1141717D01*
G01X1138517Y1664052D02*
Y1670252D01*
G01X1135359Y1656784D02*
X1133456D01*
G01X1132278Y1672573D02*
Y1684573D01*
G01D02*
X1135678D01*
G01X1143078Y1672573D02*
X1132278D01*
G01X1135678Y1684573D02*
X1137678Y1682573D01*
G01D02*
X1139678Y1684573D01*
G01D02*
X1143078D01*
G01X1134946Y1690859D02*
Y1688637D01*
X1135099Y1688172D01*
X1135406Y1687862D01*
X1135789Y1687759D01*
X1136172Y1687862D01*
X1136479Y1688172D01*
X1136632Y1688637D01*
Y1690859D01*
G01X1138889Y1687759D02*
Y1690859D01*
X1138429Y1690239D01*
G01Y1687759D02*
X1139349D01*
G01X1141912D02*
X1141989Y1688431D01*
X1142104Y1688999D01*
X1142257Y1689516D01*
X1142449Y1690084D01*
X1142756Y1690859D01*
X1141222D01*
G01X1144361Y1689051D02*
X1144629Y1689412D01*
X1144859Y1689619D01*
X1145166Y1689722D01*
X1145434Y1689619D01*
X1145626Y1689412D01*
X1145779Y1689102D01*
X1145817Y1688741D01*
X1145779Y1688431D01*
X1145626Y1688121D01*
X1145396Y1687862D01*
X1145127Y1687759D01*
X1144821Y1687862D01*
X1144552Y1688172D01*
X1144399Y1688637D01*
X1144361Y1689154D01*
X1144437Y1689826D01*
X1144552Y1690187D01*
X1144744Y1690549D01*
X1145012Y1690807D01*
X1145281Y1690859D01*
X1145549Y1690756D01*
X1145741Y1690497D01*
G01X1127088Y1728945D02*
Y1732045D01*
G01X1128698D02*
Y1728945D01*
G01Y1730495D02*
X1127088D01*
G01X1130993Y1728945D02*
Y1732045D01*
X1130533Y1731425D01*
G01Y1728945D02*
X1131453D01*
G01X1134093Y1732045D02*
X1133786Y1731942D01*
X1133556Y1731683D01*
X1133403Y1731373D01*
X1133288Y1730960D01*
X1133250Y1730495D01*
X1133288Y1730030D01*
X1133403Y1729617D01*
X1133556Y1729307D01*
X1133786Y1729048D01*
X1134093Y1728945D01*
X1134400Y1729048D01*
X1134630Y1729307D01*
X1134783Y1729617D01*
X1134898Y1730030D01*
X1134936Y1730495D01*
X1134898Y1730960D01*
X1134783Y1731373D01*
X1134630Y1731683D01*
X1134400Y1731942D01*
X1134093Y1732045D01*
G01X1137653Y1728945D02*
Y1732045D01*
X1136235Y1729823D01*
X1138151D01*
G01X1145345Y50843D02*
X1172493D01*
G01X1145345Y70529D02*
Y50843D01*
G01X1145718Y73138D02*
Y76338D01*
G01X1151918Y73138D02*
X1145718D01*
G01X1151918Y76338D02*
Y73138D01*
G01X1153076Y70529D02*
X1145345D01*
G01X1158919Y64686D02*
X1153076Y70529D01*
G01X1145718Y76338D02*
X1151918D01*
G01X1152941Y112258D02*
X1153094Y112413D01*
X1153209Y112672D01*
X1153286Y113033D01*
X1153209Y113343D01*
X1153056Y113550D01*
X1152787Y113705D01*
X1151752D01*
Y110605D01*
X1153017D01*
X1153286Y110812D01*
X1153439Y111122D01*
X1153516Y111483D01*
X1153439Y111845D01*
X1153209Y112155D01*
X1152941Y112258D01*
X1151752D01*
G01X1155734Y113705D02*
Y110605D01*
G01X1154852Y113705D02*
X1156616D01*
G01X1158106Y113188D02*
X1158336Y113498D01*
X1158604Y113653D01*
X1158911Y113705D01*
X1159294Y113602D01*
X1159562Y113343D01*
X1159639Y113033D01*
X1159601Y112723D01*
X1159447Y112465D01*
X1158681Y111948D01*
X1158336Y111587D01*
X1158106Y111070D01*
X1158029Y110605D01*
X1159639D01*
G01X1161024Y118905D02*
X1149262D01*
G01X1149537Y118512D02*
X1161339D01*
G01X1149262Y148827D02*
X1161024D01*
G01X1161339Y149220D02*
X1149537D01*
G01X1150593Y206435D02*
X1156793D01*
G01Y203235D02*
X1150593D01*
G01D02*
Y206435D01*
G01X1156793Y208235D02*
X1150593D01*
G01D02*
Y211435D01*
G01D02*
X1156793D01*
G01X1143138Y491419D02*
X1149338D01*
G01D02*
Y488219D01*
G01D02*
X1143138D01*
G01D02*
Y491419D01*
G01X1147471Y682595D02*
X1147663Y682285D01*
X1147893Y682078D01*
X1148161Y681975D01*
X1148468Y682078D01*
X1148698Y682285D01*
X1148928Y682595D01*
X1149005Y683008D01*
Y685075D01*
G01X1151338Y681975D02*
Y685075D01*
X1150878Y684455D01*
G01Y681975D02*
X1151798D01*
G01X1154361D02*
X1154438Y682647D01*
X1154553Y683215D01*
X1154706Y683732D01*
X1154898Y684300D01*
X1155205Y685075D01*
X1153671D01*
G01X1155070Y1386439D02*
X1158270D01*
G01X1155070Y1380239D02*
Y1386439D01*
G01X1158270Y1380239D02*
X1155070D01*
G01X1140633Y1387249D02*
Y1381049D01*
G01X1154228Y1380239D02*
X1151028D01*
G01X1154228Y1386439D02*
Y1380239D01*
G01X1151028Y1386439D02*
X1154228D01*
G01X1151028Y1380239D02*
Y1386439D01*
G01X1147603Y1387143D02*
Y1383943D01*
G01X1141403D02*
Y1387143D01*
G01X1147603Y1383943D02*
X1141403D01*
G01Y1387143D02*
X1147603D01*
G01X1140883Y1394000D02*
Y1397100D01*
X1141803D01*
X1142110Y1396945D01*
X1142340Y1396583D01*
X1142417Y1396170D01*
X1142340Y1395757D01*
X1142148Y1395447D01*
X1141803Y1395292D01*
X1140883D01*
G01X1143907Y1397100D02*
Y1394878D01*
X1144060Y1394413D01*
X1144367Y1394103D01*
X1144750Y1394000D01*
X1145133Y1394103D01*
X1145440Y1394413D01*
X1145593Y1394878D01*
Y1397100D01*
G01X1147850Y1394000D02*
Y1397100D01*
X1147390Y1396480D01*
G01Y1394000D02*
X1148310D01*
G01X1150950D02*
X1151218Y1394052D01*
X1151525Y1394207D01*
X1151717Y1394465D01*
X1151793Y1394827D01*
X1151717Y1395188D01*
X1151487Y1395498D01*
X1151142Y1395653D01*
X1150758D01*
X1150528Y1395757D01*
X1150337Y1396015D01*
X1150260Y1396377D01*
X1150375Y1396738D01*
X1150643Y1396997D01*
X1150950Y1397100D01*
X1151257Y1396997D01*
X1151525Y1396738D01*
X1151640Y1396377D01*
X1151563Y1396015D01*
X1151372Y1395757D01*
X1151142Y1395653D01*
X1150758D01*
X1150413Y1395498D01*
X1150183Y1395188D01*
X1150107Y1394827D01*
X1150183Y1394465D01*
X1150375Y1394207D01*
X1150682Y1394052D01*
X1150950Y1394000D01*
G01X1140883Y1389500D02*
Y1392600D01*
X1141803D01*
X1142110Y1392445D01*
X1142340Y1392083D01*
X1142417Y1391670D01*
X1142340Y1391257D01*
X1142148Y1390947D01*
X1141803Y1390792D01*
X1140883D01*
G01X1143983Y1392600D02*
Y1389500D01*
X1145517D01*
G01X1147850D02*
Y1392600D01*
X1147390Y1391980D01*
G01Y1389500D02*
X1148310D01*
G01X1150950D02*
X1151218Y1389552D01*
X1151525Y1389707D01*
X1151717Y1389965D01*
X1151793Y1390327D01*
X1151717Y1390688D01*
X1151487Y1390998D01*
X1151142Y1391153D01*
X1150758D01*
X1150528Y1391257D01*
X1150337Y1391515D01*
X1150260Y1391877D01*
X1150375Y1392238D01*
X1150643Y1392497D01*
X1150950Y1392600D01*
X1151257Y1392497D01*
X1151525Y1392238D01*
X1151640Y1391877D01*
X1151563Y1391515D01*
X1151372Y1391257D01*
X1151142Y1391153D01*
X1150758D01*
X1150413Y1390998D01*
X1150183Y1390688D01*
X1150107Y1390327D01*
X1150183Y1389965D01*
X1150375Y1389707D01*
X1150682Y1389552D01*
X1150950Y1389500D01*
G01X1145376Y1406969D02*
Y1430985D01*
G01X1179921Y1417400D02*
X1153149D01*
G01X1179921D02*
G02I-13386J0D01*
G01X1145783Y1434979D02*
Y1438179D01*
G01X1151983Y1434979D02*
X1145783D01*
G01X1151983Y1438179D02*
Y1434979D01*
G01X1145783Y1438179D02*
X1151983D01*
G01X1140772Y1443388D02*
Y1456066D01*
G01X1156126Y1443388D02*
X1140772D01*
G01Y1456066D02*
X1156126D01*
G01X1146715Y1465515D02*
Y1468615D01*
X1147635D01*
X1147942Y1468460D01*
X1148172Y1468098D01*
X1148249Y1467685D01*
X1148172Y1467272D01*
X1147980Y1466962D01*
X1147635Y1466807D01*
X1146715D01*
G01X1150582Y1465515D02*
X1150275Y1465567D01*
X1150007Y1465773D01*
X1149777Y1466083D01*
X1149624Y1466445D01*
X1149547Y1466858D01*
Y1467272D01*
X1149624Y1467685D01*
X1149777Y1468047D01*
X1150007Y1468357D01*
X1150275Y1468563D01*
X1150582Y1468615D01*
X1150889Y1468563D01*
X1151157Y1468357D01*
X1151387Y1468047D01*
X1151540Y1467685D01*
X1151617Y1467272D01*
Y1466858D01*
X1151540Y1466445D01*
X1151387Y1466083D01*
X1151157Y1465773D01*
X1150889Y1465567D01*
X1150582Y1465515D01*
G01X1150889Y1466342D02*
X1151349Y1465515D01*
G01X1153682D02*
Y1468615D01*
X1153222Y1467995D01*
G01Y1465515D02*
X1154142D01*
G01X1157242D02*
Y1468615D01*
X1155824Y1466393D01*
X1157740D01*
G01X1150294Y1551959D02*
X1140180D01*
G01X1150294Y1560099D02*
Y1551959D01*
G01X1140180Y1560099D02*
X1150294D01*
G01X1140180Y1551959D02*
Y1560099D01*
G01X1150506Y1577110D02*
Y1596796D01*
G01X1147549D02*
X1143306Y1592553D01*
G01X1143517Y1600892D02*
Y1598670D01*
X1143670Y1598205D01*
X1143977Y1597895D01*
X1144360Y1597792D01*
X1144743Y1597895D01*
X1145050Y1598205D01*
X1145203Y1598670D01*
Y1600892D01*
G01X1147460Y1597792D02*
Y1600892D01*
X1147000Y1600272D01*
G01Y1597792D02*
X1147920D01*
G01X1149717Y1598257D02*
X1149947Y1597999D01*
X1150215Y1597844D01*
X1150560Y1597792D01*
X1150905Y1597895D01*
X1151173Y1598102D01*
X1151365Y1598464D01*
X1151403Y1598877D01*
X1151327Y1599290D01*
X1151135Y1599549D01*
X1150867Y1599755D01*
X1150598Y1599807D01*
X1150330Y1599755D01*
X1149985Y1599549D01*
X1150100Y1600892D01*
X1151135D01*
G01X1150506Y1596796D02*
X1147549D01*
G01X1141717Y1670252D02*
Y1664052D01*
G01X1145707Y1663966D02*
X1142507D01*
G01X1145707Y1670166D02*
Y1663966D01*
G01X1142507Y1670166D02*
X1145707D01*
G01X1142507Y1663966D02*
Y1670166D01*
G01X1143078Y1684573D02*
Y1672573D01*
G01X1167803Y78877D02*
Y72677D01*
G01D02*
X1164603D01*
G01D02*
Y78877D01*
G01X1163611Y72339D02*
X1157411D01*
G01D02*
Y75539D01*
G01D02*
X1163611D01*
G01D02*
Y72339D01*
G01X1169882Y73691D02*
X1178944D01*
G01X1169882Y85805D02*
Y73691D01*
G01X1172493Y70529D02*
X1164762D01*
G01D02*
X1158919Y64686D01*
G01X1164603Y78877D02*
X1167803D01*
G01X1165820Y80569D02*
X1168042D01*
X1168507Y80722D01*
X1168817Y81029D01*
X1168920Y81412D01*
X1168817Y81795D01*
X1168507Y82102D01*
X1168042Y82255D01*
X1165820D01*
G01X1168920Y84512D02*
X1165820D01*
X1166440Y84052D01*
G01X1168920D02*
Y84972D01*
G01X1167628Y86884D02*
X1167267Y87152D01*
X1167060Y87382D01*
X1166957Y87689D01*
X1167060Y87957D01*
X1167267Y88149D01*
X1167577Y88302D01*
X1167938Y88340D01*
X1168248Y88302D01*
X1168558Y88149D01*
X1168817Y87919D01*
X1168920Y87650D01*
X1168817Y87344D01*
X1168507Y87075D01*
X1168042Y86922D01*
X1167525Y86884D01*
X1166853Y86960D01*
X1166492Y87075D01*
X1166130Y87267D01*
X1165872Y87535D01*
X1165820Y87804D01*
X1165923Y88072D01*
X1166182Y88264D01*
G01X1168920Y90635D02*
X1168248Y90712D01*
X1167680Y90827D01*
X1167163Y90980D01*
X1166595Y91172D01*
X1165820Y91479D01*
Y89945D01*
G01X1178944Y85805D02*
X1169882D01*
G01X1161024Y148827D02*
Y118905D01*
G01X1161339Y118512D02*
Y149220D01*
G01X1156793Y206435D02*
Y203235D01*
G01Y211435D02*
Y208235D01*
G01X1168602Y202402D02*
Y222008D01*
G01X1199114Y202402D02*
X1168602D01*
G01Y222008D02*
X1199114D01*
G01X1168106Y443941D02*
X1174306D01*
G01X1168106Y440741D02*
Y443941D01*
G01X1174306Y440741D02*
X1168106D01*
G01Y446241D02*
Y449441D01*
G01X1174306Y446241D02*
X1168106D01*
G01X1156038Y448091D02*
Y451291D01*
G01X1162238Y448091D02*
X1156038D01*
G01X1162238Y451291D02*
Y448091D01*
G01X1156038Y463291D02*
X1162238D01*
G01D02*
Y460091D01*
G01D02*
X1156038D01*
G01D02*
Y463291D01*
G01X1168106Y462741D02*
Y465941D01*
G01X1174306Y462741D02*
X1168106D01*
G01Y449441D02*
X1174306D01*
G01X1156038Y456091D02*
Y459291D01*
G01X1162238Y456091D02*
X1156038D01*
G01X1162238Y459291D02*
Y456091D01*
G01X1156038Y459291D02*
X1162238D01*
G01X1156038Y451291D02*
X1162238D01*
G01X1156038Y455291D02*
X1162238D01*
G01X1156038Y452091D02*
Y455291D01*
G01X1162238Y452091D02*
X1156038D01*
G01X1162238Y455291D02*
Y452091D01*
G01X1174306Y451741D02*
X1168106D01*
G01D02*
Y454941D01*
G01D02*
X1174306D01*
G01Y457241D02*
X1168106D01*
G01D02*
Y460441D01*
G01D02*
X1174306D01*
G01X1168106Y465941D02*
X1174306D01*
G01X1168106Y471441D02*
X1174306D01*
G01X1168106Y468241D02*
Y471441D01*
G01X1174306Y468241D02*
X1168106D01*
G01X1156038Y464091D02*
Y467291D01*
G01X1162238Y464091D02*
X1156038D01*
G01X1162238Y467291D02*
Y464091D01*
G01X1156038Y467291D02*
X1162238D01*
G01X1156038Y471291D02*
X1162238D01*
G01X1156038Y468091D02*
Y471291D01*
G01X1162238Y468091D02*
X1156038D01*
G01X1162238Y471291D02*
Y468091D01*
G01X1174306Y480091D02*
X1168106D01*
G01D02*
Y483291D01*
G01D02*
X1174306D01*
G01X1156038D02*
X1162238D01*
G01D02*
Y480091D01*
G01D02*
X1156038D01*
G01D02*
Y483291D01*
G01X1167432Y582202D02*
X1173632D01*
G01Y579002D02*
X1167432D01*
G01D02*
Y582202D01*
G01X1173632Y574002D02*
X1167432D01*
Y577202D01*
X1173632D01*
Y574002D01*
G01X1170482D02*
X1164282D01*
Y577202D01*
X1170482D01*
Y574002D01*
G01X1167492Y586222D02*
X1173692D01*
G01Y583022D02*
X1167492D01*
G01D02*
Y586222D01*
G01X1173675Y591073D02*
X1167475D01*
Y594273D01*
X1173675D01*
Y591073D01*
G01X1170525D02*
X1164325D01*
Y594273D01*
X1170525D01*
Y591073D01*
G01X1159544Y687244D02*
Y1303850D01*
G01X1185134Y687244D02*
X1159544D01*
G01X1155433Y1303850D02*
Y687244D01*
G01X1185134Y720709D02*
X1159544D01*
G01X1185134Y1291575D02*
X1159544D01*
G01X1168239Y1306689D02*
Y1349997D01*
G01X1173580Y1306689D02*
X1168239D01*
G01X1164867D02*
Y1349997D01*
G01X1159526Y1306689D02*
X1164867D01*
G01X1164896Y1354797D02*
X1171096D01*
G01X1164896Y1351597D02*
Y1354797D01*
G01X1171096Y1351597D02*
X1164896D01*
G01X1169662Y1355097D02*
X1166462D01*
G01X1169662Y1361297D02*
Y1355097D01*
G01X1166462D02*
Y1361297D01*
G01X1159482Y1353214D02*
X1158689D01*
G01X1159482Y1355814D02*
Y1353214D01*
G01X1168239Y1349997D02*
X1173580D01*
G01X1164867D02*
X1159526D01*
G01X1162348Y1368716D02*
X1165548D01*
G01X1162348Y1362516D02*
Y1368716D01*
G01X1165548Y1362516D02*
X1162348D01*
G01X1165548Y1368716D02*
Y1362516D01*
G01X1169639Y1372418D02*
X1166439D01*
G01D02*
Y1378618D01*
G01X1169639Y1374700D02*
Y1372418D01*
G01X1166439Y1368118D02*
X1169639D01*
G01X1166439Y1361918D02*
Y1368118D01*
G01X1169639Y1361918D02*
X1166439D01*
G01X1169639Y1368118D02*
Y1361918D01*
G01X1166462Y1361297D02*
X1169662D01*
G01X1169639Y1378618D02*
Y1377100D01*
G01X1166439Y1378618D02*
X1169639D01*
G01X1163155Y1380686D02*
Y1383886D01*
G01X1169355Y1380686D02*
X1163155D01*
G01X1169355Y1383886D02*
Y1380686D01*
G01X1163155Y1383886D02*
X1169355D01*
G01X1158270Y1386439D02*
Y1380239D01*
G01X1159482Y1376836D02*
Y1374645D01*
G01X1158749Y1376836D02*
X1159482D01*
G01X1159883Y1432500D02*
Y1435600D01*
X1160803D01*
X1161110Y1435445D01*
X1161340Y1435083D01*
X1161417Y1434670D01*
X1161340Y1434257D01*
X1161148Y1433947D01*
X1160803Y1433792D01*
X1159883D01*
G01X1164593Y1435342D02*
X1164363Y1435497D01*
X1164095Y1435600D01*
X1163788D01*
X1163443Y1435445D01*
X1163175Y1435187D01*
X1162983Y1434877D01*
X1162830Y1434360D01*
X1162792Y1433895D01*
X1162868Y1433430D01*
X1162983Y1433120D01*
X1163213Y1432810D01*
X1163482Y1432603D01*
X1163750Y1432500D01*
X1164018D01*
X1164287Y1432603D01*
X1164517Y1432758D01*
X1164708Y1432965D01*
G01X1166850Y1432500D02*
Y1435600D01*
X1166390Y1434980D01*
G01Y1432500D02*
X1167310D01*
G01X1169222Y1433792D02*
X1169490Y1434153D01*
X1169720Y1434360D01*
X1170027Y1434463D01*
X1170295Y1434360D01*
X1170487Y1434153D01*
X1170640Y1433843D01*
X1170678Y1433482D01*
X1170640Y1433172D01*
X1170487Y1432862D01*
X1170257Y1432603D01*
X1169988Y1432500D01*
X1169682Y1432603D01*
X1169413Y1432913D01*
X1169260Y1433378D01*
X1169222Y1433895D01*
X1169298Y1434567D01*
X1169413Y1434928D01*
X1169605Y1435290D01*
X1169873Y1435548D01*
X1170142Y1435600D01*
X1170410Y1435497D01*
X1170602Y1435238D01*
G01X1173510Y1432500D02*
Y1435600D01*
X1172092Y1433378D01*
X1174008D01*
G01X1156126Y1455869D02*
Y1443388D01*
G01X1157788Y1439094D02*
Y1450906D01*
G01X1170412Y1439094D02*
X1157788D01*
G01X1164875Y1455834D02*
Y1452634D01*
G01X1158675Y1455834D02*
X1164875D01*
G01X1158675Y1452634D02*
Y1455834D01*
G01X1164875Y1452634D02*
X1158675D01*
G01X1158742Y1456906D02*
Y1460006D01*
X1159662D01*
X1159969Y1459851D01*
X1160199Y1459489D01*
X1160276Y1459076D01*
X1160199Y1458663D01*
X1160007Y1458353D01*
X1159662Y1458198D01*
X1158742D01*
G01X1162609Y1456906D02*
X1162302Y1456958D01*
X1162034Y1457164D01*
X1161804Y1457474D01*
X1161651Y1457836D01*
X1161574Y1458249D01*
Y1458663D01*
X1161651Y1459076D01*
X1161804Y1459438D01*
X1162034Y1459748D01*
X1162302Y1459954D01*
X1162609Y1460006D01*
X1162916Y1459954D01*
X1163184Y1459748D01*
X1163414Y1459438D01*
X1163567Y1459076D01*
X1163644Y1458663D01*
Y1458249D01*
X1163567Y1457836D01*
X1163414Y1457474D01*
X1163184Y1457164D01*
X1162916Y1456958D01*
X1162609Y1456906D01*
G01X1162916Y1457733D02*
X1163376Y1456906D01*
G01X1165709D02*
Y1460006D01*
X1165249Y1459386D01*
G01Y1456906D02*
X1166169D01*
G01X1168809Y1460006D02*
X1168502Y1459903D01*
X1168272Y1459644D01*
X1168119Y1459334D01*
X1168004Y1458921D01*
X1167966Y1458456D01*
X1168004Y1457991D01*
X1168119Y1457578D01*
X1168272Y1457268D01*
X1168502Y1457009D01*
X1168809Y1456906D01*
X1169116Y1457009D01*
X1169346Y1457268D01*
X1169499Y1457578D01*
X1169614Y1457991D01*
X1169652Y1458456D01*
X1169614Y1458921D01*
X1169499Y1459334D01*
X1169346Y1459644D01*
X1169116Y1459903D01*
X1168809Y1460006D01*
G01X1157788Y1450906D02*
X1170412D01*
G01X1158765Y1555706D02*
X1160987D01*
X1161452Y1555859D01*
X1161762Y1556166D01*
X1161865Y1556549D01*
X1161762Y1556932D01*
X1161452Y1557239D01*
X1160987Y1557392D01*
X1158765D01*
G01X1161865Y1560109D02*
X1158765D01*
X1160987Y1558691D01*
Y1560607D01*
G01X1161865Y1562749D02*
X1161813Y1563017D01*
X1161658Y1563324D01*
X1161400Y1563516D01*
X1161038Y1563592D01*
X1160677Y1563516D01*
X1160367Y1563286D01*
X1160212Y1562941D01*
Y1562557D01*
X1160108Y1562327D01*
X1159850Y1562136D01*
X1159488Y1562059D01*
X1159127Y1562174D01*
X1158868Y1562442D01*
X1158765Y1562749D01*
X1158868Y1563056D01*
X1159127Y1563324D01*
X1159488Y1563439D01*
X1159850Y1563362D01*
X1160108Y1563171D01*
X1160212Y1562941D01*
Y1562557D01*
X1160367Y1562212D01*
X1160677Y1561982D01*
X1161038Y1561906D01*
X1161400Y1561982D01*
X1161658Y1562174D01*
X1161813Y1562481D01*
X1161865Y1562749D01*
G01X1165615Y1583342D02*
Y1601058D01*
G01X1169023Y1583342D02*
X1165615D01*
G01Y1601058D02*
X1169023D01*
G01X1162224Y1671073D02*
X1164446D01*
X1164911Y1671226D01*
X1165221Y1671533D01*
X1165324Y1671916D01*
X1165221Y1672299D01*
X1164911Y1672606D01*
X1164446Y1672759D01*
X1162224D01*
G01X1165324Y1675016D02*
X1162224D01*
X1162844Y1674556D01*
G01X1165324D02*
Y1675476D01*
G01Y1678116D02*
X1162224D01*
X1162844Y1677656D01*
G01X1165324D02*
Y1678576D01*
G01X1166844Y1665195D02*
X1186530D01*
G01X1166844Y1679595D02*
Y1665195D01*
G01X1186530Y1679595D02*
X1166844D01*
G01X1178422Y-28151D02*
Y-11871D01*
X1188022D01*
Y-28151D01*
X1178422D01*
G01Y-8151D02*
Y8129D01*
X1188022D01*
Y-8151D01*
X1178422D01*
G01Y11849D02*
Y28129D01*
X1188022D01*
Y11849D01*
X1178422D01*
G01X1183287Y63115D02*
Y59915D01*
G01X1177087D02*
Y63115D01*
G01X1183287Y59915D02*
X1177087D01*
G01X1183287Y58615D02*
Y55415D01*
G01X1177087Y58615D02*
X1183287D01*
G01X1177087Y55415D02*
Y58615D01*
G01X1183287Y55415D02*
X1177087D01*
G01X1183307Y54415D02*
Y51215D01*
G01X1177107Y54415D02*
X1183307D01*
G01X1177107Y51215D02*
Y54415D01*
G01X1183307Y51215D02*
X1177107D01*
G01X1172493Y50843D02*
Y70529D01*
G01X1177087Y63115D02*
X1183287D01*
G01X1190244Y73678D02*
X1181582D01*
G01D02*
Y84172D01*
G01X1178944Y73691D02*
Y85805D01*
G01X1173436Y70683D02*
Y68461D01*
X1173589Y67996D01*
X1173896Y67686D01*
X1174279Y67583D01*
X1174662Y67686D01*
X1174969Y67996D01*
X1175122Y68461D01*
Y70683D01*
G01X1176651Y70166D02*
X1176881Y70476D01*
X1177149Y70631D01*
X1177456Y70683D01*
X1177839Y70580D01*
X1178107Y70321D01*
X1178184Y70011D01*
X1178146Y69701D01*
X1177992Y69443D01*
X1177226Y68926D01*
X1176881Y68565D01*
X1176651Y68048D01*
X1176574Y67583D01*
X1178184D01*
G01X1180402D02*
X1180479Y68255D01*
X1180594Y68823D01*
X1180747Y69340D01*
X1180939Y69908D01*
X1181246Y70683D01*
X1179712D01*
G01X1183579Y67583D02*
Y70683D01*
X1183119Y70063D01*
G01Y67583D02*
X1184039D01*
G01X1184388Y88725D02*
X1190588D01*
G01Y85525D02*
X1184388D01*
G01D02*
Y88725D01*
G01X1176529Y91156D02*
Y87956D01*
G01D02*
X1170329D01*
G01D02*
Y91156D01*
G01X1190588Y89525D02*
X1184388D01*
G01D02*
Y92725D01*
G01X1181582Y84172D02*
X1190244D01*
G01X1170329Y91156D02*
X1176529D01*
G01X1170329Y95156D02*
X1176529D01*
G01D02*
Y91956D01*
G01D02*
X1170329D01*
G01D02*
Y95156D01*
G01X1184388Y92725D02*
X1190588D01*
G01X1178091Y97464D02*
X1184291D01*
G01D02*
Y94264D01*
G01D02*
X1178091D01*
G01D02*
Y97464D01*
G01X1189687Y98094D02*
X1183487D01*
G01D02*
Y101294D01*
G01D02*
X1189687D01*
G01X1181768Y198759D02*
X1181960Y198449D01*
X1182190Y198242D01*
X1182458Y198139D01*
X1182765Y198242D01*
X1182995Y198449D01*
X1183225Y198759D01*
X1183302Y199172D01*
Y201239D01*
G01X1184907Y199431D02*
X1185175Y199792D01*
X1185405Y199999D01*
X1185712Y200102D01*
X1185980Y199999D01*
X1186172Y199792D01*
X1186325Y199482D01*
X1186363Y199121D01*
X1186325Y198811D01*
X1186172Y198501D01*
X1185942Y198242D01*
X1185673Y198139D01*
X1185367Y198242D01*
X1185098Y198552D01*
X1184945Y199017D01*
X1184907Y199534D01*
X1184983Y200206D01*
X1185098Y200567D01*
X1185290Y200929D01*
X1185558Y201187D01*
X1185827Y201239D01*
X1186095Y201136D01*
X1186287Y200877D01*
G01X1185600Y430525D02*
Y424325D01*
X1182400D01*
Y430525D01*
X1185600D01*
G01X1173600Y432100D02*
Y425900D01*
X1170400D01*
Y432100D01*
X1173600D01*
G01X1181600D02*
Y425900D01*
X1178400D01*
Y432100D01*
X1181600D01*
G01X1177600D02*
Y425900D01*
X1174400D01*
Y432100D01*
X1177600D01*
G01X1174306Y443941D02*
Y440741D01*
G01Y449441D02*
Y446241D01*
G01X1182449Y460090D02*
X1179249D01*
G01D02*
Y466290D01*
G01X1182449D02*
Y460090D01*
G01X1174306Y465941D02*
Y462741D01*
G01Y454941D02*
Y451741D01*
G01Y460441D02*
Y457241D01*
G01X1179940Y468065D02*
X1176740D01*
G01D02*
Y474265D01*
G01D02*
X1179940D01*
G01D02*
Y468065D01*
G01X1179249Y466290D02*
X1182449D01*
G01X1174306Y471441D02*
Y468241D01*
G01Y483291D02*
Y480091D01*
G01X1192262Y577265D02*
X1184122D01*
G01D02*
Y587379D01*
G01X1189792Y572722D02*
X1183592D01*
G01D02*
Y575922D01*
G01D02*
X1189792D01*
G01X1173632Y582202D02*
Y579002D01*
G01X1184122Y587379D02*
X1192262D01*
G01X1173692Y586222D02*
Y583022D01*
G01X1185385Y602467D02*
Y599367D01*
G01X1184503Y602467D02*
X1186267D01*
G01X1187718Y599367D02*
Y602467D01*
X1188638D01*
X1188945Y602312D01*
X1189175Y601950D01*
X1189252Y601537D01*
X1189175Y601124D01*
X1188983Y600814D01*
X1188638Y600659D01*
X1187718D01*
G01X1192045Y599367D02*
Y602467D01*
X1190627Y600245D01*
X1192543D01*
G01X1185435Y607657D02*
Y604557D01*
G01X1184553Y607657D02*
X1186317D01*
G01X1187768Y604557D02*
Y607657D01*
X1188688D01*
X1188995Y607502D01*
X1189225Y607140D01*
X1189302Y606727D01*
X1189225Y606314D01*
X1189033Y606004D01*
X1188688Y605849D01*
X1187768D01*
G01X1190983Y604919D02*
X1191252Y604660D01*
X1191558Y604557D01*
X1191865Y604660D01*
X1192133Y604970D01*
X1192325Y605435D01*
X1192402Y605900D01*
Y606469D01*
X1192325Y606934D01*
X1192133Y607347D01*
X1191903Y607554D01*
X1191635Y607657D01*
X1191328Y607554D01*
X1191098Y607347D01*
X1190945Y607037D01*
X1190868Y606624D01*
X1190945Y606262D01*
X1191137Y605900D01*
X1191367Y605694D01*
X1191635Y605642D01*
X1191942Y605745D01*
X1192172Y606004D01*
X1192402Y606469D01*
G01X1177172Y682595D02*
X1177364Y682285D01*
X1177594Y682078D01*
X1177862Y681975D01*
X1178169Y682078D01*
X1178399Y682285D01*
X1178629Y682595D01*
X1178706Y683008D01*
Y685075D01*
G01X1181039Y681975D02*
Y685075D01*
X1180579Y684455D01*
G01Y681975D02*
X1181499D01*
G01X1183296Y682440D02*
X1183526Y682182D01*
X1183794Y682027D01*
X1184139Y681975D01*
X1184484Y682078D01*
X1184752Y682285D01*
X1184944Y682647D01*
X1184982Y683060D01*
X1184906Y683473D01*
X1184714Y683732D01*
X1184446Y683938D01*
X1184177Y683990D01*
X1183909Y683938D01*
X1183564Y683732D01*
X1183679Y685075D01*
X1184714D01*
G01X1171096Y1354797D02*
Y1351597D01*
G01X1172696Y1353214D02*
Y1355814D01*
G01X1173489Y1353214D02*
X1172696D01*
G01Y1362425D02*
Y1364123D01*
G01X1173533Y1387249D02*
Y1381049D01*
G01D02*
X1170333D01*
G01Y1387249D02*
X1173533D01*
G01X1170333Y1381049D02*
Y1387249D01*
G01X1187128Y1380239D02*
X1183928D01*
G01Y1386439D02*
X1187128D01*
G01X1183928Y1380239D02*
Y1386439D01*
G01X1174303Y1383943D02*
Y1387143D01*
G01X1180503Y1383943D02*
X1174303D01*
G01X1180503Y1387143D02*
Y1383943D01*
G01X1174303Y1387143D02*
X1180503D01*
G01X1172696Y1376836D02*
X1173704D01*
G01X1172696Y1374982D02*
Y1376836D01*
G01X1170883Y1393500D02*
Y1396600D01*
X1171803D01*
X1172110Y1396445D01*
X1172340Y1396083D01*
X1172417Y1395670D01*
X1172340Y1395257D01*
X1172148Y1394947D01*
X1171803Y1394792D01*
X1170883D01*
G01X1173907Y1396600D02*
Y1394378D01*
X1174060Y1393913D01*
X1174367Y1393603D01*
X1174750Y1393500D01*
X1175133Y1393603D01*
X1175440Y1393913D01*
X1175593Y1394378D01*
Y1396600D01*
G01X1177850Y1393500D02*
Y1396600D01*
X1177390Y1395980D01*
G01Y1393500D02*
X1178310D01*
G01X1180873D02*
X1180950Y1394172D01*
X1181065Y1394740D01*
X1181218Y1395257D01*
X1181410Y1395825D01*
X1181717Y1396600D01*
X1180183D01*
G01X1170622Y1388997D02*
Y1392097D01*
X1171542D01*
X1171849Y1391942D01*
X1172079Y1391580D01*
X1172156Y1391167D01*
X1172079Y1390754D01*
X1171887Y1390444D01*
X1171542Y1390289D01*
X1170622D01*
G01X1173722Y1392097D02*
Y1388997D01*
X1175256D01*
G01X1177589D02*
Y1392097D01*
X1177129Y1391477D01*
G01Y1388997D02*
X1178049D01*
G01X1180612D02*
X1180689Y1389669D01*
X1180804Y1390237D01*
X1180957Y1390754D01*
X1181149Y1391322D01*
X1181456Y1392097D01*
X1179922D01*
G01X1185700Y1431400D02*
X1179500D01*
G01D02*
Y1434600D01*
G01D02*
X1185700D01*
G01X1170412Y1450906D02*
Y1439094D01*
G01X1184770Y1593483D02*
X1187870D01*
Y1595017D01*
G01Y1597350D02*
X1184770D01*
X1185390Y1596890D01*
G01X1187870D02*
Y1597810D01*
G01X1185287Y1599722D02*
X1184977Y1599952D01*
X1184822Y1600220D01*
X1184770Y1600527D01*
X1184873Y1600910D01*
X1185132Y1601178D01*
X1185442Y1601255D01*
X1185752Y1601217D01*
X1186010Y1601063D01*
X1186527Y1600297D01*
X1186888Y1599952D01*
X1187405Y1599722D01*
X1187870Y1599645D01*
Y1601255D01*
G01X1183331Y1601058D02*
Y1583342D01*
G01D02*
X1179923D01*
G01X1178455Y1603190D02*
Y1607790D01*
G01X1188655Y1603190D02*
X1178455D01*
G01Y1607790D02*
X1188655D01*
G01X1184255Y1603190D02*
Y1607790D01*
G01X1194455Y1603190D02*
X1184255D01*
G01Y1607790D02*
X1194455D01*
G01X1179923Y1601058D02*
X1183331D01*
G01X1186530Y1668152D02*
X1182287Y1672395D01*
G01D02*
X1186530Y1676638D01*
G01X1180876Y1701089D02*
X1180569Y1701141D01*
X1180301Y1701347D01*
X1180071Y1701657D01*
X1179918Y1702019D01*
X1179841Y1702432D01*
Y1702846D01*
X1179918Y1703259D01*
X1180071Y1703621D01*
X1180301Y1703931D01*
X1180569Y1704137D01*
X1180876Y1704189D01*
X1181183Y1704137D01*
X1181451Y1703931D01*
X1181681Y1703621D01*
X1181834Y1703259D01*
X1181911Y1702846D01*
Y1702432D01*
X1181834Y1702019D01*
X1181681Y1701657D01*
X1181451Y1701347D01*
X1181183Y1701141D01*
X1180876Y1701089D01*
G01X1181183Y1701916D02*
X1181643Y1701089D01*
G01X1183976D02*
Y1704189D01*
X1183516Y1703569D01*
G01Y1701089D02*
X1184436D01*
G01X1187076Y1704189D02*
X1186769Y1704086D01*
X1186539Y1703827D01*
X1186386Y1703517D01*
X1186271Y1703104D01*
X1186233Y1702639D01*
X1186271Y1702174D01*
X1186386Y1701761D01*
X1186539Y1701451D01*
X1186769Y1701192D01*
X1187076Y1701089D01*
X1187383Y1701192D01*
X1187613Y1701451D01*
X1187766Y1701761D01*
X1187881Y1702174D01*
X1187919Y1702639D01*
X1187881Y1703104D01*
X1187766Y1703517D01*
X1187613Y1703827D01*
X1187383Y1704086D01*
X1187076Y1704189D01*
G01X1190636Y1701089D02*
Y1704189D01*
X1189218Y1701967D01*
X1191134D01*
G01X1201378Y-24815D02*
X1201688Y-24623D01*
X1201895Y-24393D01*
X1201998Y-24125D01*
X1201895Y-23818D01*
X1201688Y-23588D01*
X1201378Y-23358D01*
X1200965Y-23281D01*
X1198898D01*
G01X1201998Y-20948D02*
X1201946Y-20680D01*
X1201791Y-20373D01*
X1201533Y-20181D01*
X1201171Y-20105D01*
X1200810Y-20181D01*
X1200500Y-20411D01*
X1200345Y-20756D01*
Y-21140D01*
X1200241Y-21370D01*
X1199983Y-21561D01*
X1199621Y-21638D01*
X1199260Y-21523D01*
X1199001Y-21255D01*
X1198898Y-20948D01*
X1199001Y-20641D01*
X1199260Y-20373D01*
X1199621Y-20258D01*
X1199983Y-20335D01*
X1200241Y-20526D01*
X1200345Y-20756D01*
Y-21140D01*
X1200500Y-21485D01*
X1200810Y-21715D01*
X1201171Y-21791D01*
X1201533Y-21715D01*
X1201791Y-21523D01*
X1201946Y-21216D01*
X1201998Y-20948D01*
G01X1201533Y-18691D02*
X1201791Y-18461D01*
X1201946Y-18193D01*
X1201998Y-17848D01*
X1201895Y-17503D01*
X1201688Y-17235D01*
X1201326Y-17043D01*
X1200913Y-17005D01*
X1200500Y-17081D01*
X1200241Y-17273D01*
X1200035Y-17541D01*
X1199983Y-17810D01*
X1200035Y-18078D01*
X1200241Y-18423D01*
X1198898Y-18308D01*
Y-17273D01*
G01X1201126Y-4605D02*
X1201436Y-4413D01*
X1201643Y-4183D01*
X1201746Y-3915D01*
X1201643Y-3608D01*
X1201436Y-3378D01*
X1201126Y-3148D01*
X1200713Y-3071D01*
X1198646D01*
G01X1201746Y-738D02*
X1201694Y-470D01*
X1201539Y-163D01*
X1201281Y29D01*
X1200919Y105D01*
X1200558Y29D01*
X1200248Y-201D01*
X1200093Y-546D01*
Y-930D01*
X1199989Y-1160D01*
X1199731Y-1351D01*
X1199369Y-1428D01*
X1199008Y-1313D01*
X1198749Y-1045D01*
X1198646Y-738D01*
X1198749Y-431D01*
X1199008Y-163D01*
X1199369Y-48D01*
X1199731Y-125D01*
X1199989Y-316D01*
X1200093Y-546D01*
Y-930D01*
X1200248Y-1275D01*
X1200558Y-1505D01*
X1200919Y-1581D01*
X1201281Y-1505D01*
X1201539Y-1313D01*
X1201694Y-1006D01*
X1201746Y-738D01*
G01Y2362D02*
X1198646D01*
X1199266Y1902D01*
G01X1201746D02*
Y2822D01*
G01X1201093Y16128D02*
X1201403Y16320D01*
X1201610Y16550D01*
X1201713Y16818D01*
X1201610Y17125D01*
X1201403Y17355D01*
X1201093Y17585D01*
X1200680Y17662D01*
X1198613D01*
G01X1201713Y19995D02*
X1201661Y20263D01*
X1201506Y20570D01*
X1201248Y20762D01*
X1200886Y20838D01*
X1200525Y20762D01*
X1200215Y20532D01*
X1200060Y20187D01*
Y19803D01*
X1199956Y19573D01*
X1199698Y19382D01*
X1199336Y19305D01*
X1198975Y19420D01*
X1198716Y19688D01*
X1198613Y19995D01*
X1198716Y20302D01*
X1198975Y20570D01*
X1199336Y20685D01*
X1199698Y20608D01*
X1199956Y20417D01*
X1200060Y20187D01*
Y19803D01*
X1200215Y19458D01*
X1200525Y19228D01*
X1200886Y19152D01*
X1201248Y19228D01*
X1201506Y19420D01*
X1201661Y19727D01*
X1201713Y19995D01*
G01Y23555D02*
X1198613D01*
X1200835Y22137D01*
Y24053D01*
G01X1197387Y63115D02*
Y59915D01*
G01X1191187D02*
Y63115D01*
G01X1197387Y59915D02*
X1191187D01*
G01X1197487Y58615D02*
Y55415D01*
G01X1191287D02*
Y58615D01*
G01X1197487Y55415D02*
X1191287D01*
G01Y58615D02*
X1197487D01*
G01X1197407Y54415D02*
Y51215D01*
G01X1191207D02*
Y54415D01*
G01X1197407Y51215D02*
X1191207D01*
G01Y54415D02*
X1197407D01*
G01X1191187Y63115D02*
X1197387D01*
G01X1195801Y74127D02*
X1195749Y73820D01*
X1195543Y73552D01*
X1195233Y73322D01*
X1194871Y73169D01*
X1194458Y73092D01*
X1194044D01*
X1193631Y73169D01*
X1193269Y73322D01*
X1192959Y73552D01*
X1192753Y73820D01*
X1192701Y74127D01*
X1192753Y74434D01*
X1192959Y74702D01*
X1193269Y74932D01*
X1193631Y75085D01*
X1194044Y75162D01*
X1194458D01*
X1194871Y75085D01*
X1195233Y74932D01*
X1195543Y74702D01*
X1195749Y74434D01*
X1195801Y74127D01*
G01X1194974Y74434D02*
X1195801Y74894D01*
G01Y77227D02*
X1195749Y77495D01*
X1195594Y77802D01*
X1195336Y77994D01*
X1194974Y78070D01*
X1194613Y77994D01*
X1194303Y77764D01*
X1194148Y77419D01*
Y77035D01*
X1194044Y76805D01*
X1193786Y76614D01*
X1193424Y76537D01*
X1193063Y76652D01*
X1192804Y76920D01*
X1192701Y77227D01*
X1192804Y77534D01*
X1193063Y77802D01*
X1193424Y77917D01*
X1193786Y77840D01*
X1194044Y77649D01*
X1194148Y77419D01*
Y77035D01*
X1194303Y76690D01*
X1194613Y76460D01*
X1194974Y76384D01*
X1195336Y76460D01*
X1195594Y76652D01*
X1195749Y76959D01*
X1195801Y77227D01*
G01X1190244Y77025D02*
Y73678D01*
G01X1190588Y88725D02*
Y85525D01*
G01X1193888Y86450D02*
Y92650D01*
G01X1197088D02*
Y86450D01*
G01D02*
X1193888D01*
G01X1190588Y92725D02*
Y89525D01*
G01X1190244Y84172D02*
Y80825D01*
G01D02*
X1188044Y78925D01*
G01D02*
X1190244Y77025D01*
G01X1193888Y92650D02*
X1197088D01*
G01X1189687Y101294D02*
Y98094D01*
G01X1193725Y109742D02*
Y107520D01*
X1193878Y107055D01*
X1194185Y106745D01*
X1194568Y106642D01*
X1194951Y106745D01*
X1195258Y107055D01*
X1195411Y107520D01*
Y109742D01*
G01X1197016Y107004D02*
X1197285Y106745D01*
X1197591Y106642D01*
X1197898Y106745D01*
X1198166Y107055D01*
X1198358Y107520D01*
X1198435Y107985D01*
Y108554D01*
X1198358Y109019D01*
X1198166Y109432D01*
X1197936Y109639D01*
X1197668Y109742D01*
X1197361Y109639D01*
X1197131Y109432D01*
X1196978Y109122D01*
X1196901Y108709D01*
X1196978Y108347D01*
X1197170Y107985D01*
X1197400Y107779D01*
X1197668Y107727D01*
X1197975Y107830D01*
X1198205Y108089D01*
X1198435Y108554D01*
G01X1199018Y105107D02*
X1200518Y103336D01*
G01X1193887Y105107D02*
X1199018D01*
G01X1193887Y96643D02*
Y105107D01*
G01X1207149Y96643D02*
X1193887D01*
G01X1196802Y166587D02*
Y163387D01*
G01X1190602D02*
Y166587D01*
G01X1196802Y163387D02*
X1190602D01*
G01X1196802Y162587D02*
Y159387D01*
G01X1190602D02*
Y162587D01*
G01X1196802Y159387D02*
X1190602D01*
G01Y162587D02*
X1196802D01*
G01Y178787D02*
Y175587D01*
G01X1190602Y178787D02*
X1196802D01*
G01X1190602Y175587D02*
Y178787D01*
G01X1196802Y175587D02*
X1190602D01*
G01X1196802Y174787D02*
Y171587D01*
G01X1190602Y174787D02*
X1196802D01*
G01X1190602Y171587D02*
Y174787D01*
G01X1196802Y171587D02*
X1190602D01*
G01Y166587D02*
X1196802D01*
G01X1188007Y180551D02*
Y185151D01*
G01X1198007Y180551D02*
Y185151D01*
G01X1188007Y185051D02*
Y185151D01*
X1198007D01*
G01Y180551D02*
X1188007D01*
G01X1199114Y222008D02*
Y202402D01*
G01X1193027Y433802D02*
Y430602D01*
G01X1186827Y433802D02*
X1193027D01*
G01X1186827Y430602D02*
Y433802D01*
G01X1193027Y430602D02*
X1186827D01*
G01X1193027Y449802D02*
Y446602D01*
G01X1186827D02*
Y449802D01*
G01X1193027Y446602D02*
X1186827D01*
G01X1193027Y441802D02*
Y438602D01*
G01X1186827Y441802D02*
X1193027D01*
G01X1186827Y438602D02*
Y441802D01*
G01X1193027Y438602D02*
X1186827D01*
G01Y434602D02*
Y437802D01*
G01X1193027Y434602D02*
X1186827D01*
G01X1193027Y437802D02*
Y434602D01*
G01X1186827Y437802D02*
X1193027D01*
G01X1186827Y442602D02*
Y445802D01*
G01X1193027Y442602D02*
X1186827D01*
G01X1193027Y445802D02*
Y442602D01*
G01X1186827Y445802D02*
X1193027D01*
G01Y458602D02*
X1186827D01*
G01D02*
Y461802D01*
G01D02*
X1193027D01*
G01D02*
Y458602D01*
G01X1198327Y461802D02*
X1204527D01*
G01Y458602D02*
X1198327D01*
G01D02*
Y461802D01*
G01X1186827Y449802D02*
X1193027D01*
G01X1186827Y450602D02*
Y453802D01*
G01X1193027Y450602D02*
X1186827D01*
G01X1193027Y453802D02*
Y450602D01*
G01X1186827Y453802D02*
X1193027D01*
G01X1193147Y468792D02*
X1186947D01*
G01D02*
Y471992D01*
G01D02*
X1193147D01*
G01D02*
Y468792D01*
G01X1193087Y463672D02*
X1186887D01*
G01D02*
Y466872D01*
G01D02*
X1193087D01*
G01D02*
Y463672D01*
G01X1198387Y466872D02*
X1204587D01*
G01Y463672D02*
X1198387D01*
G01D02*
Y466872D01*
G01X1198463Y471976D02*
X1204663D01*
G01Y468776D02*
X1198463D01*
G01D02*
Y471976D01*
G01X1194097Y564761D02*
X1196319D01*
X1196784Y564914D01*
X1197094Y565221D01*
X1197197Y565604D01*
X1197094Y565987D01*
X1196784Y566294D01*
X1196319Y566447D01*
X1194097D01*
G01X1197197Y568704D02*
X1194097D01*
X1194717Y568244D01*
G01X1197197D02*
Y569164D01*
G01X1194097Y571804D02*
X1194200Y571497D01*
X1194459Y571267D01*
X1194769Y571114D01*
X1195182Y570999D01*
X1195647Y570961D01*
X1196112Y570999D01*
X1196525Y571114D01*
X1196835Y571267D01*
X1197094Y571497D01*
X1197197Y571804D01*
X1197094Y572111D01*
X1196835Y572341D01*
X1196525Y572494D01*
X1196112Y572609D01*
X1195647Y572647D01*
X1195182Y572609D01*
X1194769Y572494D01*
X1194459Y572341D01*
X1194200Y572111D01*
X1194097Y571804D01*
G01X1196732Y574061D02*
X1196990Y574291D01*
X1197145Y574559D01*
X1197197Y574904D01*
X1197094Y575249D01*
X1196887Y575517D01*
X1196525Y575709D01*
X1196112Y575747D01*
X1195699Y575671D01*
X1195440Y575479D01*
X1195234Y575211D01*
X1195182Y574942D01*
X1195234Y574674D01*
X1195440Y574329D01*
X1194097Y574444D01*
Y575479D01*
G01X1192262Y587379D02*
Y577265D01*
G01X1189792Y575922D02*
Y572722D01*
G01X1204212Y580843D02*
X1198012D01*
G01D02*
Y584043D01*
G01X1204212Y585843D02*
X1198012D01*
G01D02*
Y589043D01*
G01D02*
X1204212D01*
G01X1198012Y584043D02*
X1204212D01*
G01X1189245Y687244D02*
Y1303850D01*
G01X1214835Y687244D02*
X1189245D01*
G01X1185134Y1303850D02*
Y687244D01*
G01X1214835Y720709D02*
X1189245D01*
G01X1214835Y1291575D02*
X1189245D01*
G01X1197767Y1306689D02*
Y1349997D01*
G01X1192426Y1306689D02*
X1197767D01*
G01X1197696Y1354797D02*
X1203896D01*
G01X1197696Y1351597D02*
Y1354797D01*
G01X1203896Y1351597D02*
X1197696D01*
G01X1202462Y1355097D02*
X1199262D01*
G01D02*
Y1361297D01*
G01X1192382Y1353214D02*
X1191589D01*
G01X1192382Y1355814D02*
Y1353214D01*
G01X1197767Y1349997D02*
X1192426D01*
G01X1195248Y1368716D02*
X1198448D01*
G01X1195248Y1362516D02*
Y1368716D01*
G01X1198448Y1362516D02*
X1195248D01*
G01X1198448Y1368716D02*
Y1362516D01*
G01X1202439Y1372418D02*
X1199239D01*
G01D02*
Y1378618D01*
G01Y1368118D02*
X1202439D01*
G01X1199239Y1361918D02*
Y1368118D01*
G01X1202439Y1361918D02*
X1199239D01*
G01X1199262Y1361297D02*
X1202462D01*
G01X1199239Y1378618D02*
X1202439D01*
G01X1196015Y1380488D02*
Y1383688D01*
G01X1202215Y1380488D02*
X1196015D01*
G01Y1383688D02*
X1202215D01*
G01X1191170Y1386439D02*
Y1380239D01*
G01X1187970Y1386439D02*
X1191170D01*
G01X1187970Y1380239D02*
Y1386439D01*
G01X1191170Y1380239D02*
X1187970D01*
G01X1187128Y1386439D02*
Y1380239D01*
G01X1192382Y1376836D02*
Y1374645D01*
G01X1191649Y1376836D02*
X1192382D01*
G01X1191383Y1386500D02*
Y1389600D01*
X1192303D01*
X1192610Y1389445D01*
X1192840Y1389083D01*
X1192917Y1388670D01*
X1192840Y1388257D01*
X1192648Y1387947D01*
X1192303Y1387792D01*
X1191383D01*
G01X1194483Y1389600D02*
Y1386500D01*
X1196017D01*
G01X1198350D02*
Y1389600D01*
X1197890Y1388980D01*
G01Y1386500D02*
X1198810D01*
G01X1200607Y1387120D02*
X1200837Y1386758D01*
X1201143Y1386552D01*
X1201488Y1386500D01*
X1201795Y1386552D01*
X1202102Y1386810D01*
X1202293Y1387120D01*
X1202332Y1387430D01*
X1202255Y1387792D01*
X1201987Y1388050D01*
X1201718Y1388153D01*
X1201373D01*
G01X1201718D02*
X1201948Y1388308D01*
X1202140Y1388567D01*
X1202217Y1388877D01*
X1202140Y1389187D01*
X1201948Y1389445D01*
X1201603Y1389600D01*
X1201258Y1389548D01*
X1200913Y1389342D01*
G01X1192600Y1399400D02*
X1186400D01*
G01Y1402600D02*
X1192600D01*
G01D02*
Y1399400D01*
G01X1186400D02*
Y1402600D01*
G01X1192600Y1394900D02*
X1186400D01*
G01Y1398100D02*
X1192600D01*
G01D02*
Y1394900D01*
G01X1186400D02*
Y1398100D01*
G01X1195400D02*
X1201600D01*
G01Y1394900D02*
X1195400D01*
G01D02*
Y1398100D01*
G01Y1402600D02*
X1201600D01*
G01Y1399400D02*
X1195400D01*
G01D02*
Y1402600D01*
G01X1191383Y1390500D02*
Y1393600D01*
X1192303D01*
X1192610Y1393445D01*
X1192840Y1393083D01*
X1192917Y1392670D01*
X1192840Y1392257D01*
X1192648Y1391947D01*
X1192303Y1391792D01*
X1191383D01*
G01X1194407Y1393600D02*
Y1391378D01*
X1194560Y1390913D01*
X1194867Y1390603D01*
X1195250Y1390500D01*
X1195633Y1390603D01*
X1195940Y1390913D01*
X1196093Y1391378D01*
Y1393600D01*
G01X1198350Y1390500D02*
Y1393600D01*
X1197890Y1392980D01*
G01Y1390500D02*
X1198810D01*
G01X1201910D02*
Y1393600D01*
X1200492Y1391378D01*
X1202408D01*
G01X1192600Y1403900D02*
X1186400D01*
G01X1192600Y1407100D02*
Y1403900D01*
G01X1186400Y1407100D02*
X1192600D01*
G01X1186400Y1403900D02*
Y1407100D01*
G01X1192600Y1408400D02*
X1186400D01*
G01Y1411600D02*
X1192600D01*
G01D02*
Y1408400D01*
G01X1186400D02*
Y1411600D01*
G01X1201600Y1417400D02*
X1195400D01*
G01D02*
Y1420600D01*
G01X1201600Y1412900D02*
X1195400D01*
G01D02*
Y1416100D01*
G01D02*
X1201600D01*
G01X1195400Y1408400D02*
Y1411600D01*
G01X1201600Y1408400D02*
X1195400D01*
G01Y1411600D02*
X1201600D01*
G01X1195400Y1403900D02*
Y1407100D01*
G01X1201600Y1403900D02*
X1195400D01*
G01Y1407100D02*
X1201600D01*
G01X1195400Y1420600D02*
X1201600D01*
G01Y1426900D02*
X1195400D01*
G01D02*
Y1430100D01*
G01D02*
X1201600D01*
G01Y1431400D02*
X1195400D01*
G01D02*
Y1434600D01*
G01X1185700D02*
Y1431400D01*
G01X1201600Y1422400D02*
X1195400D01*
G01D02*
Y1425600D01*
G01D02*
X1201600D01*
G01X1186500Y1430100D02*
X1192700D01*
G01D02*
Y1426900D01*
G01D02*
X1186500D01*
G01D02*
Y1430100D01*
G01X1192700Y1434600D02*
Y1431400D01*
G01D02*
X1186500D01*
G01D02*
Y1434600D01*
G01X1192600Y1435900D02*
X1186400D01*
G01D02*
Y1439100D01*
G01X1192600D02*
Y1435900D01*
G01X1186400Y1439100D02*
X1192600D01*
G01X1195400Y1434600D02*
X1201600D01*
G01Y1435900D02*
X1195400D01*
G01D02*
Y1439100D01*
G01D02*
X1201600D01*
G01Y1445900D02*
X1195400D01*
G01D02*
Y1449100D01*
G01Y1444100D02*
X1201600D01*
G01Y1440900D02*
X1195400D01*
G01D02*
Y1444100D01*
G01X1186500Y1434600D02*
X1192700D01*
G01X1195400Y1449100D02*
X1201600D01*
G01X1185306Y1540451D02*
Y1557400D01*
G01X1191900Y1540451D02*
X1185306D01*
G01Y1561100D02*
Y1575491D01*
G01D02*
X1191400D01*
G01X1190306Y1595952D02*
Y1601952D01*
G01X1202306Y1595952D02*
X1190306D01*
G01X1190332Y1595098D02*
X1202332D01*
G01X1190332Y1589098D02*
Y1595098D01*
G01X1202332Y1589098D02*
X1190332D01*
G01X1188655Y1607790D02*
Y1603190D01*
G01X1194455Y1607790D02*
Y1603190D01*
G01X1190306Y1601952D02*
X1202306D01*
G01X1195911Y1603454D02*
Y1615454D01*
G01X1201911Y1603454D02*
X1195911D01*
G01Y1615454D02*
X1201911D01*
G01X1186530Y1665195D02*
Y1668152D01*
G01X1188255Y1671450D02*
Y1674650D01*
G01X1194455Y1671450D02*
X1188255D01*
G01X1194455Y1674650D02*
Y1671450D01*
G01X1188255Y1674650D02*
X1194455D01*
G01X1199502Y1686897D02*
Y1683550D01*
G01Y1679750D02*
Y1676403D01*
G01X1197302Y1681650D02*
X1199502Y1679750D01*
G01Y1683550D02*
X1197302Y1681650D01*
G01X1190840Y1676403D02*
Y1686897D01*
G01X1199502Y1676403D02*
X1190840D01*
G01X1186530Y1676638D02*
Y1679595D01*
G01X1187937Y1695450D02*
X1194137D01*
G01D02*
Y1692250D01*
G01X1187937D02*
Y1695450D01*
G01X1194137Y1692250D02*
X1187937D01*
G01Y1696250D02*
Y1699450D01*
G01X1194137Y1696250D02*
X1187937D01*
G01X1194137Y1699450D02*
Y1696250D01*
G01X1187937Y1699450D02*
X1194137D01*
G01X1194937Y1696250D02*
Y1699450D01*
G01X1201137Y1696250D02*
X1194937D01*
G01Y1699450D02*
X1201137D01*
G01X1194937Y1695450D02*
X1201137D01*
G01X1194937Y1692250D02*
Y1695450D01*
G01X1201137Y1692250D02*
X1194937D01*
G01X1197287Y1691450D02*
Y1688250D01*
G01X1191087Y1691450D02*
X1197287D01*
G01X1191087Y1688250D02*
Y1691450D01*
G01X1197287Y1688250D02*
X1191087D01*
G01X1190840Y1686897D02*
X1199502D01*
G01X1187807Y1710418D02*
Y1716618D01*
G01X1191007Y1710418D02*
X1187807D01*
G01X1191007Y1716618D02*
Y1710418D01*
G01X1193184Y1715227D02*
X1192877Y1715279D01*
X1192609Y1715485D01*
X1192379Y1715795D01*
X1192226Y1716157D01*
X1192149Y1716570D01*
Y1716984D01*
X1192226Y1717397D01*
X1192379Y1717759D01*
X1192609Y1718069D01*
X1192877Y1718275D01*
X1193184Y1718327D01*
X1193491Y1718275D01*
X1193759Y1718069D01*
X1193989Y1717759D01*
X1194142Y1717397D01*
X1194219Y1716984D01*
Y1716570D01*
X1194142Y1716157D01*
X1193989Y1715795D01*
X1193759Y1715485D01*
X1193491Y1715279D01*
X1193184Y1715227D01*
G01X1193491Y1716054D02*
X1193951Y1715227D01*
G01X1196284D02*
Y1718327D01*
X1195824Y1717707D01*
G01Y1715227D02*
X1196744D01*
G01X1198656Y1717810D02*
X1198886Y1718120D01*
X1199154Y1718275D01*
X1199461Y1718327D01*
X1199844Y1718224D01*
X1200112Y1717965D01*
X1200189Y1717655D01*
X1200151Y1717345D01*
X1199997Y1717087D01*
X1199231Y1716570D01*
X1198886Y1716209D01*
X1198656Y1715692D01*
X1198579Y1715227D01*
X1200189D01*
G01X1201832Y1715589D02*
X1202101Y1715330D01*
X1202407Y1715227D01*
X1202714Y1715330D01*
X1202982Y1715640D01*
X1203174Y1716105D01*
X1203251Y1716570D01*
Y1717139D01*
X1203174Y1717604D01*
X1202982Y1718017D01*
X1202752Y1718224D01*
X1202484Y1718327D01*
X1202177Y1718224D01*
X1201947Y1718017D01*
X1201794Y1717707D01*
X1201717Y1717294D01*
X1201794Y1716932D01*
X1201986Y1716570D01*
X1202216Y1716364D01*
X1202484Y1716312D01*
X1202791Y1716415D01*
X1203021Y1716674D01*
X1203251Y1717139D01*
G01X1192760Y1714033D02*
X1203254D01*
G01X1192760Y1705371D02*
Y1714033D01*
G01X1196107Y1705371D02*
X1192760D01*
G01X1198007Y1707571D02*
X1196107Y1705371D01*
G01X1199907D02*
X1198007Y1707571D01*
G01X1198377Y1730203D02*
Y1733403D01*
G01X1204577Y1730203D02*
X1198377D01*
G01X1187807Y1716618D02*
X1191007D01*
G01X1192807Y1728033D02*
X1203301D01*
G01X1192807Y1719371D02*
Y1728033D01*
G01X1196154Y1719371D02*
X1192807D01*
G01X1198054Y1721571D02*
X1196154Y1719371D01*
G01X1199954D02*
X1198054Y1721571D01*
G01X1198377Y1733403D02*
X1204577D01*
G01X1213981Y84246D02*
Y90446D01*
G01D02*
X1217181D01*
G01Y84246D02*
X1213981D01*
G01X1208481Y93246D02*
Y96446D01*
G01X1214681Y93246D02*
X1208481D01*
G01X1214681Y96446D02*
Y93246D01*
G01X1208481Y96446D02*
X1214681D01*
G01X1207149Y105107D02*
Y96643D01*
G01X1202018Y105107D02*
X1207149D01*
G01X1200518Y103336D02*
X1202018Y105107D01*
G01X1200656Y135466D02*
X1206856D01*
G01Y132266D02*
X1200656D01*
G01D02*
Y135466D01*
G01X1206856D02*
Y132266D01*
G01X1200656Y130348D02*
X1206856D01*
G01Y127148D02*
X1200656D01*
G01D02*
Y130348D01*
G01X1206856D02*
Y127148D01*
G01X1209424Y135638D02*
Y126976D01*
G01D02*
X1219938D01*
G01Y135638D02*
X1209424D01*
G01X1226693Y142739D02*
X1214693D01*
G01Y148739D02*
X1226693D01*
G01X1214693Y142739D02*
Y148739D01*
G01X1209388Y140274D02*
Y138052D01*
X1209541Y137587D01*
X1209848Y137277D01*
X1210231Y137174D01*
X1210614Y137277D01*
X1210921Y137587D01*
X1211074Y138052D01*
Y140274D01*
G01X1213331Y137174D02*
Y140274D01*
X1212871Y139654D01*
G01Y137174D02*
X1213791D01*
G01X1215703Y138466D02*
X1215971Y138827D01*
X1216201Y139034D01*
X1216508Y139137D01*
X1216776Y139034D01*
X1216968Y138827D01*
X1217121Y138517D01*
X1217159Y138156D01*
X1217121Y137846D01*
X1216968Y137536D01*
X1216738Y137277D01*
X1216469Y137174D01*
X1216163Y137277D01*
X1215894Y137587D01*
X1215741Y138052D01*
X1215703Y138569D01*
X1215779Y139241D01*
X1215894Y139602D01*
X1216086Y139964D01*
X1216354Y140222D01*
X1216623Y140274D01*
X1216891Y140171D01*
X1217083Y139912D01*
G01X1218803Y138466D02*
X1219071Y138827D01*
X1219301Y139034D01*
X1219608Y139137D01*
X1219876Y139034D01*
X1220068Y138827D01*
X1220221Y138517D01*
X1220259Y138156D01*
X1220221Y137846D01*
X1220068Y137536D01*
X1219838Y137277D01*
X1219569Y137174D01*
X1219263Y137277D01*
X1218994Y137587D01*
X1218841Y138052D01*
X1218803Y138569D01*
X1218879Y139241D01*
X1218994Y139602D01*
X1219186Y139964D01*
X1219454Y140222D01*
X1219723Y140274D01*
X1219991Y140171D01*
X1220183Y139912D01*
G01X1207112Y166587D02*
Y163387D01*
G01X1200912D02*
Y166587D01*
G01X1207112Y163387D02*
X1200912D01*
G01X1207112Y162587D02*
Y159387D01*
G01X1200912Y162587D02*
X1207112D01*
G01X1200912Y159387D02*
Y162587D01*
G01X1207112Y159387D02*
X1200912D01*
G01Y166587D02*
X1207112D01*
G01X1200912Y178787D02*
X1207112D01*
G01X1200912Y175587D02*
Y178787D01*
G01X1207112Y175587D02*
X1200912D01*
G01X1207112Y178787D02*
Y175587D01*
G01X1200912Y179587D02*
Y182787D01*
G01X1207112Y179587D02*
X1200912D01*
G01X1207112Y182787D02*
Y179587D01*
G01X1207143Y187342D02*
X1200943D01*
G01D02*
Y190542D01*
G01X1207143D02*
Y187342D01*
G01X1200943Y190542D02*
X1207143D01*
G01X1200912Y186787D02*
X1207112D01*
G01D02*
Y183587D01*
G01X1200912D02*
Y186787D01*
G01X1207112Y183587D02*
X1200912D01*
G01Y182787D02*
X1207112D01*
G01X1209827Y261515D02*
X1206727D01*
Y262281D01*
X1206882Y262588D01*
X1207089Y262818D01*
X1207399Y263010D01*
X1207760Y263163D01*
X1208277Y263201D01*
X1208794Y263163D01*
X1209155Y263010D01*
X1209465Y262818D01*
X1209672Y262588D01*
X1209827Y262281D01*
Y261515D01*
G01X1208535Y264730D02*
X1208174Y264998D01*
X1207967Y265228D01*
X1207864Y265535D01*
X1207967Y265803D01*
X1208174Y265995D01*
X1208484Y266148D01*
X1208845Y266186D01*
X1209155Y266148D01*
X1209465Y265995D01*
X1209724Y265765D01*
X1209827Y265496D01*
X1209724Y265190D01*
X1209414Y264921D01*
X1208949Y264768D01*
X1208432Y264730D01*
X1207760Y264806D01*
X1207399Y264921D01*
X1207037Y265113D01*
X1206779Y265381D01*
X1206727Y265650D01*
X1206830Y265918D01*
X1207089Y266110D01*
G01X1206727Y268558D02*
X1206830Y268251D01*
X1207089Y268021D01*
X1207399Y267868D01*
X1207812Y267753D01*
X1208277Y267715D01*
X1208742Y267753D01*
X1209155Y267868D01*
X1209465Y268021D01*
X1209724Y268251D01*
X1209827Y268558D01*
X1209724Y268865D01*
X1209465Y269095D01*
X1209155Y269248D01*
X1208742Y269363D01*
X1208277Y269401D01*
X1207812Y269363D01*
X1207399Y269248D01*
X1207089Y269095D01*
X1206830Y268865D01*
X1206727Y268558D01*
G01Y271658D02*
X1206830Y271351D01*
X1207089Y271121D01*
X1207399Y270968D01*
X1207812Y270853D01*
X1208277Y270815D01*
X1208742Y270853D01*
X1209155Y270968D01*
X1209465Y271121D01*
X1209724Y271351D01*
X1209827Y271658D01*
X1209724Y271965D01*
X1209465Y272195D01*
X1209155Y272348D01*
X1208742Y272463D01*
X1208277Y272501D01*
X1207812Y272463D01*
X1207399Y272348D01*
X1207089Y272195D01*
X1206830Y271965D01*
X1206727Y271658D01*
G01Y274758D02*
X1206830Y274451D01*
X1207089Y274221D01*
X1207399Y274068D01*
X1207812Y273953D01*
X1208277Y273915D01*
X1208742Y273953D01*
X1209155Y274068D01*
X1209465Y274221D01*
X1209724Y274451D01*
X1209827Y274758D01*
X1209724Y275065D01*
X1209465Y275295D01*
X1209155Y275448D01*
X1208742Y275563D01*
X1208277Y275601D01*
X1207812Y275563D01*
X1207399Y275448D01*
X1207089Y275295D01*
X1206830Y275065D01*
X1206727Y274758D01*
G01X1212194Y272458D02*
Y279548D01*
G01D02*
X1215994D01*
G01Y272408D02*
X1212244D01*
G01X1212194Y272858D02*
Y280048D01*
G01D02*
X1215994D01*
G01X1212194Y273458D02*
Y280548D01*
G01D02*
X1215994D01*
G01X1216898Y295621D02*
X1211898D01*
Y297141D01*
X1212148Y297648D01*
X1212731Y298028D01*
X1213398Y298155D01*
X1214065Y298028D01*
X1214565Y297711D01*
X1214815Y297141D01*
Y295621D01*
G01X1211898Y300088D02*
X1216898Y300975D01*
X1211898Y301988D01*
X1216898Y303001D01*
X1211898Y303888D01*
G01X1216898Y305821D02*
X1211898D01*
Y307405D01*
X1212148Y307911D01*
X1212481Y308228D01*
X1213148Y308355D01*
X1213815Y308228D01*
X1214231Y307848D01*
X1214481Y307405D01*
Y305821D01*
G01Y307405D02*
X1216898Y308355D01*
G01X1214398Y312568D02*
Y313835D01*
X1215898D01*
X1216398Y313455D01*
X1216731Y313011D01*
X1216898Y312378D01*
X1216731Y311745D01*
X1216398Y311301D01*
X1215898Y310921D01*
X1215315Y310668D01*
X1214648Y310541D01*
X1214065D01*
X1213565Y310668D01*
X1212981Y310921D01*
X1212481Y311301D01*
X1212148Y311681D01*
X1211898Y312188D01*
Y312631D01*
X1212065Y313138D01*
X1212398Y313518D01*
G01X1216898Y315895D02*
X1211898D01*
Y317161D01*
X1212148Y317668D01*
X1212481Y318048D01*
X1212981Y318365D01*
X1213565Y318618D01*
X1214398Y318681D01*
X1215231Y318618D01*
X1215815Y318365D01*
X1216315Y318048D01*
X1216648Y317668D01*
X1216898Y317161D01*
Y315895D01*
G01X1218565Y320488D02*
Y324288D01*
G01X1216898Y326221D02*
X1211898D01*
Y327741D01*
X1212148Y328248D01*
X1212731Y328628D01*
X1213398Y328755D01*
X1214065Y328628D01*
X1214565Y328311D01*
X1214815Y327741D01*
Y326221D01*
G01X1216898Y332588D02*
X1211898D01*
X1212898Y331828D01*
G01X1216898D02*
Y333348D01*
G01X1211898Y336105D02*
X1216898Y337688D01*
X1211898Y339271D01*
G01X1212731Y341585D02*
X1212231Y341965D01*
X1211981Y342408D01*
X1211898Y342915D01*
X1212065Y343548D01*
X1212481Y343991D01*
X1212981Y344118D01*
X1213481Y344055D01*
X1213898Y343801D01*
X1214731Y342535D01*
X1215315Y341965D01*
X1216148Y341585D01*
X1216898Y341458D01*
Y344118D01*
G01X1218565Y345988D02*
Y349788D01*
G01X1216898Y351405D02*
X1211898Y352988D01*
X1216898Y354571D01*
G01X1215148Y354001D02*
Y351975D01*
G01X1211898Y356695D02*
X1215481D01*
X1216231Y356948D01*
X1216731Y357455D01*
X1216898Y358088D01*
X1216731Y358721D01*
X1216231Y359228D01*
X1215481Y359481D01*
X1211898D01*
G01X1216898Y361858D02*
X1211898Y364518D01*
G01Y361858D02*
X1216898Y364518D01*
G01X1208218Y449218D02*
Y429532D01*
G01D02*
X1222618D01*
G01X1215418Y444975D02*
X1211175Y449218D01*
G01X1204527Y461802D02*
Y458602D01*
G01X1207425Y453542D02*
Y451320D01*
X1207578Y450855D01*
X1207885Y450545D01*
X1208268Y450442D01*
X1208651Y450545D01*
X1208958Y450855D01*
X1209111Y451320D01*
Y453542D01*
G01X1211368Y450442D02*
Y453542D01*
X1210908Y452922D01*
G01Y450442D02*
X1211828D01*
G01X1211175Y449218D02*
X1208218D01*
G01X1204587Y466872D02*
Y463672D01*
G01X1204663Y471976D02*
Y468776D01*
G01X1204212Y584043D02*
Y580843D01*
G01Y589043D02*
Y585843D01*
G01X1208423Y682595D02*
X1208615Y682285D01*
X1208845Y682078D01*
X1209113Y681975D01*
X1209420Y682078D01*
X1209650Y682285D01*
X1209880Y682595D01*
X1209957Y683008D01*
Y685075D01*
G01X1212290Y681975D02*
Y685075D01*
X1211830Y684455D01*
G01Y681975D02*
X1212750D01*
G01X1201039Y1306689D02*
Y1349997D01*
G01X1206380Y1306689D02*
X1201039D01*
G01X1203896Y1354797D02*
Y1351597D01*
G01X1202462Y1361297D02*
Y1355097D01*
G01X1205496Y1353214D02*
Y1355814D01*
G01X1206289Y1353214D02*
X1205496D01*
G01X1201039Y1349997D02*
X1206380D01*
G01X1202439Y1374900D02*
Y1372418D01*
G01Y1368118D02*
Y1361918D01*
G01X1205496Y1362425D02*
Y1364123D01*
G01X1202439Y1378618D02*
Y1377000D01*
G01X1206333Y1387249D02*
Y1381049D01*
G01D02*
X1203133D01*
G01Y1387249D02*
X1206333D01*
G01X1203133Y1381049D02*
Y1387249D01*
G01X1202215Y1383688D02*
Y1380488D01*
G01X1207103Y1383943D02*
Y1387143D01*
G01X1213303Y1383943D02*
X1207103D01*
G01X1213303Y1387143D02*
Y1383943D01*
G01X1207103Y1387143D02*
X1213303D01*
G01X1205496Y1376836D02*
X1206504D01*
G01X1205496Y1374982D02*
Y1376836D01*
G01X1206400Y1402600D02*
X1212600D01*
G01D02*
Y1399400D01*
G01D02*
X1206400D01*
G01D02*
Y1402600D01*
G01Y1392400D02*
Y1398600D01*
G01X1209600D02*
Y1392400D01*
G01D02*
X1206400D01*
G01Y1398600D02*
X1209600D01*
G01X1201600Y1398100D02*
Y1394900D01*
G01Y1402600D02*
Y1399400D01*
G01Y1420600D02*
Y1417400D01*
G01Y1416100D02*
Y1412900D01*
G01Y1411600D02*
Y1408400D01*
G01Y1407100D02*
Y1403900D01*
G01X1211439Y1408091D02*
X1209091D01*
G01D02*
Y1410439D01*
G01X1201600Y1430100D02*
Y1426900D01*
G01Y1434600D02*
Y1431400D01*
G01Y1425600D02*
Y1422400D01*
G01X1209091Y1429561D02*
Y1431909D01*
G01D02*
X1211439D01*
G01X1201600Y1439100D02*
Y1435900D01*
G01Y1449100D02*
Y1445900D01*
G01Y1444100D02*
Y1440900D01*
G01X1208275Y1442440D02*
Y1445540D01*
X1209195D01*
X1209502Y1445385D01*
X1209732Y1445023D01*
X1209809Y1444610D01*
X1209732Y1444197D01*
X1209540Y1443887D01*
X1209195Y1443732D01*
X1208275D01*
G01X1211299Y1445540D02*
Y1443318D01*
X1211452Y1442853D01*
X1211759Y1442543D01*
X1212142Y1442440D01*
X1212525Y1442543D01*
X1212832Y1442853D01*
X1212985Y1443318D01*
Y1445540D01*
G01X1215242Y1442440D02*
Y1445540D01*
X1214782Y1444920D01*
G01Y1442440D02*
X1215702D01*
G01X1217614Y1445023D02*
X1217844Y1445333D01*
X1218112Y1445488D01*
X1218419Y1445540D01*
X1218802Y1445437D01*
X1219070Y1445178D01*
X1219147Y1444868D01*
X1219109Y1444558D01*
X1218955Y1444300D01*
X1218189Y1443783D01*
X1217844Y1443422D01*
X1217614Y1442905D01*
X1217537Y1442440D01*
X1219147D01*
G01X1202306Y1601952D02*
Y1595952D01*
G01X1202332Y1595098D02*
Y1589098D01*
G01X1205194Y1588732D02*
Y1586510D01*
X1205347Y1586045D01*
X1205654Y1585735D01*
X1206037Y1585632D01*
X1206420Y1585735D01*
X1206727Y1586045D01*
X1206880Y1586510D01*
Y1588732D01*
G01X1208409Y1586924D02*
X1208677Y1587285D01*
X1208907Y1587492D01*
X1209214Y1587595D01*
X1209482Y1587492D01*
X1209674Y1587285D01*
X1209827Y1586975D01*
X1209865Y1586614D01*
X1209827Y1586304D01*
X1209674Y1585994D01*
X1209444Y1585735D01*
X1209175Y1585632D01*
X1208869Y1585735D01*
X1208600Y1586045D01*
X1208447Y1586510D01*
X1208409Y1587027D01*
X1208485Y1587699D01*
X1208600Y1588060D01*
X1208792Y1588422D01*
X1209060Y1588680D01*
X1209329Y1588732D01*
X1209597Y1588629D01*
X1209789Y1588370D01*
G01X1212237Y1588732D02*
X1211930Y1588629D01*
X1211700Y1588370D01*
X1211547Y1588060D01*
X1211432Y1587647D01*
X1211394Y1587182D01*
X1211432Y1586717D01*
X1211547Y1586304D01*
X1211700Y1585994D01*
X1211930Y1585735D01*
X1212237Y1585632D01*
X1212544Y1585735D01*
X1212774Y1585994D01*
X1212927Y1586304D01*
X1213042Y1586717D01*
X1213080Y1587182D01*
X1213042Y1587647D01*
X1212927Y1588060D01*
X1212774Y1588370D01*
X1212544Y1588629D01*
X1212237Y1588732D01*
G01X1215337Y1585632D02*
Y1588732D01*
X1214877Y1588112D01*
G01Y1585632D02*
X1215797D01*
G01X1218437Y1588732D02*
X1218130Y1588629D01*
X1217900Y1588370D01*
X1217747Y1588060D01*
X1217632Y1587647D01*
X1217594Y1587182D01*
X1217632Y1586717D01*
X1217747Y1586304D01*
X1217900Y1585994D01*
X1218130Y1585735D01*
X1218437Y1585632D01*
X1218744Y1585735D01*
X1218974Y1585994D01*
X1219127Y1586304D01*
X1219242Y1586717D01*
X1219280Y1587182D01*
X1219242Y1587647D01*
X1219127Y1588060D01*
X1218974Y1588370D01*
X1218744Y1588629D01*
X1218437Y1588732D01*
G01X1215943Y1599607D02*
X1215713Y1599762D01*
X1215445Y1599865D01*
X1215138D01*
X1214793Y1599710D01*
X1214525Y1599452D01*
X1214333Y1599142D01*
X1214180Y1598625D01*
X1214142Y1598160D01*
X1214218Y1597695D01*
X1214333Y1597385D01*
X1214563Y1597075D01*
X1214832Y1596868D01*
X1215100Y1596765D01*
X1215368D01*
X1215637Y1596868D01*
X1215867Y1597023D01*
X1216058Y1597230D01*
G01X1218123Y1596765D02*
X1218200Y1597437D01*
X1218315Y1598005D01*
X1218468Y1598522D01*
X1218660Y1599090D01*
X1218967Y1599865D01*
X1217433D01*
G01X1221300D02*
X1220993Y1599762D01*
X1220763Y1599503D01*
X1220610Y1599193D01*
X1220495Y1598780D01*
X1220457Y1598315D01*
X1220495Y1597850D01*
X1220610Y1597437D01*
X1220763Y1597127D01*
X1220993Y1596868D01*
X1221300Y1596765D01*
X1221607Y1596868D01*
X1221837Y1597127D01*
X1221990Y1597437D01*
X1222105Y1597850D01*
X1222143Y1598315D01*
X1222105Y1598780D01*
X1221990Y1599193D01*
X1221837Y1599503D01*
X1221607Y1599762D01*
X1221300Y1599865D01*
G01X1223557Y1597385D02*
X1223787Y1597023D01*
X1224093Y1596817D01*
X1224438Y1596765D01*
X1224745Y1596817D01*
X1225052Y1597075D01*
X1225243Y1597385D01*
X1225282Y1597695D01*
X1225205Y1598057D01*
X1224937Y1598315D01*
X1224668Y1598418D01*
X1224323D01*
G01X1224668D02*
X1224898Y1598573D01*
X1225090Y1598832D01*
X1225167Y1599142D01*
X1225090Y1599452D01*
X1224898Y1599710D01*
X1224553Y1599865D01*
X1224208Y1599813D01*
X1223863Y1599607D01*
G01X1226772Y1599348D02*
X1227002Y1599658D01*
X1227270Y1599813D01*
X1227577Y1599865D01*
X1227960Y1599762D01*
X1228228Y1599503D01*
X1228305Y1599193D01*
X1228267Y1598883D01*
X1228113Y1598625D01*
X1227347Y1598108D01*
X1227002Y1597747D01*
X1226772Y1597230D01*
X1226695Y1596765D01*
X1228305D01*
G01X1201911Y1615454D02*
Y1603454D01*
G01X1202758Y1621774D02*
X1208758D01*
Y1609774D01*
X1202758D01*
Y1621774D01*
G01X1209608D02*
X1215608D01*
Y1609774D01*
X1209608D01*
Y1621774D01*
G01X1213065Y1605850D02*
X1215305D01*
G01X1214092Y1607475D02*
Y1604225D01*
G01X1208716Y1663780D02*
X1208908Y1663470D01*
X1209138Y1663263D01*
X1209406Y1663160D01*
X1209713Y1663263D01*
X1209943Y1663470D01*
X1210173Y1663780D01*
X1210250Y1664193D01*
Y1666260D01*
G01X1212583Y1663160D02*
Y1666260D01*
X1212123Y1665640D01*
G01Y1663160D02*
X1213043D01*
G01X1215683Y1666260D02*
X1215376Y1666157D01*
X1215146Y1665898D01*
X1214993Y1665588D01*
X1214878Y1665175D01*
X1214840Y1664710D01*
X1214878Y1664245D01*
X1214993Y1663832D01*
X1215146Y1663522D01*
X1215376Y1663263D01*
X1215683Y1663160D01*
X1215990Y1663263D01*
X1216220Y1663522D01*
X1216373Y1663832D01*
X1216488Y1664245D01*
X1216526Y1664710D01*
X1216488Y1665175D01*
X1216373Y1665588D01*
X1216220Y1665898D01*
X1215990Y1666157D01*
X1215683Y1666260D01*
G01X1218783Y1663160D02*
X1219051Y1663212D01*
X1219358Y1663367D01*
X1219550Y1663625D01*
X1219626Y1663987D01*
X1219550Y1664348D01*
X1219320Y1664658D01*
X1218975Y1664813D01*
X1218591D01*
X1218361Y1664917D01*
X1218170Y1665175D01*
X1218093Y1665537D01*
X1218208Y1665898D01*
X1218476Y1666157D01*
X1218783Y1666260D01*
X1219090Y1666157D01*
X1219358Y1665898D01*
X1219473Y1665537D01*
X1219396Y1665175D01*
X1219205Y1664917D01*
X1218975Y1664813D01*
X1218591D01*
X1218246Y1664658D01*
X1218016Y1664348D01*
X1217940Y1663987D01*
X1218016Y1663625D01*
X1218208Y1663367D01*
X1218515Y1663212D01*
X1218783Y1663160D01*
G01X1203597Y1671459D02*
Y1674659D01*
G01X1209797Y1671459D02*
X1203597D01*
G01X1209797Y1674659D02*
Y1671459D01*
G01X1203597Y1674659D02*
X1209797D01*
G01X1206182Y1676412D02*
Y1686906D01*
G01X1214844Y1676412D02*
X1206182D01*
G01X1212644Y1681659D02*
X1214844Y1679759D01*
G01Y1683559D02*
X1212644Y1681659D01*
G01X1204278Y1677006D02*
X1204226Y1676699D01*
X1204020Y1676431D01*
X1203710Y1676201D01*
X1203348Y1676048D01*
X1202935Y1675971D01*
X1202521D01*
X1202108Y1676048D01*
X1201746Y1676201D01*
X1201436Y1676431D01*
X1201230Y1676699D01*
X1201178Y1677006D01*
X1201230Y1677313D01*
X1201436Y1677581D01*
X1201746Y1677811D01*
X1202108Y1677964D01*
X1202521Y1678041D01*
X1202935D01*
X1203348Y1677964D01*
X1203710Y1677811D01*
X1204020Y1677581D01*
X1204226Y1677313D01*
X1204278Y1677006D01*
G01X1203451Y1677313D02*
X1204278Y1677773D01*
G01Y1680106D02*
X1201178D01*
X1201798Y1679646D01*
G01X1204278D02*
Y1680566D01*
G01X1203658Y1682363D02*
X1204020Y1682593D01*
X1204226Y1682899D01*
X1204278Y1683244D01*
X1204226Y1683551D01*
X1203968Y1683858D01*
X1203658Y1684049D01*
X1203348Y1684088D01*
X1202986Y1684011D01*
X1202728Y1683743D01*
X1202625Y1683474D01*
Y1683129D01*
G01Y1683474D02*
X1202470Y1683704D01*
X1202211Y1683896D01*
X1201901Y1683973D01*
X1201591Y1683896D01*
X1201333Y1683704D01*
X1201178Y1683359D01*
X1201230Y1683014D01*
X1201436Y1682669D01*
G01X1201178Y1686306D02*
X1201281Y1685999D01*
X1201540Y1685769D01*
X1201850Y1685616D01*
X1202263Y1685501D01*
X1202728Y1685463D01*
X1203193Y1685501D01*
X1203606Y1685616D01*
X1203916Y1685769D01*
X1204175Y1685999D01*
X1204278Y1686306D01*
X1204175Y1686613D01*
X1203916Y1686843D01*
X1203606Y1686996D01*
X1203193Y1687111D01*
X1202728Y1687149D01*
X1202263Y1687111D01*
X1201850Y1686996D01*
X1201540Y1686843D01*
X1201281Y1686613D01*
X1201178Y1686306D01*
G01X1209479Y1695459D02*
Y1692259D01*
G01X1203279Y1695459D02*
X1209479D01*
G01X1203279Y1692259D02*
Y1695459D01*
G01X1209479Y1692259D02*
X1203279D01*
G01Y1696259D02*
Y1699459D01*
G01X1209479Y1696259D02*
X1203279D01*
G01X1209479Y1699459D02*
Y1696259D01*
G01X1203279Y1699459D02*
X1209479D01*
G01X1210279Y1696259D02*
Y1699459D01*
G01X1216479Y1696259D02*
X1210279D01*
G01Y1699459D02*
X1216479D01*
G01X1210279Y1695459D02*
X1216479D01*
G01X1210279Y1692259D02*
Y1695459D01*
G01X1216479Y1692259D02*
X1210279D01*
G01X1212629Y1691459D02*
Y1688259D01*
G01X1206429Y1691459D02*
X1212629D01*
G01X1206429Y1688259D02*
Y1691459D01*
G01X1212629Y1688259D02*
X1206429D01*
G01X1201137Y1699450D02*
Y1696250D01*
G01Y1695450D02*
Y1692250D01*
G01X1206182Y1686906D02*
X1214844D01*
G01X1211854Y1712336D02*
X1208654D01*
G01X1211854Y1718536D02*
Y1712336D01*
G01X1208654D02*
Y1718536D01*
G01X1212654Y1712336D02*
Y1718536D01*
G01X1215854Y1712336D02*
X1212654D01*
G01Y1711536D02*
X1215854D01*
G01X1212654Y1705336D02*
Y1711536D01*
G01X1215854Y1705336D02*
X1212654D01*
G01X1211854D02*
X1208654D01*
G01X1211854Y1711536D02*
Y1705336D01*
G01X1208654Y1711536D02*
X1211854D01*
G01X1208654Y1705336D02*
Y1711536D01*
G01X1203254Y1714033D02*
Y1705371D01*
G01D02*
X1199907D01*
G01X1211854Y1726336D02*
X1208654D01*
G01X1211854Y1732536D02*
Y1726336D01*
G01X1208654D02*
Y1732536D01*
G01Y1718536D02*
X1211854D01*
G01X1204577Y1733403D02*
Y1730203D01*
G01X1212654Y1726336D02*
Y1732536D01*
G01X1215854Y1726336D02*
X1212654D01*
G01Y1725536D02*
X1215854D01*
G01X1212654Y1719336D02*
Y1725536D01*
G01X1215854Y1719336D02*
X1212654D01*
G01X1211854D02*
X1208654D01*
G01X1211854Y1725536D02*
Y1719336D01*
G01X1208654Y1725536D02*
X1211854D01*
G01X1208654Y1719336D02*
Y1725536D01*
G01X1207854Y1723186D02*
X1204654D01*
G01X1207854Y1729386D02*
Y1723186D01*
G01X1204654Y1729386D02*
X1207854D01*
G01X1204654Y1723186D02*
Y1729386D01*
G01X1212654Y1718536D02*
X1215854D01*
G01X1203301Y1728033D02*
Y1719371D01*
G01D02*
X1199954D01*
G01X1208654Y1732536D02*
X1211854D01*
G01X1212654D02*
X1215854D01*
G01X1230948Y-541887D02*
X1227848D01*
X1230431Y-540890D01*
X1227848Y-539893D01*
X1230948D01*
G01Y-537023D02*
Y-538557D01*
X1227848D01*
Y-537023D01*
G01X1229346Y-537637D02*
Y-538557D01*
G01X1230483Y-535533D02*
X1230741Y-535303D01*
X1230896Y-535035D01*
X1230948Y-534690D01*
X1230845Y-534345D01*
X1230638Y-534077D01*
X1230276Y-533885D01*
X1229863Y-533847D01*
X1229450Y-533923D01*
X1229191Y-534115D01*
X1228985Y-534383D01*
X1228933Y-534652D01*
X1228985Y-534920D01*
X1229191Y-535265D01*
X1227848Y-535150D01*
Y-534115D01*
G01X1223388Y-23387D02*
X1223698Y-23195D01*
X1223905Y-22965D01*
X1224008Y-22697D01*
X1223905Y-22390D01*
X1223698Y-22160D01*
X1223388Y-21930D01*
X1222975Y-21853D01*
X1220908D01*
G01X1224008Y-19597D02*
X1223336Y-19520D01*
X1222768Y-19405D01*
X1222251Y-19252D01*
X1221683Y-19060D01*
X1220908Y-18753D01*
Y-20287D01*
G01X1224008Y-16420D02*
X1220908D01*
X1221528Y-16880D01*
G01X1224008D02*
Y-15960D01*
G01X1223185Y-4686D02*
X1223495Y-4494D01*
X1223702Y-4264D01*
X1223805Y-3996D01*
X1223702Y-3689D01*
X1223495Y-3459D01*
X1223185Y-3229D01*
X1222772Y-3152D01*
X1220705D01*
G01X1223805Y-896D02*
X1223133Y-819D01*
X1222565Y-704D01*
X1222048Y-551D01*
X1221480Y-359D01*
X1220705Y-52D01*
Y-1586D01*
G01X1223185Y1438D02*
X1223547Y1668D01*
X1223753Y1974D01*
X1223805Y2319D01*
X1223753Y2626D01*
X1223495Y2933D01*
X1223185Y3124D01*
X1222875Y3163D01*
X1222513Y3086D01*
X1222255Y2818D01*
X1222152Y2549D01*
Y2204D01*
G01Y2549D02*
X1221997Y2779D01*
X1221738Y2971D01*
X1221428Y3048D01*
X1221118Y2971D01*
X1220860Y2779D01*
X1220705Y2434D01*
X1220757Y2089D01*
X1220963Y1744D01*
G01X1222727Y13960D02*
X1223037Y14152D01*
X1223244Y14382D01*
X1223347Y14650D01*
X1223244Y14957D01*
X1223037Y15187D01*
X1222727Y15417D01*
X1222314Y15494D01*
X1220247D01*
G01X1223347Y17827D02*
X1223295Y18095D01*
X1223140Y18402D01*
X1222882Y18594D01*
X1222520Y18670D01*
X1222159Y18594D01*
X1221849Y18364D01*
X1221694Y18019D01*
Y17635D01*
X1221590Y17405D01*
X1221332Y17214D01*
X1220970Y17137D01*
X1220609Y17252D01*
X1220350Y17520D01*
X1220247Y17827D01*
X1220350Y18134D01*
X1220609Y18402D01*
X1220970Y18517D01*
X1221332Y18440D01*
X1221590Y18249D01*
X1221694Y18019D01*
Y17635D01*
X1221849Y17290D01*
X1222159Y17060D01*
X1222520Y16984D01*
X1222882Y17060D01*
X1223140Y17252D01*
X1223295Y17559D01*
X1223347Y17827D01*
G01X1220247Y20927D02*
X1220350Y20620D01*
X1220609Y20390D01*
X1220919Y20237D01*
X1221332Y20122D01*
X1221797Y20084D01*
X1222262Y20122D01*
X1222675Y20237D01*
X1222985Y20390D01*
X1223244Y20620D01*
X1223347Y20927D01*
X1223244Y21234D01*
X1222985Y21464D01*
X1222675Y21617D01*
X1222262Y21732D01*
X1221797Y21770D01*
X1221332Y21732D01*
X1220919Y21617D01*
X1220609Y21464D01*
X1220350Y21234D01*
X1220247Y20927D01*
G01X1222055Y23299D02*
X1221694Y23567D01*
X1221487Y23797D01*
X1221384Y24104D01*
X1221487Y24372D01*
X1221694Y24564D01*
X1222004Y24717D01*
X1222365Y24755D01*
X1222675Y24717D01*
X1222985Y24564D01*
X1223244Y24334D01*
X1223347Y24065D01*
X1223244Y23759D01*
X1222934Y23490D01*
X1222469Y23337D01*
X1221952Y23299D01*
X1221280Y23375D01*
X1220919Y23490D01*
X1220557Y23682D01*
X1220299Y23950D01*
X1220247Y24219D01*
X1220350Y24487D01*
X1220609Y24679D01*
G01X1222985Y26475D02*
X1223244Y26744D01*
X1223347Y27050D01*
X1223244Y27357D01*
X1222934Y27625D01*
X1222469Y27817D01*
X1222004Y27894D01*
X1221435D01*
X1220970Y27817D01*
X1220557Y27625D01*
X1220350Y27395D01*
X1220247Y27127D01*
X1220350Y26820D01*
X1220557Y26590D01*
X1220867Y26437D01*
X1221280Y26360D01*
X1221642Y26437D01*
X1222004Y26629D01*
X1222210Y26859D01*
X1222262Y27127D01*
X1222159Y27434D01*
X1221900Y27664D01*
X1221435Y27894D01*
G01X1217656Y63927D02*
Y53691D01*
G01D02*
X1257026D01*
G01X1229467D02*
Y55660D01*
G01D02*
X1219624D01*
G01D02*
Y70227D01*
G01X1257026Y72195D02*
X1217656D01*
G01D02*
Y63927D01*
G01X1219624Y70227D02*
X1223291D01*
G01X1227791D02*
X1255058D01*
G01X1221855Y84246D02*
Y90446D01*
G01D02*
X1225055D01*
G01D02*
Y84246D01*
G01D02*
X1221855D01*
G01X1217181Y90446D02*
Y84246D01*
G01X1231912Y89535D02*
X1228712D01*
G01D02*
Y95735D01*
G01D02*
X1231912D01*
G01X1219938Y126976D02*
Y135638D01*
G01X1232793Y131139D02*
X1226593D01*
Y134339D01*
X1232793D01*
Y131139D01*
G01X1223443Y134339D02*
X1229643D01*
Y131139D01*
X1223443D01*
Y134339D01*
G01X1232793Y126639D02*
X1226593D01*
Y129839D01*
X1232793D01*
Y126639D01*
G01X1223443Y129839D02*
X1229643D01*
Y126639D01*
X1223443D01*
Y129839D01*
G01X1229593Y146839D02*
X1235793D01*
G01X1229593Y143639D02*
Y146839D01*
G01X1235793Y143639D02*
X1229593D01*
G01X1226693Y148739D02*
Y142739D01*
G01X1223844Y161076D02*
X1238560D01*
G01X1223844Y181154D02*
Y161076D01*
G01X1231202Y177115D02*
X1227163Y181154D01*
G01X1218599Y191742D02*
Y189520D01*
X1218752Y189055D01*
X1219059Y188745D01*
X1219442Y188642D01*
X1219825Y188745D01*
X1220132Y189055D01*
X1220285Y189520D01*
Y191742D01*
G01X1221814Y191225D02*
X1222044Y191535D01*
X1222312Y191690D01*
X1222619Y191742D01*
X1223002Y191639D01*
X1223270Y191380D01*
X1223347Y191070D01*
X1223309Y190760D01*
X1223155Y190502D01*
X1222389Y189985D01*
X1222044Y189624D01*
X1221814Y189107D01*
X1221737Y188642D01*
X1223347D01*
G01X1224914Y189934D02*
X1225182Y190295D01*
X1225412Y190502D01*
X1225719Y190605D01*
X1225987Y190502D01*
X1226179Y190295D01*
X1226332Y189985D01*
X1226370Y189624D01*
X1226332Y189314D01*
X1226179Y189004D01*
X1225949Y188745D01*
X1225680Y188642D01*
X1225374Y188745D01*
X1225105Y189055D01*
X1224952Y189520D01*
X1224914Y190037D01*
X1224990Y190709D01*
X1225105Y191070D01*
X1225297Y191432D01*
X1225565Y191690D01*
X1225834Y191742D01*
X1226102Y191639D01*
X1226294Y191380D01*
G01X1228090Y189004D02*
X1228359Y188745D01*
X1228665Y188642D01*
X1228972Y188745D01*
X1229240Y189055D01*
X1229432Y189520D01*
X1229509Y189985D01*
Y190554D01*
X1229432Y191019D01*
X1229240Y191432D01*
X1229010Y191639D01*
X1228742Y191742D01*
X1228435Y191639D01*
X1228205Y191432D01*
X1228052Y191122D01*
X1227975Y190709D01*
X1228052Y190347D01*
X1228244Y189985D01*
X1228474Y189779D01*
X1228742Y189727D01*
X1229049Y189830D01*
X1229279Y190089D01*
X1229509Y190554D01*
G01X1227163Y181154D02*
X1223844D01*
G01X1228766Y260794D02*
X1225666D01*
Y261560D01*
X1225821Y261867D01*
X1226028Y262097D01*
X1226338Y262289D01*
X1226699Y262442D01*
X1227216Y262480D01*
X1227733Y262442D01*
X1228094Y262289D01*
X1228404Y262097D01*
X1228611Y261867D01*
X1228766Y261560D01*
Y260794D01*
G01Y264737D02*
X1228714Y265005D01*
X1228559Y265312D01*
X1228301Y265504D01*
X1227939Y265580D01*
X1227578Y265504D01*
X1227268Y265274D01*
X1227113Y264929D01*
Y264545D01*
X1227009Y264315D01*
X1226751Y264124D01*
X1226389Y264047D01*
X1226028Y264162D01*
X1225769Y264430D01*
X1225666Y264737D01*
X1225769Y265044D01*
X1226028Y265312D01*
X1226389Y265427D01*
X1226751Y265350D01*
X1227009Y265159D01*
X1227113Y264929D01*
Y264545D01*
X1227268Y264200D01*
X1227578Y263970D01*
X1227939Y263894D01*
X1228301Y263970D01*
X1228559Y264162D01*
X1228714Y264469D01*
X1228766Y264737D01*
G01Y267837D02*
X1228714Y268105D01*
X1228559Y268412D01*
X1228301Y268604D01*
X1227939Y268680D01*
X1227578Y268604D01*
X1227268Y268374D01*
X1227113Y268029D01*
Y267645D01*
X1227009Y267415D01*
X1226751Y267224D01*
X1226389Y267147D01*
X1226028Y267262D01*
X1225769Y267530D01*
X1225666Y267837D01*
X1225769Y268144D01*
X1226028Y268412D01*
X1226389Y268527D01*
X1226751Y268450D01*
X1227009Y268259D01*
X1227113Y268029D01*
Y267645D01*
X1227268Y267300D01*
X1227578Y267070D01*
X1227939Y266994D01*
X1228301Y267070D01*
X1228559Y267262D01*
X1228714Y267569D01*
X1228766Y267837D01*
G01X1220766Y260794D02*
X1217666D01*
Y261560D01*
X1217821Y261867D01*
X1218028Y262097D01*
X1218338Y262289D01*
X1218699Y262442D01*
X1219216Y262480D01*
X1219733Y262442D01*
X1220094Y262289D01*
X1220404Y262097D01*
X1220611Y261867D01*
X1220766Y261560D01*
Y260794D01*
G01X1220404Y264085D02*
X1220663Y264354D01*
X1220766Y264660D01*
X1220663Y264967D01*
X1220353Y265235D01*
X1219888Y265427D01*
X1219423Y265504D01*
X1218854D01*
X1218389Y265427D01*
X1217976Y265235D01*
X1217769Y265005D01*
X1217666Y264737D01*
X1217769Y264430D01*
X1217976Y264200D01*
X1218286Y264047D01*
X1218699Y263970D01*
X1219061Y264047D01*
X1219423Y264239D01*
X1219629Y264469D01*
X1219681Y264737D01*
X1219578Y265044D01*
X1219319Y265274D01*
X1218854Y265504D01*
G01X1220146Y266994D02*
X1220508Y267224D01*
X1220714Y267530D01*
X1220766Y267875D01*
X1220714Y268182D01*
X1220456Y268489D01*
X1220146Y268680D01*
X1219836Y268719D01*
X1219474Y268642D01*
X1219216Y268374D01*
X1219113Y268105D01*
Y267760D01*
G01Y268105D02*
X1218958Y268335D01*
X1218699Y268527D01*
X1218389Y268604D01*
X1218079Y268527D01*
X1217821Y268335D01*
X1217666Y267990D01*
X1217718Y267645D01*
X1217924Y267300D01*
G01X1228194Y273458D02*
Y280548D01*
G01D02*
X1231994D01*
G01X1228194Y272858D02*
Y280048D01*
G01D02*
X1231994D01*
G01X1228194Y272458D02*
Y279548D01*
G01D02*
X1231994D01*
G01Y272408D02*
X1228244D01*
G01X1220194Y273458D02*
Y280548D01*
G01D02*
X1223994D01*
G01D02*
Y273458D01*
G01X1220194Y272858D02*
Y280048D01*
G01D02*
X1223994D01*
G01D02*
Y272858D01*
G01X1220194Y272458D02*
Y279548D01*
G01D02*
X1223994D01*
G01D02*
Y272408D01*
G01D02*
X1220244D01*
G01X1215994Y279548D02*
Y272408D01*
G01Y280048D02*
Y272858D01*
G01Y280548D02*
Y273458D01*
G01X1229361Y296481D02*
X1224361D01*
Y298065D01*
X1224611Y298571D01*
X1224944Y298888D01*
X1225611Y299015D01*
X1226278Y298888D01*
X1226694Y298508D01*
X1226944Y298065D01*
Y296481D01*
G01Y298065D02*
X1229361Y299015D01*
G01X1228694Y301518D02*
X1229111Y302025D01*
X1229361Y302595D01*
Y303101D01*
X1229111Y303608D01*
X1228694Y303988D01*
X1228111Y304178D01*
X1227528Y304051D01*
X1227028Y303735D01*
X1226694Y303165D01*
X1226528Y302405D01*
X1226194Y301961D01*
X1225611Y301771D01*
X1225028Y301898D01*
X1224611Y302215D01*
X1224361Y302658D01*
Y303101D01*
X1224528Y303545D01*
X1224944Y303925D01*
G01X1224361Y307948D02*
X1229361D01*
G01X1224361Y306491D02*
Y309405D01*
G01X1231028Y311148D02*
Y314948D01*
G01X1224778Y319541D02*
X1224528Y319161D01*
X1224361Y318718D01*
Y318211D01*
X1224611Y317641D01*
X1225028Y317198D01*
X1225528Y316881D01*
X1226361Y316628D01*
X1227111Y316565D01*
X1227861Y316691D01*
X1228361Y316881D01*
X1228861Y317261D01*
X1229194Y317705D01*
X1229361Y318148D01*
Y318591D01*
X1229194Y319035D01*
X1228944Y319415D01*
X1228611Y319731D01*
G01X1229361Y321981D02*
X1224361D01*
Y323501D01*
X1224611Y324008D01*
X1225194Y324388D01*
X1225861Y324515D01*
X1226528Y324388D01*
X1227028Y324071D01*
X1227278Y323501D01*
Y321981D01*
G01X1224361Y326955D02*
X1227944D01*
X1228694Y327208D01*
X1229194Y327715D01*
X1229361Y328348D01*
X1229194Y328981D01*
X1228694Y329488D01*
X1227944Y329741D01*
X1224361D01*
G01Y333448D02*
X1224528Y332941D01*
X1224944Y332561D01*
X1225444Y332308D01*
X1226111Y332118D01*
X1226861Y332055D01*
X1227611Y332118D01*
X1228278Y332308D01*
X1228778Y332561D01*
X1229194Y332941D01*
X1229361Y333448D01*
X1229194Y333955D01*
X1228778Y334335D01*
X1228278Y334588D01*
X1227611Y334778D01*
X1226861Y334841D01*
X1226111Y334778D01*
X1225444Y334588D01*
X1224944Y334335D01*
X1224528Y333955D01*
X1224361Y333448D01*
G01X1231028Y336648D02*
Y340448D01*
G01X1229361Y342381D02*
X1224361D01*
Y343965D01*
X1224611Y344471D01*
X1224944Y344788D01*
X1225611Y344915D01*
X1226278Y344788D01*
X1226694Y344408D01*
X1226944Y343965D01*
Y342381D01*
G01Y343965D02*
X1229361Y344915D01*
G01X1228694Y347418D02*
X1229111Y347925D01*
X1229361Y348495D01*
Y349001D01*
X1229111Y349508D01*
X1228694Y349888D01*
X1228111Y350078D01*
X1227528Y349951D01*
X1227028Y349635D01*
X1226694Y349065D01*
X1226528Y348305D01*
X1226194Y347861D01*
X1225611Y347671D01*
X1225028Y347798D01*
X1224611Y348115D01*
X1224361Y348558D01*
Y349001D01*
X1224528Y349445D01*
X1224944Y349825D01*
G01X1229361Y352201D02*
X1224361D01*
X1228528Y353848D01*
X1224361Y355495D01*
X1229361D01*
G01Y357681D02*
X1224361D01*
Y359265D01*
X1224611Y359771D01*
X1224944Y360088D01*
X1225611Y360215D01*
X1226278Y360088D01*
X1226694Y359708D01*
X1226944Y359265D01*
Y357681D01*
G01Y359265D02*
X1229361Y360215D01*
G01X1228694Y362718D02*
X1229111Y363225D01*
X1229361Y363795D01*
Y364301D01*
X1229111Y364808D01*
X1228694Y365188D01*
X1228111Y365378D01*
X1227528Y365251D01*
X1227028Y364935D01*
X1226694Y364365D01*
X1226528Y363605D01*
X1226194Y363161D01*
X1225611Y362971D01*
X1225028Y363098D01*
X1224611Y363415D01*
X1224361Y363858D01*
Y364301D01*
X1224528Y364745D01*
X1224944Y365125D01*
G01X1224361Y369148D02*
X1229361D01*
G01X1224361Y367691D02*
Y370605D01*
G01X1222618Y429532D02*
Y449218D01*
G01X1219661D02*
X1215418Y444975D01*
G01X1220902Y472719D02*
Y453033D01*
G01D02*
X1235302D01*
G01X1222618Y449218D02*
X1219661D01*
G01X1223179Y477133D02*
Y474911D01*
X1223332Y474446D01*
X1223639Y474136D01*
X1224022Y474033D01*
X1224405Y474136D01*
X1224712Y474446D01*
X1224865Y474911D01*
Y477133D01*
G01X1226394Y475325D02*
X1226662Y475686D01*
X1226892Y475893D01*
X1227199Y475996D01*
X1227467Y475893D01*
X1227659Y475686D01*
X1227812Y475376D01*
X1227850Y475015D01*
X1227812Y474705D01*
X1227659Y474395D01*
X1227429Y474136D01*
X1227160Y474033D01*
X1226854Y474136D01*
X1226585Y474446D01*
X1226432Y474911D01*
X1226394Y475428D01*
X1226470Y476100D01*
X1226585Y476461D01*
X1226777Y476823D01*
X1227045Y477081D01*
X1227314Y477133D01*
X1227582Y477030D01*
X1227774Y476771D01*
G01X1230682Y474033D02*
Y477133D01*
X1229264Y474911D01*
X1231180D01*
G01X1228102Y468476D02*
X1223859Y472719D01*
G01D02*
X1220902D01*
G01X1232345D02*
X1228102Y468476D01*
G01X1214835Y776500D02*
Y687244D01*
G01Y1025500D02*
Y1011000D01*
G01Y1303850D02*
Y1252000D01*
G01X1225226Y1306689D02*
X1230567D01*
G01X1225182Y1353214D02*
X1224389D01*
G01X1225182Y1355814D02*
Y1353214D01*
G01X1230567Y1349997D02*
X1225226D01*
G01X1228048Y1368716D02*
X1231248D01*
G01X1228048Y1362516D02*
Y1368716D01*
G01X1231248Y1362516D02*
X1228048D01*
G01X1220770Y1386439D02*
X1223970D01*
G01X1220770Y1380239D02*
Y1386439D01*
G01X1223970Y1380239D02*
X1220770D01*
G01X1223970Y1386439D02*
Y1380239D01*
G01X1219928Y1386439D02*
Y1380239D01*
G01D02*
X1216728D01*
G01Y1386439D02*
X1219928D01*
G01X1216728Y1380239D02*
Y1386439D01*
G01X1225182Y1376836D02*
Y1374645D01*
G01X1224449Y1376836D02*
X1225182D01*
G01X1217680Y1619113D02*
X1253420D01*
Y1602183D01*
X1217680D01*
Y1619113D01*
G01X1216530Y1602182D02*
X1218039Y1602186D01*
G01X1216480Y1619115D02*
X1216486Y1602132D01*
G01X1217080Y1619115D02*
X1217076Y1602140D01*
G01X1217680Y1619115D02*
X1217677Y1602175D01*
G01X1216480Y1619115D02*
X1217680D01*
G01X1231500Y1646023D02*
X1223600D01*
G01X1222046Y1659000D02*
Y1736118D01*
G01X1219620Y1677091D02*
X1219568Y1676784D01*
X1219362Y1676516D01*
X1219052Y1676286D01*
X1218690Y1676133D01*
X1218277Y1676056D01*
X1217863D01*
X1217450Y1676133D01*
X1217088Y1676286D01*
X1216778Y1676516D01*
X1216572Y1676784D01*
X1216520Y1677091D01*
X1216572Y1677398D01*
X1216778Y1677666D01*
X1217088Y1677896D01*
X1217450Y1678049D01*
X1217863Y1678126D01*
X1218277D01*
X1218690Y1678049D01*
X1219052Y1677896D01*
X1219362Y1677666D01*
X1219568Y1677398D01*
X1219620Y1677091D01*
G01X1218793Y1677398D02*
X1219620Y1677858D01*
G01Y1680191D02*
X1216520D01*
X1217140Y1679731D01*
G01X1219620D02*
Y1680651D01*
G01X1219000Y1682448D02*
X1219362Y1682678D01*
X1219568Y1682984D01*
X1219620Y1683329D01*
X1219568Y1683636D01*
X1219310Y1683943D01*
X1219000Y1684134D01*
X1218690Y1684173D01*
X1218328Y1684096D01*
X1218070Y1683828D01*
X1217967Y1683559D01*
Y1683214D01*
G01Y1683559D02*
X1217812Y1683789D01*
X1217553Y1683981D01*
X1217243Y1684058D01*
X1216933Y1683981D01*
X1216675Y1683789D01*
X1216520Y1683444D01*
X1216572Y1683099D01*
X1216778Y1682754D01*
G01X1219000Y1685548D02*
X1219362Y1685778D01*
X1219568Y1686084D01*
X1219620Y1686429D01*
X1219568Y1686736D01*
X1219310Y1687043D01*
X1219000Y1687234D01*
X1218690Y1687273D01*
X1218328Y1687196D01*
X1218070Y1686928D01*
X1217967Y1686659D01*
Y1686314D01*
G01Y1686659D02*
X1217812Y1686889D01*
X1217553Y1687081D01*
X1217243Y1687158D01*
X1216933Y1687081D01*
X1216675Y1686889D01*
X1216520Y1686544D01*
X1216572Y1686199D01*
X1216778Y1685854D01*
G01X1214844Y1679759D02*
Y1676412D01*
G01Y1686906D02*
Y1683559D01*
G01X1226655Y1683636D02*
X1223555D01*
Y1684556D01*
X1223710Y1684863D01*
X1224072Y1685093D01*
X1224485Y1685170D01*
X1224898Y1685093D01*
X1225208Y1684901D01*
X1225363Y1684556D01*
Y1683636D01*
G01X1226655Y1686736D02*
X1223555D01*
Y1687695D01*
X1223710Y1688001D01*
X1223917Y1688193D01*
X1224330Y1688270D01*
X1224743Y1688193D01*
X1225002Y1687963D01*
X1225157Y1687695D01*
Y1686736D01*
G01Y1687695D02*
X1226655Y1688270D01*
G01Y1691370D02*
Y1689836D01*
X1223555D01*
Y1691370D01*
G01X1225053Y1690756D02*
Y1689836D01*
G01X1226242Y1692898D02*
X1226500Y1693205D01*
X1226655Y1693550D01*
Y1693856D01*
X1226500Y1694163D01*
X1226242Y1694393D01*
X1225880Y1694508D01*
X1225518Y1694431D01*
X1225208Y1694240D01*
X1225002Y1693895D01*
X1224898Y1693435D01*
X1224692Y1693166D01*
X1224330Y1693051D01*
X1223968Y1693128D01*
X1223710Y1693320D01*
X1223555Y1693588D01*
Y1693856D01*
X1223658Y1694125D01*
X1223917Y1694355D01*
G01X1226242Y1695998D02*
X1226500Y1696305D01*
X1226655Y1696650D01*
Y1696956D01*
X1226500Y1697263D01*
X1226242Y1697493D01*
X1225880Y1697608D01*
X1225518Y1697531D01*
X1225208Y1697340D01*
X1225002Y1696995D01*
X1224898Y1696535D01*
X1224692Y1696266D01*
X1224330Y1696151D01*
X1223968Y1696228D01*
X1223710Y1696420D01*
X1223555Y1696688D01*
Y1696956D01*
X1223658Y1697225D01*
X1223917Y1697455D01*
G01X1225622Y1699405D02*
Y1700401D01*
G01X1226655Y1702275D02*
X1223555D01*
Y1703731D01*
G01X1225053Y1703195D02*
Y1702275D01*
G01X1223555Y1705643D02*
Y1706563D01*
G01Y1706103D02*
X1226655D01*
G01Y1705643D02*
Y1706563D01*
G01X1223555Y1709203D02*
X1226655D01*
G01X1223555Y1708321D02*
Y1710085D01*
G01X1231300Y1686125D02*
X1228200D01*
G01Y1687581D02*
X1230112Y1686125D01*
G01X1231300Y1687811D02*
X1229233Y1686776D01*
G01X1228200Y1681476D02*
X1231300D01*
Y1683010D01*
G01Y1676522D02*
X1228200D01*
X1230783Y1677519D01*
X1228200Y1678516D01*
X1231300D01*
G01Y1671913D02*
X1228200D01*
X1231300Y1673677D01*
X1228200D01*
G01X1216479Y1699459D02*
Y1696259D01*
G01Y1695459D02*
Y1692259D01*
G01X1230680Y1690925D02*
X1230990Y1691117D01*
X1231197Y1691347D01*
X1231300Y1691615D01*
X1231197Y1691922D01*
X1230990Y1692152D01*
X1230680Y1692382D01*
X1230267Y1692459D01*
X1228200D01*
G01X1231300Y1700336D02*
X1228200D01*
G01Y1701946D02*
X1231300D01*
G01X1229750D02*
Y1700336D01*
G01X1228200Y1695957D02*
Y1696877D01*
G01Y1696417D02*
X1231300D01*
G01Y1695957D02*
Y1696877D01*
G01X1215854Y1718536D02*
Y1712336D01*
G01Y1711536D02*
Y1705336D01*
G01X1231300Y1716081D02*
Y1714547D01*
X1228200D01*
Y1716081D01*
G01X1229698Y1715467D02*
Y1714547D01*
G01X1231300Y1709862D02*
X1228200D01*
Y1711318D01*
G01X1229698Y1710782D02*
Y1709862D01*
G01X1229750Y1706096D02*
Y1706863D01*
X1230680D01*
X1230990Y1706633D01*
X1231197Y1706364D01*
X1231300Y1705981D01*
X1231197Y1705598D01*
X1230990Y1705329D01*
X1230680Y1705099D01*
X1230318Y1704946D01*
X1229905Y1704869D01*
X1229543D01*
X1229233Y1704946D01*
X1228872Y1705099D01*
X1228562Y1705329D01*
X1228355Y1705559D01*
X1228200Y1705866D01*
Y1706134D01*
X1228303Y1706441D01*
X1228510Y1706671D01*
G01X1215854Y1732536D02*
Y1726336D01*
G01Y1725536D02*
Y1719336D01*
G01X1231300Y1719196D02*
X1228200D01*
Y1719962D01*
X1228355Y1720269D01*
X1228562Y1720499D01*
X1228872Y1720691D01*
X1229233Y1720844D01*
X1229750Y1720882D01*
X1230267Y1720844D01*
X1230628Y1720691D01*
X1230938Y1720499D01*
X1231145Y1720269D01*
X1231300Y1719962D01*
Y1719196D01*
G01X1229647Y1729795D02*
X1229492Y1729948D01*
X1229233Y1730063D01*
X1228872Y1730140D01*
X1228562Y1730063D01*
X1228355Y1729910D01*
X1228200Y1729641D01*
Y1728606D01*
X1231300D01*
Y1729871D01*
X1231093Y1730140D01*
X1230783Y1730293D01*
X1230422Y1730370D01*
X1230060Y1730293D01*
X1229750Y1730063D01*
X1229647Y1729795D01*
Y1728606D01*
G01X1228458Y1725606D02*
X1228303Y1725376D01*
X1228200Y1725108D01*
Y1724801D01*
X1228355Y1724456D01*
X1228613Y1724188D01*
X1228923Y1723996D01*
X1229440Y1723843D01*
X1229905Y1723805D01*
X1230370Y1723881D01*
X1230680Y1723996D01*
X1230990Y1724226D01*
X1231197Y1724495D01*
X1231300Y1724763D01*
Y1725031D01*
X1231197Y1725300D01*
X1231042Y1725530D01*
X1230835Y1725721D01*
G01X1244822Y-11871D02*
Y-28151D01*
X1235222D01*
Y-11871D01*
X1244822D01*
G01Y8129D02*
Y-8151D01*
X1235222D01*
Y8129D01*
X1244822D01*
G01Y28129D02*
Y11849D01*
X1235222D01*
Y28129D01*
X1244822D01*
G01X1231912Y95735D02*
Y89535D01*
G01X1249832Y87710D02*
X1233632D01*
G01D02*
Y100710D01*
G01X1234039Y105277D02*
Y103055D01*
X1234192Y102590D01*
X1234499Y102280D01*
X1234882Y102177D01*
X1235265Y102280D01*
X1235572Y102590D01*
X1235725Y103055D01*
Y105277D01*
G01X1237330Y102539D02*
X1237599Y102280D01*
X1237905Y102177D01*
X1238212Y102280D01*
X1238480Y102590D01*
X1238672Y103055D01*
X1238749Y103520D01*
Y104089D01*
X1238672Y104554D01*
X1238480Y104967D01*
X1238250Y105174D01*
X1237982Y105277D01*
X1237675Y105174D01*
X1237445Y104967D01*
X1237292Y104657D01*
X1237215Y104244D01*
X1237292Y103882D01*
X1237484Y103520D01*
X1237714Y103314D01*
X1237982Y103262D01*
X1238289Y103365D01*
X1238519Y103624D01*
X1238749Y104089D01*
G01X1240430Y102539D02*
X1240699Y102280D01*
X1241005Y102177D01*
X1241312Y102280D01*
X1241580Y102590D01*
X1241772Y103055D01*
X1241849Y103520D01*
Y104089D01*
X1241772Y104554D01*
X1241580Y104967D01*
X1241350Y105174D01*
X1241082Y105277D01*
X1240775Y105174D01*
X1240545Y104967D01*
X1240392Y104657D01*
X1240315Y104244D01*
X1240392Y103882D01*
X1240584Y103520D01*
X1240814Y103314D01*
X1241082Y103262D01*
X1241389Y103365D01*
X1241619Y103624D01*
X1241849Y104089D01*
G01X1233632Y100710D02*
X1240232D01*
G01D02*
X1241732Y98210D01*
G01D02*
X1243232Y100710D01*
G01D02*
X1249832D01*
G01X1246293Y126639D02*
X1240093D01*
G01D02*
Y129839D01*
G01D02*
X1246293D01*
G01X1240093Y135639D02*
Y138839D01*
G01X1246293Y135639D02*
X1240093D01*
G01Y134339D02*
X1246293D01*
G01X1240093Y131139D02*
Y134339D01*
G01X1246293Y131139D02*
X1240093D01*
G01Y125339D02*
X1246293D01*
G01X1240093Y122139D02*
Y125339D01*
G01X1246293Y122139D02*
X1240093D01*
G01Y138839D02*
X1246293D01*
G01X1235793Y146839D02*
Y143639D01*
G01X1240093D02*
Y146839D01*
G01X1246293Y143639D02*
X1240093D01*
G01Y146839D02*
X1246293D01*
G01X1238560Y161076D02*
Y181154D01*
G01X1235241D02*
X1231202Y177115D01*
G01X1238560Y181154D02*
X1235241D01*
G01X1244766Y260794D02*
X1241666D01*
Y261560D01*
X1241821Y261867D01*
X1242028Y262097D01*
X1242338Y262289D01*
X1242699Y262442D01*
X1243216Y262480D01*
X1243733Y262442D01*
X1244094Y262289D01*
X1244404Y262097D01*
X1244611Y261867D01*
X1244766Y261560D01*
Y260794D01*
G01X1244404Y264085D02*
X1244663Y264354D01*
X1244766Y264660D01*
X1244663Y264967D01*
X1244353Y265235D01*
X1243888Y265427D01*
X1243423Y265504D01*
X1242854D01*
X1242389Y265427D01*
X1241976Y265235D01*
X1241769Y265005D01*
X1241666Y264737D01*
X1241769Y264430D01*
X1241976Y264200D01*
X1242286Y264047D01*
X1242699Y263970D01*
X1243061Y264047D01*
X1243423Y264239D01*
X1243629Y264469D01*
X1243681Y264737D01*
X1243578Y265044D01*
X1243319Y265274D01*
X1242854Y265504D01*
G01X1244404Y267185D02*
X1244663Y267454D01*
X1244766Y267760D01*
X1244663Y268067D01*
X1244353Y268335D01*
X1243888Y268527D01*
X1243423Y268604D01*
X1242854D01*
X1242389Y268527D01*
X1241976Y268335D01*
X1241769Y268105D01*
X1241666Y267837D01*
X1241769Y267530D01*
X1241976Y267300D01*
X1242286Y267147D01*
X1242699Y267070D01*
X1243061Y267147D01*
X1243423Y267339D01*
X1243629Y267569D01*
X1243681Y267837D01*
X1243578Y268144D01*
X1243319Y268374D01*
X1242854Y268604D01*
G01X1236766Y260794D02*
X1233666D01*
Y261560D01*
X1233821Y261867D01*
X1234028Y262097D01*
X1234338Y262289D01*
X1234699Y262442D01*
X1235216Y262480D01*
X1235733Y262442D01*
X1236094Y262289D01*
X1236404Y262097D01*
X1236611Y261867D01*
X1236766Y261560D01*
Y260794D01*
G01X1236404Y264085D02*
X1236663Y264354D01*
X1236766Y264660D01*
X1236663Y264967D01*
X1236353Y265235D01*
X1235888Y265427D01*
X1235423Y265504D01*
X1234854D01*
X1234389Y265427D01*
X1233976Y265235D01*
X1233769Y265005D01*
X1233666Y264737D01*
X1233769Y264430D01*
X1233976Y264200D01*
X1234286Y264047D01*
X1234699Y263970D01*
X1235061Y264047D01*
X1235423Y264239D01*
X1235629Y264469D01*
X1235681Y264737D01*
X1235578Y265044D01*
X1235319Y265274D01*
X1234854Y265504D01*
G01X1236766Y267837D02*
X1236714Y268105D01*
X1236559Y268412D01*
X1236301Y268604D01*
X1235939Y268680D01*
X1235578Y268604D01*
X1235268Y268374D01*
X1235113Y268029D01*
Y267645D01*
X1235009Y267415D01*
X1234751Y267224D01*
X1234389Y267147D01*
X1234028Y267262D01*
X1233769Y267530D01*
X1233666Y267837D01*
X1233769Y268144D01*
X1234028Y268412D01*
X1234389Y268527D01*
X1234751Y268450D01*
X1235009Y268259D01*
X1235113Y268029D01*
Y267645D01*
X1235268Y267300D01*
X1235578Y267070D01*
X1235939Y266994D01*
X1236301Y267070D01*
X1236559Y267262D01*
X1236714Y267569D01*
X1236766Y267837D01*
G01X1244194Y273458D02*
Y280548D01*
G01D02*
X1247994D01*
G01X1244194Y272858D02*
Y280048D01*
G01D02*
X1247994D01*
G01X1244194Y272458D02*
Y279548D01*
G01D02*
X1247994D01*
G01Y272408D02*
X1244244D01*
G01X1236194Y273458D02*
Y280548D01*
G01D02*
X1239994D01*
G01D02*
Y273458D01*
G01X1236194Y272858D02*
Y280048D01*
G01D02*
X1239994D01*
G01D02*
Y272858D01*
G01X1236194Y272458D02*
Y279548D01*
G01D02*
X1239994D01*
G01D02*
Y272408D01*
G01D02*
X1236244D01*
G01X1231994Y280548D02*
Y273458D01*
G01Y280048D02*
Y272858D01*
G01Y279548D02*
Y272408D01*
G01X1238364Y295312D02*
X1238781Y295819D01*
X1239031Y296389D01*
Y296895D01*
X1238781Y297402D01*
X1238364Y297782D01*
X1237781Y297972D01*
X1237198Y297845D01*
X1236698Y297529D01*
X1236364Y296959D01*
X1236198Y296199D01*
X1235864Y295755D01*
X1235281Y295565D01*
X1234698Y295692D01*
X1234281Y296009D01*
X1234031Y296452D01*
Y296895D01*
X1234198Y297339D01*
X1234614Y297719D01*
G01X1234448Y303135D02*
X1234198Y302755D01*
X1234031Y302312D01*
Y301805D01*
X1234281Y301235D01*
X1234698Y300792D01*
X1235198Y300475D01*
X1236031Y300222D01*
X1236781Y300159D01*
X1237531Y300285D01*
X1238031Y300475D01*
X1238531Y300855D01*
X1238864Y301299D01*
X1239031Y301742D01*
Y302185D01*
X1238864Y302629D01*
X1238614Y303009D01*
X1238281Y303325D01*
G01X1239031Y305195D02*
X1234031D01*
X1238198Y306842D01*
X1234031Y308489D01*
X1239031D01*
G01X1240698Y310042D02*
Y313842D01*
G01X1238364Y315712D02*
X1238781Y316219D01*
X1239031Y316789D01*
Y317295D01*
X1238781Y317802D01*
X1238364Y318182D01*
X1237781Y318372D01*
X1237198Y318245D01*
X1236698Y317929D01*
X1236364Y317359D01*
X1236198Y316599D01*
X1235864Y316155D01*
X1235281Y315965D01*
X1234698Y316092D01*
X1234281Y316409D01*
X1234031Y316852D01*
Y317295D01*
X1234198Y317739D01*
X1234614Y318119D01*
G01X1239031Y322142D02*
X1236781D01*
X1234031Y320875D01*
G01Y323409D02*
X1236781Y322142D01*
G01X1238364Y325912D02*
X1238781Y326419D01*
X1239031Y326989D01*
Y327495D01*
X1238781Y328002D01*
X1238364Y328382D01*
X1237781Y328572D01*
X1237198Y328445D01*
X1236698Y328129D01*
X1236364Y327559D01*
X1236198Y326799D01*
X1235864Y326355D01*
X1235281Y326165D01*
X1234698Y326292D01*
X1234281Y326609D01*
X1234031Y327052D01*
Y327495D01*
X1234198Y327939D01*
X1234614Y328319D01*
G01X1240698Y330442D02*
Y334242D01*
G01X1239031Y336175D02*
X1234031D01*
Y337695D01*
X1234281Y338202D01*
X1234864Y338582D01*
X1235531Y338709D01*
X1236198Y338582D01*
X1236698Y338265D01*
X1236948Y337695D01*
Y336175D01*
G01X1234031Y340642D02*
X1239031Y341529D01*
X1234031Y342542D01*
X1239031Y343555D01*
X1234031Y344442D01*
G01X1239031Y346375D02*
X1234031D01*
Y347959D01*
X1234281Y348465D01*
X1234614Y348782D01*
X1235281Y348909D01*
X1235948Y348782D01*
X1236364Y348402D01*
X1236614Y347959D01*
Y346375D01*
G01Y347959D02*
X1239031Y348909D01*
G01Y352742D02*
X1238948Y352235D01*
X1238614Y351792D01*
X1238114Y351412D01*
X1237531Y351159D01*
X1236864Y351032D01*
X1236198D01*
X1235531Y351159D01*
X1234948Y351412D01*
X1234448Y351792D01*
X1234114Y352235D01*
X1234031Y352742D01*
X1234114Y353249D01*
X1234448Y353692D01*
X1234948Y354072D01*
X1235531Y354325D01*
X1236198Y354452D01*
X1236864D01*
X1237531Y354325D01*
X1238114Y354072D01*
X1238614Y353692D01*
X1238948Y353249D01*
X1239031Y352742D01*
G01Y356449D02*
X1234031D01*
G01Y358855D02*
X1237114Y356449D01*
G01X1239031Y359235D02*
X1235698Y357525D01*
G01X1247631Y295375D02*
X1242631D01*
Y296895D01*
X1242881Y297402D01*
X1243464Y297782D01*
X1244131Y297909D01*
X1244798Y297782D01*
X1245298Y297465D01*
X1245548Y296895D01*
Y295375D01*
G01X1246881Y300349D02*
X1247298Y300729D01*
X1247548Y301172D01*
X1247631Y301742D01*
X1247464Y302312D01*
X1247131Y302755D01*
X1246548Y303072D01*
X1245881Y303135D01*
X1245214Y303009D01*
X1244798Y302692D01*
X1244464Y302249D01*
X1244381Y301805D01*
X1244464Y301362D01*
X1244798Y300792D01*
X1242631Y300982D01*
Y302692D01*
G01Y305259D02*
X1247631Y306842D01*
X1242631Y308425D01*
G01X1241554Y428855D02*
Y425655D01*
G01X1235354Y428855D02*
X1241554D01*
G01X1235354Y425655D02*
Y428855D01*
G01X1241554Y425655D02*
X1235354D01*
G01X1241554Y436855D02*
Y433655D01*
G01X1235354D02*
Y436855D01*
G01X1241554Y433655D02*
X1235354D01*
G01X1241554Y432855D02*
Y429655D01*
G01X1235354Y432855D02*
X1241554D01*
G01X1235354Y429655D02*
Y432855D01*
G01X1241554Y429655D02*
X1235354D01*
G01Y445655D02*
Y448855D01*
G01X1241554Y445655D02*
X1235354D01*
G01X1241554Y448855D02*
Y445655D01*
G01Y440855D02*
Y437655D01*
G01X1235354Y440855D02*
X1241554D01*
G01X1235354Y437655D02*
Y440855D01*
G01X1241554Y437655D02*
X1235354D01*
G01Y441655D02*
Y444855D01*
G01X1241554Y441655D02*
X1235354D01*
G01X1241554Y444855D02*
Y441655D01*
G01X1235354Y444855D02*
X1241554D01*
G01X1235354Y436855D02*
X1241554D01*
G01X1235354Y448855D02*
X1241554D01*
G01X1235302Y453033D02*
Y472719D01*
G01X1244227Y469752D02*
X1250427D01*
G01Y466552D02*
X1244227D01*
G01D02*
Y469752D01*
G01X1235302Y472719D02*
X1232345D01*
G01X1232945Y781811D02*
Y803200D01*
G01X1600661Y781811D02*
X1232945D01*
G01Y818200D02*
Y833200D01*
G01Y850800D02*
Y867900D01*
G01Y905400D02*
Y919000D01*
G01Y936200D02*
Y954600D01*
G01Y973100D02*
Y1005600D01*
G01Y1010600D02*
Y1063600D01*
G01Y1079100D02*
Y1098900D01*
G01Y1112200D02*
Y1129300D01*
G01Y1153300D02*
Y1175400D01*
G01Y1190200D02*
Y1212600D01*
G01Y1224100D02*
Y1359960D01*
G01X1239030Y1260543D02*
Y1303851D01*
G01X1244371Y1260543D02*
X1239030D01*
G01X1232945Y1256024D02*
X1417800D01*
G01X1241887Y1308651D02*
Y1305451D01*
G01X1235687Y1308651D02*
X1241887D01*
G01X1235687Y1305451D02*
Y1308651D01*
G01X1241887Y1305451D02*
X1235687D01*
G01X1240453Y1315151D02*
Y1308951D01*
G01D02*
X1237253D01*
G01D02*
Y1315151D01*
G01X1243487Y1307068D02*
Y1309668D01*
G01X1244280Y1307068D02*
X1243487D01*
G01X1239030Y1303851D02*
X1244371D01*
G01X1230567Y1306689D02*
Y1349997D01*
G01X1240430Y1326272D02*
X1237230D01*
G01D02*
Y1332472D01*
G01X1240430Y1328300D02*
Y1326272D01*
G01Y1321972D02*
Y1315772D01*
G01X1237230Y1321972D02*
X1240430D01*
G01X1237230Y1315772D02*
Y1321972D01*
G01X1240430Y1315772D02*
X1237230D01*
G01X1237253Y1315151D02*
X1240453D01*
G01X1243487Y1316279D02*
Y1317977D01*
G01X1244324Y1334903D02*
X1241124D01*
G01X1244324Y1341103D02*
Y1334903D01*
G01X1241124Y1341103D02*
X1244324D01*
G01X1241124Y1334903D02*
Y1341103D01*
G01X1240430Y1332472D02*
Y1331000D01*
G01X1237230Y1332472D02*
X1240430D01*
G01X1243487Y1330690D02*
X1244495D01*
G01X1243487Y1328836D02*
Y1330690D01*
G01X1235116Y1368706D02*
Y1362506D01*
G01X1231916Y1368706D02*
X1235116D01*
G01X1231916Y1362506D02*
Y1368706D01*
G01X1235116Y1362506D02*
X1231916D01*
G01X1231248Y1368716D02*
Y1362516D01*
G01X1232945Y1371330D02*
Y1393819D01*
G01D02*
X1330600D01*
G01X1244600Y1404900D02*
X1238400D01*
G01D02*
Y1408100D01*
G01D02*
X1244600D01*
G01X1246417Y1416862D02*
X1240217D01*
G01D02*
Y1420062D01*
G01X1250100Y1408900D02*
X1243900D01*
G01D02*
Y1412100D01*
G01D02*
X1250100D01*
G01Y1412900D02*
X1243900D01*
G01D02*
Y1416100D01*
G01D02*
X1250100D01*
G01X1232909Y1408091D02*
X1230561D01*
G01X1232909Y1410439D02*
Y1408091D01*
G01X1243400Y1432400D02*
Y1438600D01*
G01X1246600Y1432400D02*
X1243400D01*
G01Y1425400D02*
Y1431600D01*
G01D02*
X1246600D01*
G01Y1425400D02*
X1243400D01*
G01X1246459Y1420762D02*
X1240259D01*
G01D02*
Y1423962D01*
G01D02*
X1246459D01*
G01X1240217Y1420062D02*
X1246417D01*
G01X1230561Y1431909D02*
X1232909D01*
G01D02*
Y1429561D01*
G01X1243400Y1438600D02*
X1246600D01*
G01X1243400Y1439400D02*
Y1445600D01*
G01X1246600Y1439400D02*
X1243400D01*
G01Y1445600D02*
X1246600D01*
G01X1239400Y1439400D02*
Y1445600D01*
G01X1242600D02*
Y1439400D01*
G01D02*
X1239400D01*
G01Y1445600D02*
X1242600D01*
G01X1237804Y1600436D02*
X1237244Y1600811D01*
X1236591Y1601061D01*
X1235844D01*
X1235004Y1600686D01*
X1234351Y1600061D01*
X1233884Y1599311D01*
X1233511Y1598061D01*
X1233418Y1596936D01*
X1233604Y1595811D01*
X1233884Y1595061D01*
X1234444Y1594311D01*
X1235098Y1593811D01*
X1235751Y1593561D01*
X1236404D01*
X1237058Y1593811D01*
X1237618Y1594186D01*
X1238084Y1594686D01*
G01X1241384Y1593561D02*
Y1601061D01*
X1243624D01*
X1244371Y1600686D01*
X1244931Y1599811D01*
X1245118Y1598811D01*
X1244931Y1597811D01*
X1244464Y1597061D01*
X1243624Y1596686D01*
X1241384D01*
G01X1248698Y1601061D02*
Y1595686D01*
X1249071Y1594561D01*
X1249818Y1593811D01*
X1250751Y1593561D01*
X1251684Y1593811D01*
X1252431Y1594561D01*
X1252804Y1595686D01*
Y1601061D01*
G01X1258251D02*
X1257504Y1600811D01*
X1256944Y1600186D01*
X1256571Y1599436D01*
X1256291Y1598436D01*
X1256198Y1597311D01*
X1256291Y1596186D01*
X1256571Y1595186D01*
X1256944Y1594436D01*
X1257504Y1593811D01*
X1258251Y1593561D01*
X1258998Y1593811D01*
X1259558Y1594436D01*
X1259931Y1595186D01*
X1260211Y1596186D01*
X1260304Y1597311D01*
X1260211Y1598436D01*
X1259931Y1599436D01*
X1259558Y1600186D01*
X1258998Y1600811D01*
X1258251Y1601061D01*
G01X1278884Y1593561D02*
Y1601061D01*
X1281124D01*
X1281871Y1600686D01*
X1282431Y1599811D01*
X1282618Y1598811D01*
X1282431Y1597811D01*
X1281964Y1597061D01*
X1281124Y1596686D01*
X1278884D01*
G01X1290304Y1600436D02*
X1289744Y1600811D01*
X1289091Y1601061D01*
X1288344D01*
X1287504Y1600686D01*
X1286851Y1600061D01*
X1286384Y1599311D01*
X1286011Y1598061D01*
X1285918Y1596936D01*
X1286104Y1595811D01*
X1286384Y1595061D01*
X1286944Y1594311D01*
X1287598Y1593811D01*
X1288251Y1593561D01*
X1288904D01*
X1289558Y1593811D01*
X1290118Y1594186D01*
X1290584Y1594686D01*
G01X1294631Y1601061D02*
X1296871D01*
G01X1295751D02*
Y1593561D01*
G01X1294631D02*
X1296871D01*
G01X1301851Y1596936D02*
X1304838D01*
X1304558Y1597811D01*
X1304091Y1598311D01*
X1303438Y1598561D01*
X1302784Y1598436D01*
X1302224Y1598061D01*
X1301851Y1597186D01*
X1301664Y1596436D01*
Y1595686D01*
X1301851Y1594936D01*
X1302318Y1594186D01*
X1302878Y1593686D01*
X1303531Y1593561D01*
X1304184Y1593811D01*
X1304838Y1594561D01*
G01X1323884Y1593561D02*
Y1601061D01*
X1326124D01*
X1326871Y1600686D01*
X1327431Y1599811D01*
X1327618Y1598811D01*
X1327431Y1597811D01*
X1326964Y1597061D01*
X1326124Y1596686D01*
X1323884D01*
G01X1333251Y1601061D02*
X1332504Y1600811D01*
X1331944Y1600186D01*
X1331571Y1599436D01*
X1331291Y1598436D01*
X1331198Y1597311D01*
X1331291Y1596186D01*
X1331571Y1595186D01*
X1331944Y1594436D01*
X1332504Y1593811D01*
X1333251Y1593561D01*
X1333998Y1593811D01*
X1334558Y1594436D01*
X1334931Y1595186D01*
X1335211Y1596186D01*
X1335304Y1597311D01*
X1335211Y1598436D01*
X1334931Y1599436D01*
X1334558Y1600186D01*
X1333998Y1600811D01*
X1333251Y1601061D01*
G01X1348064Y1592186D02*
X1348438Y1593811D01*
G01X1361384Y1593561D02*
Y1601061D01*
X1363624D01*
X1364371Y1600686D01*
X1364931Y1599811D01*
X1365118Y1598811D01*
X1364931Y1597811D01*
X1364464Y1597061D01*
X1363624Y1596686D01*
X1361384D01*
G01X1370751Y1593561D02*
Y1601061D01*
X1369631Y1599561D01*
G01Y1593561D02*
X1371871D01*
G01X1240611Y1656012D02*
X1237511D01*
X1238131Y1655552D01*
G01X1240611D02*
Y1656472D01*
G01X1243000Y1646023D02*
X1236400D01*
G01X1233857Y1736118D02*
Y1657834D01*
G01X1237000D02*
X1242900D01*
G01X1233857Y1740118D02*
X1300392D01*
G01X1240878Y1736412D02*
X1245878D01*
G01X1240878Y1739812D02*
Y1736412D01*
G01X1242878Y1737812D02*
X1240878Y1739812D01*
G01X1238878Y1737812D02*
X1242878D01*
G01X1240878Y1739812D02*
X1238878Y1737812D01*
G01X1257026Y53691D02*
Y72195D01*
G01X1255058Y70227D02*
Y55660D01*
G01D02*
X1245215D01*
G01D02*
Y53691D01*
G01X1253252Y75646D02*
X1253444Y75336D01*
X1253674Y75129D01*
X1253942Y75026D01*
X1254249Y75129D01*
X1254479Y75336D01*
X1254709Y75646D01*
X1254786Y76059D01*
Y78126D01*
G01X1257119Y75026D02*
X1257387Y75078D01*
X1257694Y75233D01*
X1257886Y75491D01*
X1257962Y75853D01*
X1257886Y76214D01*
X1257656Y76524D01*
X1257311Y76679D01*
X1256927D01*
X1256697Y76783D01*
X1256506Y77041D01*
X1256429Y77403D01*
X1256544Y77764D01*
X1256812Y78023D01*
X1257119Y78126D01*
X1257426Y78023D01*
X1257694Y77764D01*
X1257809Y77403D01*
X1257732Y77041D01*
X1257541Y76783D01*
X1257311Y76679D01*
X1256927D01*
X1256582Y76524D01*
X1256352Y76214D01*
X1256276Y75853D01*
X1256352Y75491D01*
X1256544Y75233D01*
X1256851Y75078D01*
X1257119Y75026D01*
G01X1251552Y85795D02*
Y91995D01*
G01X1254752D02*
Y85795D01*
G01D02*
X1251552D01*
G01X1261072Y85764D02*
X1257872D01*
G01D02*
Y91964D01*
G01X1249832Y100710D02*
Y87710D01*
G01X1251552Y96425D02*
Y102625D01*
G01D02*
X1254752D01*
G01D02*
Y96425D01*
G01D02*
X1251552D01*
G01Y91995D02*
X1254752D01*
G01X1257872Y91964D02*
X1261072D01*
G01X1246293Y129839D02*
Y126639D01*
G01Y138839D02*
Y135639D01*
G01Y134339D02*
Y131139D01*
G01Y125339D02*
Y122139D01*
G01Y146839D02*
Y143639D01*
G01X1256507Y154130D02*
Y157330D01*
G01X1262707Y154130D02*
X1256507D01*
G01Y157330D02*
X1262707D01*
G01X1256507Y162451D02*
Y165651D01*
G01X1262707Y162451D02*
X1256507D01*
G01Y158451D02*
Y161651D01*
G01X1262707Y158451D02*
X1256507D01*
G01Y161651D02*
X1262707D01*
G01X1256507Y177651D02*
X1262707D01*
G01Y174451D02*
X1256507D01*
G01D02*
Y177651D01*
G01X1262707Y178951D02*
X1256507D01*
G01D02*
Y182151D01*
G01Y165651D02*
X1262707D01*
G01X1256507Y166451D02*
Y169651D01*
G01X1262707Y166451D02*
X1256507D01*
G01Y169651D02*
X1262707D01*
G01X1256507Y170451D02*
Y173651D01*
G01X1262707Y170451D02*
X1256507D01*
G01Y173651D02*
X1262707D01*
G01X1256507Y182151D02*
X1262707D01*
G01X1256507Y183451D02*
Y186651D01*
G01X1262707Y183451D02*
X1256507D01*
G01Y186651D02*
X1262707D01*
G01X1256693Y238644D02*
Y239544D01*
G01X1270079Y233307D02*
X1256693D01*
G01D02*
Y234544D01*
G01Y254881D02*
X1270079D01*
G01X1256693Y253644D02*
Y254881D01*
G01Y248644D02*
Y249544D01*
G01Y243644D02*
Y244544D01*
G01X1260766Y260794D02*
X1257666D01*
Y261560D01*
X1257821Y261867D01*
X1258028Y262097D01*
X1258338Y262289D01*
X1258699Y262442D01*
X1259216Y262480D01*
X1259733Y262442D01*
X1260094Y262289D01*
X1260404Y262097D01*
X1260611Y261867D01*
X1260766Y261560D01*
Y260794D01*
G01X1260404Y264085D02*
X1260663Y264354D01*
X1260766Y264660D01*
X1260663Y264967D01*
X1260353Y265235D01*
X1259888Y265427D01*
X1259423Y265504D01*
X1258854D01*
X1258389Y265427D01*
X1257976Y265235D01*
X1257769Y265005D01*
X1257666Y264737D01*
X1257769Y264430D01*
X1257976Y264200D01*
X1258286Y264047D01*
X1258699Y263970D01*
X1259061Y264047D01*
X1259423Y264239D01*
X1259629Y264469D01*
X1259681Y264737D01*
X1259578Y265044D01*
X1259319Y265274D01*
X1258854Y265504D01*
G01X1259474Y267109D02*
X1259113Y267377D01*
X1258906Y267607D01*
X1258803Y267914D01*
X1258906Y268182D01*
X1259113Y268374D01*
X1259423Y268527D01*
X1259784Y268565D01*
X1260094Y268527D01*
X1260404Y268374D01*
X1260663Y268144D01*
X1260766Y267875D01*
X1260663Y267569D01*
X1260353Y267300D01*
X1259888Y267147D01*
X1259371Y267109D01*
X1258699Y267185D01*
X1258338Y267300D01*
X1257976Y267492D01*
X1257718Y267760D01*
X1257666Y268029D01*
X1257769Y268297D01*
X1258028Y268489D01*
G01X1252766Y260794D02*
X1249666D01*
Y261560D01*
X1249821Y261867D01*
X1250028Y262097D01*
X1250338Y262289D01*
X1250699Y262442D01*
X1251216Y262480D01*
X1251733Y262442D01*
X1252094Y262289D01*
X1252404Y262097D01*
X1252611Y261867D01*
X1252766Y261560D01*
Y260794D01*
G01X1252404Y264085D02*
X1252663Y264354D01*
X1252766Y264660D01*
X1252663Y264967D01*
X1252353Y265235D01*
X1251888Y265427D01*
X1251423Y265504D01*
X1250854D01*
X1250389Y265427D01*
X1249976Y265235D01*
X1249769Y265005D01*
X1249666Y264737D01*
X1249769Y264430D01*
X1249976Y264200D01*
X1250286Y264047D01*
X1250699Y263970D01*
X1251061Y264047D01*
X1251423Y264239D01*
X1251629Y264469D01*
X1251681Y264737D01*
X1251578Y265044D01*
X1251319Y265274D01*
X1250854Y265504D01*
G01X1252766Y267837D02*
X1249666D01*
X1250286Y267377D01*
G01X1252766D02*
Y268297D01*
G01X1247994Y280548D02*
Y273458D01*
G01Y280048D02*
Y272858D01*
G01Y279548D02*
Y272408D01*
G01X1252194Y273458D02*
Y280548D01*
G01D02*
X1255994D01*
G01D02*
Y273458D01*
G01X1252194Y272858D02*
Y280048D01*
G01D02*
X1255994D01*
G01D02*
Y272858D01*
G01X1252194Y272458D02*
Y279548D01*
G01D02*
X1255994D01*
G01D02*
Y272408D01*
G01D02*
X1252244D01*
G01X1255231Y295375D02*
X1250231D01*
Y296895D01*
X1250481Y297402D01*
X1251064Y297782D01*
X1251731Y297909D01*
X1252398Y297782D01*
X1252898Y297465D01*
X1253148Y296895D01*
Y295375D01*
G01X1254231Y300349D02*
X1254814Y300729D01*
X1255148Y301235D01*
X1255231Y301805D01*
X1255148Y302312D01*
X1254731Y302819D01*
X1254231Y303135D01*
X1253731Y303199D01*
X1253148Y303072D01*
X1252731Y302629D01*
X1252564Y302185D01*
Y301615D01*
G01Y302185D02*
X1252314Y302565D01*
X1251898Y302882D01*
X1251398Y303009D01*
X1250898Y302882D01*
X1250481Y302565D01*
X1250231Y301995D01*
X1250314Y301425D01*
X1250648Y300855D01*
G01X1250231Y305259D02*
X1255231Y306842D01*
X1250231Y308425D01*
G01X1254231Y310549D02*
X1254814Y310929D01*
X1255148Y311435D01*
X1255231Y312005D01*
X1255148Y312512D01*
X1254731Y313019D01*
X1254231Y313335D01*
X1253731Y313399D01*
X1253148Y313272D01*
X1252731Y312829D01*
X1252564Y312385D01*
Y311815D01*
G01Y312385D02*
X1252314Y312765D01*
X1251898Y313082D01*
X1251398Y313209D01*
X1250898Y313082D01*
X1250481Y312765D01*
X1250231Y312195D01*
X1250314Y311625D01*
X1250648Y311055D01*
G01X1262831Y295375D02*
X1257831D01*
Y296895D01*
X1258081Y297402D01*
X1258664Y297782D01*
X1259331Y297909D01*
X1259998Y297782D01*
X1260498Y297465D01*
X1260748Y296895D01*
Y295375D01*
G01X1257831Y299842D02*
X1262831Y300729D01*
X1257831Y301742D01*
X1262831Y302755D01*
X1257831Y303642D01*
G01X1262831Y305575D02*
X1257831D01*
Y307159D01*
X1258081Y307665D01*
X1258414Y307982D01*
X1259081Y308109D01*
X1259748Y307982D01*
X1260164Y307602D01*
X1260414Y307159D01*
Y305575D01*
G01Y307159D02*
X1262831Y308109D01*
G01X1260331Y312322D02*
Y313589D01*
X1261831D01*
X1262331Y313209D01*
X1262664Y312765D01*
X1262831Y312132D01*
X1262664Y311499D01*
X1262331Y311055D01*
X1261831Y310675D01*
X1261248Y310422D01*
X1260581Y310295D01*
X1259998D01*
X1259498Y310422D01*
X1258914Y310675D01*
X1258414Y311055D01*
X1258081Y311435D01*
X1257831Y311942D01*
Y312385D01*
X1257998Y312892D01*
X1258331Y313272D01*
G01X1262831Y315649D02*
X1257831D01*
Y316915D01*
X1258081Y317422D01*
X1258414Y317802D01*
X1258914Y318119D01*
X1259498Y318372D01*
X1260331Y318435D01*
X1261164Y318372D01*
X1261748Y318119D01*
X1262248Y317802D01*
X1262581Y317422D01*
X1262831Y316915D01*
Y315649D01*
G01X1264498Y320242D02*
Y324042D01*
G01X1262831Y325975D02*
X1257831D01*
Y327495D01*
X1258081Y328002D01*
X1258664Y328382D01*
X1259331Y328509D01*
X1259998Y328382D01*
X1260498Y328065D01*
X1260748Y327495D01*
Y325975D01*
G01X1262831Y332342D02*
X1257831D01*
X1258831Y331582D01*
G01X1262831D02*
Y333102D01*
G01X1257831Y335859D02*
X1262831Y337442D01*
X1257831Y339025D01*
G01X1262831Y342542D02*
X1262748Y342985D01*
X1262498Y343492D01*
X1262081Y343809D01*
X1261498Y343935D01*
X1260914Y343809D01*
X1260414Y343429D01*
X1260164Y342859D01*
Y342225D01*
X1259998Y341845D01*
X1259581Y341529D01*
X1258998Y341402D01*
X1258414Y341592D01*
X1257998Y342035D01*
X1257831Y342542D01*
X1257998Y343049D01*
X1258414Y343492D01*
X1258998Y343682D01*
X1259581Y343555D01*
X1259998Y343239D01*
X1260164Y342859D01*
Y342225D01*
X1260414Y341655D01*
X1260914Y341275D01*
X1261498Y341149D01*
X1262081Y341275D01*
X1262498Y341592D01*
X1262748Y342099D01*
X1262831Y342542D01*
G01X1264498Y345742D02*
Y349542D01*
G01X1262831Y351159D02*
X1257831Y352742D01*
X1262831Y354325D01*
G01X1261081Y353755D02*
Y351729D01*
G01X1257831Y356449D02*
X1261414D01*
X1262164Y356702D01*
X1262664Y357209D01*
X1262831Y357842D01*
X1262664Y358475D01*
X1262164Y358982D01*
X1261414Y359235D01*
X1257831D01*
G01X1262831Y361612D02*
X1257831Y364272D01*
G01Y361612D02*
X1262831Y364272D01*
G01X1263547Y457582D02*
X1257347D01*
G01D02*
Y460782D01*
G01D02*
X1263547D01*
G01X1263617Y452772D02*
X1257417D01*
G01D02*
Y455972D01*
G01D02*
X1263617D01*
G01X1259547Y462772D02*
X1253347D01*
G01D02*
Y465972D01*
G01X1254662Y454782D02*
Y451582D01*
G01X1248462Y454782D02*
X1254662D01*
G01X1248462Y451582D02*
Y454782D01*
G01X1254662Y451582D02*
X1248462D01*
G01X1254662Y459782D02*
Y456582D01*
G01X1248462Y459782D02*
X1254662D01*
G01X1248462Y456582D02*
Y459782D01*
G01X1254662Y456582D02*
X1248462D01*
G01X1250427Y469752D02*
Y466552D01*
G01X1253347Y465972D02*
X1259547D01*
G01X1249168Y653654D02*
Y656754D01*
G01X1250778D02*
Y653654D01*
G01Y655204D02*
X1249168D01*
G01X1253073Y653654D02*
Y656754D01*
X1252613Y656134D01*
G01Y653654D02*
X1253533D01*
G01X1256173Y656754D02*
X1255866Y656651D01*
X1255636Y656392D01*
X1255483Y656082D01*
X1255368Y655669D01*
X1255330Y655204D01*
X1255368Y654739D01*
X1255483Y654326D01*
X1255636Y654016D01*
X1255866Y653757D01*
X1256173Y653654D01*
X1256480Y653757D01*
X1256710Y654016D01*
X1256863Y654326D01*
X1256978Y654739D01*
X1257016Y655204D01*
X1256978Y655669D01*
X1256863Y656082D01*
X1256710Y656392D01*
X1256480Y656651D01*
X1256173Y656754D01*
G01X1259273Y653654D02*
Y656754D01*
X1258813Y656134D01*
G01Y653654D02*
X1259733D01*
G01X1258385Y759390D02*
Y753190D01*
X1255185D01*
Y759390D01*
X1258385D01*
G01Y762540D02*
Y756340D01*
X1255185D01*
Y762540D01*
X1258385D01*
G01X1254400Y763400D02*
Y766600D01*
G01X1260600Y763400D02*
X1254400D01*
G01Y766600D02*
X1260600D01*
G01X1258996Y1341086D02*
Y1344286D01*
G01X1265196Y1341086D02*
X1258996D01*
G01X1258761Y1340293D02*
X1261961D01*
G01X1258761Y1334093D02*
Y1340293D01*
G01X1261961Y1334093D02*
X1258761D01*
G01X1245094Y1337797D02*
Y1340997D01*
G01X1251294Y1337797D02*
X1245094D01*
G01X1251294Y1340997D02*
Y1337797D01*
G01X1245094Y1340997D02*
X1251294D01*
G01X1257919Y1334093D02*
X1254719D01*
G01X1257919Y1340293D02*
Y1334093D01*
G01X1254719Y1340293D02*
X1257919D01*
G01X1254719Y1334093D02*
Y1340293D01*
G01X1258996Y1344286D02*
X1265196D01*
G01X1250315Y1373435D02*
Y1376535D01*
G01X1251925D02*
Y1373435D01*
G01Y1374985D02*
X1250315D01*
G01X1253377Y1374055D02*
X1253607Y1373693D01*
X1253913Y1373487D01*
X1254258Y1373435D01*
X1254565Y1373487D01*
X1254872Y1373745D01*
X1255063Y1374055D01*
X1255102Y1374365D01*
X1255025Y1374727D01*
X1254757Y1374985D01*
X1254488Y1375088D01*
X1254143D01*
G01X1254488D02*
X1254718Y1375243D01*
X1254910Y1375502D01*
X1254987Y1375812D01*
X1254910Y1376122D01*
X1254718Y1376380D01*
X1254373Y1376535D01*
X1254028Y1376483D01*
X1253683Y1376277D01*
G01X1257243Y1373435D02*
X1257320Y1374107D01*
X1257435Y1374675D01*
X1257588Y1375192D01*
X1257780Y1375760D01*
X1258087Y1376535D01*
X1256553D01*
G01X1245400Y1401900D02*
Y1408100D01*
G01X1248600D02*
Y1401900D01*
G01D02*
X1245400D01*
G01X1244600Y1408100D02*
Y1404900D01*
G01X1246417Y1420062D02*
Y1416862D01*
G01X1245400Y1408100D02*
X1248600D01*
G01X1250100Y1412100D02*
Y1408900D01*
G01Y1416100D02*
Y1412900D01*
G01X1250600Y1438600D02*
Y1432400D01*
G01D02*
X1247400D01*
G01D02*
Y1438600D01*
G01X1246600D02*
Y1432400D01*
G01Y1431600D02*
Y1425400D01*
G01X1250459Y1418400D02*
X1247259D01*
G01D02*
Y1424600D01*
G01D02*
X1250459D01*
G01D02*
Y1418400D01*
G01X1246459Y1423962D02*
Y1420762D01*
G01X1251400Y1432400D02*
Y1438600D01*
G01X1254600D02*
Y1432400D01*
G01D02*
X1251400D01*
G01X1254459Y1418400D02*
X1251259D01*
G01D02*
Y1424600D01*
G01D02*
X1254459D01*
G01D02*
Y1418400D01*
G01X1255259D02*
Y1424600D01*
G01D02*
X1258459D01*
G01D02*
Y1418400D01*
G01D02*
X1255259D01*
G01X1247400Y1425400D02*
Y1431600D01*
G01D02*
X1250600D01*
G01D02*
Y1425400D01*
G01D02*
X1247400D01*
G01X1254600Y1431600D02*
Y1425400D01*
G01D02*
X1251400D01*
G01D02*
Y1431600D01*
G01D02*
X1254600D01*
G01X1247400Y1438600D02*
X1250600D01*
G01X1246600Y1445600D02*
Y1439400D01*
G01X1251400Y1438600D02*
X1254600D01*
G01X1290998Y1602365D02*
X1255258D01*
Y1619295D01*
X1290998D01*
Y1602365D01*
G01X1250040Y1620527D02*
X1252466D01*
G01X1260192Y1620605D02*
X1257766D01*
G01X1255543Y1654462D02*
X1255905Y1654692D01*
X1256111Y1654998D01*
X1256163Y1655343D01*
X1256111Y1655650D01*
X1255853Y1655957D01*
X1255543Y1656148D01*
X1255233Y1656187D01*
X1254871Y1656110D01*
X1254613Y1655842D01*
X1254510Y1655573D01*
Y1655228D01*
G01Y1655573D02*
X1254355Y1655803D01*
X1254096Y1655995D01*
X1253786Y1656072D01*
X1253476Y1655995D01*
X1253218Y1655803D01*
X1253063Y1655458D01*
X1253115Y1655113D01*
X1253321Y1654768D01*
G01X1249304Y1654769D02*
X1248994Y1654999D01*
X1248839Y1655267D01*
X1248787Y1655574D01*
X1248890Y1655957D01*
X1249149Y1656225D01*
X1249459Y1656302D01*
X1249769Y1656264D01*
X1250027Y1656110D01*
X1250544Y1655344D01*
X1250905Y1654999D01*
X1251422Y1654769D01*
X1251887Y1654692D01*
Y1656302D01*
G01X1255300Y1646023D02*
X1248500D01*
G01X1249100Y1657834D02*
X1255000D01*
G01X1248961Y1736629D02*
X1247895D01*
Y1739129D01*
X1248961D01*
G01X1248535Y1737921D02*
X1247895D01*
G01X1250041Y1736629D02*
Y1739129D01*
X1250575D01*
X1250788Y1739004D01*
X1250948Y1738837D01*
X1251081Y1738587D01*
X1251188Y1738296D01*
X1251215Y1737879D01*
X1251188Y1737462D01*
X1251081Y1737171D01*
X1250948Y1736921D01*
X1250788Y1736754D01*
X1250575Y1736629D01*
X1250041D01*
G01X1252988Y1737879D02*
X1253521D01*
Y1737129D01*
X1253361Y1736879D01*
X1253175Y1736712D01*
X1252908Y1736629D01*
X1252641Y1736712D01*
X1252455Y1736879D01*
X1252295Y1737129D01*
X1252188Y1737421D01*
X1252135Y1737754D01*
Y1738046D01*
X1252188Y1738296D01*
X1252295Y1738587D01*
X1252455Y1738837D01*
X1252615Y1739004D01*
X1252828Y1739129D01*
X1253015D01*
X1253228Y1739046D01*
X1253388Y1738879D01*
G01X1255561Y1736629D02*
X1254495D01*
Y1739129D01*
X1255561D01*
G01X1255135Y1737921D02*
X1254495D01*
G01X1259428Y1736629D02*
X1259215Y1736671D01*
X1259028Y1736837D01*
X1258868Y1737087D01*
X1258761Y1737379D01*
X1258708Y1737712D01*
Y1738046D01*
X1258761Y1738379D01*
X1258868Y1738671D01*
X1259028Y1738921D01*
X1259215Y1739087D01*
X1259428Y1739129D01*
X1259641Y1739087D01*
X1259828Y1738921D01*
X1259988Y1738671D01*
X1260095Y1738379D01*
X1260148Y1738046D01*
Y1737712D01*
X1260095Y1737379D01*
X1259988Y1737087D01*
X1259828Y1736837D01*
X1259641Y1736671D01*
X1259428Y1736629D01*
G01X1261121D02*
Y1739129D01*
X1262135D01*
G01X1261761Y1737921D02*
X1261121D01*
G01X1265441Y1736629D02*
Y1739129D01*
X1265975D01*
X1266188Y1739004D01*
X1266348Y1738837D01*
X1266481Y1738587D01*
X1266588Y1738296D01*
X1266615Y1737879D01*
X1266588Y1737462D01*
X1266481Y1737171D01*
X1266348Y1736921D01*
X1266188Y1736754D01*
X1265975Y1736629D01*
X1265441D01*
G01X1267561D02*
X1268228Y1739129D01*
X1268895Y1736629D01*
G01X1268655Y1737504D02*
X1267801D01*
G01X1269841Y1739129D02*
Y1737337D01*
X1269948Y1736962D01*
X1270161Y1736712D01*
X1270428Y1736629D01*
X1270695Y1736712D01*
X1270908Y1736962D01*
X1271015Y1737337D01*
Y1739129D01*
G01X1272788Y1737879D02*
X1273321D01*
Y1737129D01*
X1273161Y1736879D01*
X1272975Y1736712D01*
X1272708Y1736629D01*
X1272441Y1736712D01*
X1272255Y1736879D01*
X1272095Y1737129D01*
X1271988Y1737421D01*
X1271935Y1737754D01*
Y1738046D01*
X1271988Y1738296D01*
X1272095Y1738587D01*
X1272255Y1738837D01*
X1272415Y1739004D01*
X1272628Y1739129D01*
X1272815D01*
X1273028Y1739046D01*
X1273188Y1738879D01*
G01X1274268Y1736629D02*
Y1739129D01*
G01X1275388D02*
Y1736629D01*
G01Y1737879D02*
X1274268D01*
G01X1277028Y1739129D02*
Y1736629D01*
G01X1276415Y1739129D02*
X1277641D01*
G01X1279761Y1736629D02*
X1278695D01*
Y1739129D01*
X1279761D01*
G01X1279335Y1737921D02*
X1278695D01*
G01X1280895Y1736629D02*
Y1739129D01*
X1281561D01*
X1281775Y1739004D01*
X1281908Y1738837D01*
X1281961Y1738504D01*
X1281908Y1738171D01*
X1281748Y1737962D01*
X1281561Y1737837D01*
X1280895D01*
G01X1281561D02*
X1281961Y1736629D01*
G01X1286415Y1738921D02*
X1286255Y1739046D01*
X1286068Y1739129D01*
X1285855D01*
X1285615Y1739004D01*
X1285428Y1738796D01*
X1285295Y1738546D01*
X1285188Y1738129D01*
X1285161Y1737754D01*
X1285215Y1737379D01*
X1285295Y1737129D01*
X1285455Y1736879D01*
X1285641Y1736712D01*
X1285828Y1736629D01*
X1286015D01*
X1286201Y1736712D01*
X1286361Y1736837D01*
X1286495Y1737004D01*
G01X1287361Y1736629D02*
X1288028Y1739129D01*
X1288695Y1736629D01*
G01X1288455Y1737504D02*
X1287601D01*
G01X1289695Y1736629D02*
Y1739129D01*
X1290361D01*
X1290575Y1739004D01*
X1290708Y1738837D01*
X1290761Y1738504D01*
X1290708Y1738171D01*
X1290548Y1737962D01*
X1290361Y1737837D01*
X1289695D01*
G01X1290361D02*
X1290761Y1736629D01*
G01X1291841D02*
Y1739129D01*
X1292375D01*
X1292588Y1739004D01*
X1292748Y1738837D01*
X1292881Y1738587D01*
X1292988Y1738296D01*
X1293015Y1737879D01*
X1292988Y1737462D01*
X1292881Y1737171D01*
X1292748Y1736921D01*
X1292588Y1736754D01*
X1292375Y1736629D01*
X1291841D01*
G01X1245878Y1736412D02*
X1246778Y1737312D01*
G01X1267275Y63641D02*
Y66741D01*
X1268195D01*
X1268502Y66586D01*
X1268732Y66224D01*
X1268809Y65811D01*
X1268732Y65398D01*
X1268540Y65088D01*
X1268195Y64933D01*
X1267275D01*
G01X1271142Y66741D02*
X1270835Y66638D01*
X1270605Y66379D01*
X1270452Y66069D01*
X1270337Y65656D01*
X1270299Y65191D01*
X1270337Y64726D01*
X1270452Y64313D01*
X1270605Y64003D01*
X1270835Y63744D01*
X1271142Y63641D01*
X1271449Y63744D01*
X1271679Y64003D01*
X1271832Y64313D01*
X1271947Y64726D01*
X1271985Y65191D01*
X1271947Y65656D01*
X1271832Y66069D01*
X1271679Y66379D01*
X1271449Y66638D01*
X1271142Y66741D01*
G01X1273092Y62608D02*
X1275392D01*
G01X1276499Y66741D02*
Y64519D01*
X1276652Y64054D01*
X1276959Y63744D01*
X1277342Y63641D01*
X1277725Y63744D01*
X1278032Y64054D01*
X1278185Y64519D01*
Y66741D01*
G01X1279484Y63641D02*
X1280442Y66741D01*
X1281400Y63641D01*
G01X1281055Y64726D02*
X1279829D01*
G01X1282775Y63641D02*
Y66741D01*
X1283734D01*
X1284040Y66586D01*
X1284232Y66379D01*
X1284309Y65966D01*
X1284232Y65553D01*
X1284002Y65294D01*
X1283734Y65139D01*
X1282775D01*
G01X1283734D02*
X1284309Y63641D01*
G01X1286642Y66741D02*
Y63641D01*
G01X1285760Y66741D02*
X1287524D01*
G01X1289742Y63641D02*
Y66741D01*
X1289282Y66121D01*
G01Y63641D02*
X1290202D01*
G01X1261072Y91964D02*
Y85764D01*
G01X1261872D02*
Y91964D01*
G01X1265072D02*
Y85764D01*
G01D02*
X1261872D01*
G01Y91964D02*
X1265072D01*
G01X1263853Y125398D02*
Y123176D01*
X1264006Y122711D01*
X1264313Y122401D01*
X1264696Y122298D01*
X1265079Y122401D01*
X1265386Y122711D01*
X1265539Y123176D01*
Y125398D01*
G01X1267796Y122298D02*
Y125398D01*
X1267336Y124778D01*
G01Y122298D02*
X1268256D01*
G01X1270244Y122660D02*
X1270513Y122401D01*
X1270819Y122298D01*
X1271126Y122401D01*
X1271394Y122711D01*
X1271586Y123176D01*
X1271663Y123641D01*
Y124210D01*
X1271586Y124675D01*
X1271394Y125088D01*
X1271164Y125295D01*
X1270896Y125398D01*
X1270589Y125295D01*
X1270359Y125088D01*
X1270206Y124778D01*
X1270129Y124365D01*
X1270206Y124003D01*
X1270398Y123641D01*
X1270628Y123435D01*
X1270896Y123383D01*
X1271203Y123486D01*
X1271433Y123745D01*
X1271663Y124210D01*
G01X1273153Y122918D02*
X1273383Y122556D01*
X1273689Y122350D01*
X1274034Y122298D01*
X1274341Y122350D01*
X1274648Y122608D01*
X1274839Y122918D01*
X1274878Y123228D01*
X1274801Y123590D01*
X1274533Y123848D01*
X1274264Y123951D01*
X1273919D01*
G01X1274264D02*
X1274494Y124106D01*
X1274686Y124365D01*
X1274763Y124675D01*
X1274686Y124985D01*
X1274494Y125243D01*
X1274149Y125398D01*
X1273804Y125346D01*
X1273459Y125140D01*
G01X1263534Y126500D02*
X1277042D01*
G01X1263534Y146106D02*
Y126500D01*
G01X1277211Y148430D02*
X1271011D01*
G01D02*
Y151630D01*
G01X1274591Y146106D02*
X1270288Y141803D01*
G01X1265985Y146106D02*
X1263534D01*
G01X1270288Y141803D02*
X1265985Y146106D01*
G01X1262707Y157330D02*
Y154130D01*
G01Y165651D02*
Y162451D01*
G01Y161651D02*
Y158451D01*
G01X1277211Y152430D02*
X1271011D01*
G01D02*
Y155630D01*
G01D02*
X1277211D01*
G01X1271011Y151630D02*
X1277211D01*
G01X1274112Y164451D02*
X1267912D01*
Y167651D01*
X1274112D01*
Y164451D01*
G01X1271062Y167651D02*
X1277262D01*
Y164451D01*
X1271062D01*
Y167651D01*
G01X1274112Y160451D02*
X1267912D01*
Y163651D01*
X1274112D01*
Y160451D01*
G01X1271062Y163651D02*
X1277262D01*
Y160451D01*
X1271062D01*
Y163651D01*
G01Y159651D02*
X1277262D01*
Y156451D01*
X1271062D01*
Y159651D01*
G01X1274112Y156451D02*
X1267912D01*
Y159651D01*
X1274112D01*
Y156451D01*
G01X1262707Y177651D02*
Y174451D01*
G01Y182151D02*
Y178951D01*
G01Y169651D02*
Y166451D01*
G01Y173651D02*
Y170451D01*
G01X1267912Y182165D02*
X1274112D01*
Y178965D01*
X1267912D01*
Y182165D01*
G01X1277262Y178965D02*
X1271062D01*
Y182165D01*
X1277262D01*
Y178965D01*
G01X1267912Y177651D02*
X1274112D01*
Y174451D01*
X1267912D01*
Y177651D01*
G01X1277262Y174451D02*
X1271062D01*
Y177651D01*
X1277262D01*
Y174451D01*
G01X1274112Y169951D02*
X1267912D01*
Y173151D01*
X1274112D01*
Y169951D01*
G01X1271062Y173151D02*
X1277262D01*
Y169951D01*
X1271062D01*
Y173151D01*
G01X1262707Y186651D02*
Y183451D01*
G01X1274112Y183387D02*
X1267912D01*
Y186587D01*
X1274112D01*
Y183387D01*
G01X1271062Y186587D02*
X1277262D01*
Y183387D01*
X1271062D01*
Y186587D01*
G01X1270079Y239544D02*
Y238644D01*
G01Y234544D02*
Y233307D01*
G01Y254881D02*
Y253644D01*
G01Y249544D02*
Y248644D01*
G01Y244544D02*
Y243644D01*
G01X1276766Y260794D02*
X1273666D01*
Y261560D01*
X1273821Y261867D01*
X1274028Y262097D01*
X1274338Y262289D01*
X1274699Y262442D01*
X1275216Y262480D01*
X1275733Y262442D01*
X1276094Y262289D01*
X1276404Y262097D01*
X1276611Y261867D01*
X1276766Y261560D01*
Y260794D01*
G01Y264660D02*
X1276094Y264737D01*
X1275526Y264852D01*
X1275009Y265005D01*
X1274441Y265197D01*
X1273666Y265504D01*
Y263970D01*
G01X1276766Y268297D02*
X1273666D01*
X1275888Y266879D01*
Y268795D01*
G01X1268766Y260794D02*
X1265666D01*
Y261560D01*
X1265821Y261867D01*
X1266028Y262097D01*
X1266338Y262289D01*
X1266699Y262442D01*
X1267216Y262480D01*
X1267733Y262442D01*
X1268094Y262289D01*
X1268404Y262097D01*
X1268611Y261867D01*
X1268766Y261560D01*
Y260794D01*
G01Y264660D02*
X1268094Y264737D01*
X1267526Y264852D01*
X1267009Y265005D01*
X1266441Y265197D01*
X1265666Y265504D01*
Y263970D01*
G01X1268146Y266994D02*
X1268508Y267224D01*
X1268714Y267530D01*
X1268766Y267875D01*
X1268714Y268182D01*
X1268456Y268489D01*
X1268146Y268680D01*
X1267836Y268719D01*
X1267474Y268642D01*
X1267216Y268374D01*
X1267113Y268105D01*
Y267760D01*
G01Y268105D02*
X1266958Y268335D01*
X1266699Y268527D01*
X1266389Y268604D01*
X1266079Y268527D01*
X1265821Y268335D01*
X1265666Y267990D01*
X1265718Y267645D01*
X1265924Y267300D01*
G01X1268194Y273458D02*
Y280548D01*
G01D02*
X1271994D01*
G01D02*
Y273458D01*
G01X1268194Y272858D02*
Y280048D01*
G01D02*
X1271994D01*
G01D02*
Y272858D01*
G01X1268194Y272458D02*
Y279548D01*
G01D02*
X1271994D01*
G01D02*
Y272408D01*
G01D02*
X1268244D01*
G01X1260194Y273458D02*
Y280548D01*
G01D02*
X1263994D01*
G01D02*
Y273458D01*
G01X1260194Y272858D02*
Y280048D01*
G01D02*
X1263994D01*
G01D02*
Y272858D01*
G01X1260194Y272458D02*
Y279548D01*
G01D02*
X1263994D01*
G01D02*
Y272408D01*
G01D02*
X1260244D01*
G01X1271231Y295375D02*
X1266231D01*
Y296895D01*
X1266481Y297402D01*
X1267064Y297782D01*
X1267731Y297909D01*
X1268398Y297782D01*
X1268898Y297465D01*
X1269148Y296895D01*
Y295375D01*
G01X1266231Y299842D02*
X1271231Y300729D01*
X1266231Y301742D01*
X1271231Y302755D01*
X1266231Y303642D01*
G01X1271231Y305575D02*
X1266231D01*
Y307159D01*
X1266481Y307665D01*
X1266814Y307982D01*
X1267481Y308109D01*
X1268148Y307982D01*
X1268564Y307602D01*
X1268814Y307159D01*
Y305575D01*
G01Y307159D02*
X1271231Y308109D01*
G01X1268731Y312322D02*
Y313589D01*
X1270231D01*
X1270731Y313209D01*
X1271064Y312765D01*
X1271231Y312132D01*
X1271064Y311499D01*
X1270731Y311055D01*
X1270231Y310675D01*
X1269648Y310422D01*
X1268981Y310295D01*
X1268398D01*
X1267898Y310422D01*
X1267314Y310675D01*
X1266814Y311055D01*
X1266481Y311435D01*
X1266231Y311942D01*
Y312385D01*
X1266398Y312892D01*
X1266731Y313272D01*
G01X1271231Y315649D02*
X1266231D01*
Y316915D01*
X1266481Y317422D01*
X1266814Y317802D01*
X1267314Y318119D01*
X1267898Y318372D01*
X1268731Y318435D01*
X1269564Y318372D01*
X1270148Y318119D01*
X1270648Y317802D01*
X1270981Y317422D01*
X1271231Y316915D01*
Y315649D01*
G01X1272898Y320242D02*
Y324042D01*
G01X1271231Y325975D02*
X1266231D01*
Y327495D01*
X1266481Y328002D01*
X1267064Y328382D01*
X1267731Y328509D01*
X1268398Y328382D01*
X1268898Y328065D01*
X1269148Y327495D01*
Y325975D01*
G01X1270564Y331012D02*
X1270981Y331519D01*
X1271231Y332089D01*
Y332595D01*
X1270981Y333102D01*
X1270564Y333482D01*
X1269981Y333672D01*
X1269398Y333545D01*
X1268898Y333229D01*
X1268564Y332659D01*
X1268398Y331899D01*
X1268064Y331455D01*
X1267481Y331265D01*
X1266898Y331392D01*
X1266481Y331709D01*
X1266231Y332152D01*
Y332595D01*
X1266398Y333039D01*
X1266814Y333419D01*
G01X1272898Y335542D02*
Y339342D01*
G01X1271231Y341275D02*
X1266231D01*
Y342795D01*
X1266481Y343302D01*
X1267064Y343682D01*
X1267731Y343809D01*
X1268398Y343682D01*
X1268898Y343365D01*
X1269148Y342795D01*
Y341275D01*
G01X1266231Y345742D02*
X1271231Y346629D01*
X1266231Y347642D01*
X1271231Y348655D01*
X1266231Y349542D01*
G01X1271231Y351475D02*
X1266231D01*
Y353059D01*
X1266481Y353565D01*
X1266814Y353882D01*
X1267481Y354009D01*
X1268148Y353882D01*
X1268564Y353502D01*
X1268814Y353059D01*
Y351475D01*
G01Y353059D02*
X1271231Y354009D01*
G01Y357842D02*
X1271148Y357335D01*
X1270814Y356892D01*
X1270314Y356512D01*
X1269731Y356259D01*
X1269064Y356132D01*
X1268398D01*
X1267731Y356259D01*
X1267148Y356512D01*
X1266648Y356892D01*
X1266314Y357335D01*
X1266231Y357842D01*
X1266314Y358349D01*
X1266648Y358792D01*
X1267148Y359172D01*
X1267731Y359425D01*
X1268398Y359552D01*
X1269064D01*
X1269731Y359425D01*
X1270314Y359172D01*
X1270814Y358792D01*
X1271148Y358349D01*
X1271231Y357842D01*
G01Y361549D02*
X1266231D01*
G01Y363955D02*
X1269314Y361549D01*
G01X1271231Y364335D02*
X1267898Y362625D01*
G01X1260900Y392100D02*
X1267100D01*
Y388900D01*
X1260900D01*
Y392100D01*
G01X1268949Y389284D02*
Y392484D01*
G01X1275149Y389284D02*
X1268949D01*
G01Y392484D02*
X1275149D01*
G01X1267299Y396725D02*
Y393525D01*
G01X1261099Y396725D02*
X1267299D01*
G01X1261099Y393525D02*
Y396725D01*
G01X1267299Y393525D02*
X1261099D01*
G01X1267302Y400725D02*
Y397525D01*
G01X1261102Y400725D02*
X1267302D01*
G01X1261102Y397525D02*
Y400725D01*
G01X1267302Y397525D02*
X1261102D01*
G01X1273996Y400819D02*
Y402772D01*
G01X1275949Y400819D02*
X1273996D01*
G01X1261102Y409525D02*
Y412725D01*
G01X1267302Y409525D02*
X1261102D01*
G01X1267302Y412725D02*
Y409525D01*
G01X1261102Y412725D02*
X1267302D01*
G01X1261102Y405525D02*
Y408725D01*
G01X1267302Y405525D02*
X1261102D01*
G01X1267302Y408725D02*
Y405525D01*
G01X1261102Y408725D02*
X1267302D01*
G01X1261102Y413525D02*
Y416725D01*
G01X1267302Y413525D02*
X1261102D01*
G01X1267302Y416725D02*
Y413525D01*
G01X1261102Y416725D02*
X1267302D01*
G01X1273996Y412631D02*
X1275949D01*
G01X1273996Y410678D02*
Y412631D01*
G01X1269524Y424966D02*
Y422744D01*
X1269677Y422279D01*
X1269984Y421969D01*
X1270367Y421866D01*
X1270750Y421969D01*
X1271057Y422279D01*
X1271210Y422744D01*
Y424966D01*
G01X1272624Y422331D02*
X1272854Y422073D01*
X1273122Y421918D01*
X1273467Y421866D01*
X1273812Y421969D01*
X1274080Y422176D01*
X1274272Y422538D01*
X1274310Y422951D01*
X1274234Y423364D01*
X1274042Y423623D01*
X1273774Y423829D01*
X1273505Y423881D01*
X1273237Y423829D01*
X1272892Y423623D01*
X1273007Y424966D01*
X1274042D01*
G01X1275839Y424449D02*
X1276069Y424759D01*
X1276337Y424914D01*
X1276644Y424966D01*
X1277027Y424863D01*
X1277295Y424604D01*
X1277372Y424294D01*
X1277334Y423984D01*
X1277180Y423726D01*
X1276414Y423209D01*
X1276069Y422848D01*
X1275839Y422331D01*
X1275762Y421866D01*
X1277372D01*
G01X1263547Y460782D02*
Y457582D01*
G01X1263617Y455972D02*
Y452772D01*
G01X1259547Y465972D02*
Y462772D01*
G01X1272077Y760388D02*
Y766588D01*
G01X1275277Y760388D02*
X1272077D01*
G01X1265306Y759390D02*
Y753190D01*
X1262106D01*
Y759390D01*
X1265306D01*
G01Y762540D02*
Y756340D01*
X1262106D01*
Y762540D01*
X1265306D01*
G01X1267600Y766600D02*
Y763400D01*
G01X1261400Y766600D02*
X1267600D01*
G01X1261400Y763400D02*
Y766600D01*
G01X1267600Y763400D02*
X1261400D01*
G01X1272077Y766588D02*
X1275277D01*
G01X1260600Y766600D02*
Y763400D01*
G01X1265004Y860721D02*
Y902800D01*
G01X1265100Y860721D02*
X1265004D01*
G01Y913900D02*
Y927600D01*
G01Y938800D02*
Y950600D01*
G01Y958300D02*
Y969000D01*
G01Y977700D02*
Y1007100D01*
G01Y1014900D02*
Y1059100D01*
G01Y1069500D02*
Y1082300D01*
G01Y1090800D02*
Y1101400D01*
G01Y1112000D02*
Y1123800D01*
G01Y1135400D02*
Y1172900D01*
G01X1273200Y1177705D02*
X1330000D01*
G01X1271926Y1260458D02*
Y1303766D01*
G01X1277267Y1260458D02*
X1271926D01*
G01X1268558Y1260543D02*
Y1303851D01*
G01X1263217Y1260543D02*
X1268558D01*
G01X1268583Y1308623D02*
X1274783D01*
G01X1268583Y1305423D02*
Y1308623D01*
G01X1274783Y1305423D02*
X1268583D01*
G01X1273349Y1308923D02*
X1270149D01*
G01X1273349Y1315123D02*
Y1308923D01*
G01X1270149D02*
Y1315123D01*
G01X1263173Y1307068D02*
X1262380D01*
G01X1263173Y1309668D02*
Y1307068D01*
G01X1271926Y1303766D02*
X1277267D01*
G01X1268558Y1303851D02*
X1263217D01*
G01X1273326Y1326244D02*
X1270126D01*
G01D02*
Y1332444D01*
G01Y1321944D02*
X1273326D01*
G01X1270126Y1315744D02*
Y1321944D01*
G01X1273326Y1315744D02*
X1270126D01*
G01X1273326Y1321944D02*
Y1315744D01*
G01X1269239Y1322370D02*
Y1316170D01*
G01X1266039Y1322370D02*
X1269239D01*
G01X1266039Y1316170D02*
Y1322370D01*
G01X1269239Y1316170D02*
X1266039D01*
G01X1270149Y1315123D02*
X1273349D01*
G01X1273326Y1332444D02*
Y1329500D01*
G01X1270126Y1332444D02*
X1273326D01*
G01X1277220Y1334875D02*
X1274020D01*
G01Y1341075D02*
X1277220D01*
G01X1274020Y1334875D02*
Y1341075D01*
G01X1273042Y1337712D02*
Y1334512D01*
G01X1266842D02*
Y1337712D01*
G01X1273042Y1334512D02*
X1266842D01*
G01Y1337712D02*
X1273042D01*
G01X1265196Y1344286D02*
Y1341086D01*
G01X1261961Y1340293D02*
Y1334093D01*
G01X1263173Y1330690D02*
Y1328499D01*
G01X1262440Y1330690D02*
X1263173D01*
G01X1266913Y1343351D02*
Y1346451D01*
X1267833D01*
X1268140Y1346296D01*
X1268370Y1345934D01*
X1268447Y1345521D01*
X1268370Y1345108D01*
X1268178Y1344798D01*
X1267833Y1344643D01*
X1266913D01*
G01X1270013Y1346451D02*
Y1343351D01*
X1271547D01*
G01X1273880D02*
Y1346451D01*
X1273420Y1345831D01*
G01Y1343351D02*
X1274340D01*
G01X1277440D02*
Y1346451D01*
X1276022Y1344229D01*
X1277938D01*
G01X1266883Y1347500D02*
Y1350600D01*
X1267803D01*
X1268110Y1350445D01*
X1268340Y1350083D01*
X1268417Y1349670D01*
X1268340Y1349257D01*
X1268148Y1348947D01*
X1267803Y1348792D01*
X1266883D01*
G01X1269907Y1350600D02*
Y1348378D01*
X1270060Y1347913D01*
X1270367Y1347603D01*
X1270750Y1347500D01*
X1271133Y1347603D01*
X1271440Y1347913D01*
X1271593Y1348378D01*
Y1350600D01*
G01X1273850Y1347500D02*
Y1350600D01*
X1273390Y1349980D01*
G01Y1347500D02*
X1274310D01*
G01X1276107Y1347965D02*
X1276337Y1347707D01*
X1276605Y1347552D01*
X1276950Y1347500D01*
X1277295Y1347603D01*
X1277563Y1347810D01*
X1277755Y1348172D01*
X1277793Y1348585D01*
X1277717Y1348998D01*
X1277525Y1349257D01*
X1277257Y1349463D01*
X1276988Y1349515D01*
X1276720Y1349463D01*
X1276375Y1349257D01*
X1276490Y1350600D01*
X1277525D01*
G01X1275070Y1540451D02*
X1267700D01*
G01X1267800Y1575491D02*
X1275070D01*
G01X1264233Y1656472D02*
X1261133D01*
X1263355Y1655054D01*
Y1656970D01*
G01X1274697Y1652510D02*
X1274955Y1652740D01*
X1275110Y1653008D01*
X1275162Y1653353D01*
X1275059Y1653698D01*
X1274852Y1653966D01*
X1274490Y1654158D01*
X1274077Y1654196D01*
X1273664Y1654120D01*
X1273405Y1653928D01*
X1273199Y1653660D01*
X1273147Y1653391D01*
X1273199Y1653123D01*
X1273405Y1652778D01*
X1272062Y1652893D01*
Y1653928D01*
G01X1267500Y1646023D02*
X1260600D01*
G01X1279400D02*
X1272700D01*
G01X1273200Y1657834D02*
X1279000D01*
G01X1261100D02*
X1267000D01*
G01X1286364Y96904D02*
Y90704D01*
G01D02*
X1283164D01*
G01D02*
Y96904D01*
G01X1282364D02*
Y90704D01*
G01D02*
X1279164D01*
G01D02*
Y96904D01*
G01X1277581Y92214D02*
Y86014D01*
G01D02*
X1274381D01*
G01D02*
Y92214D01*
G01X1283164Y96904D02*
X1286364D01*
G01X1279164D02*
X1282364D01*
G01X1274381Y92214D02*
X1277581D01*
G01X1277042Y126500D02*
Y146106D01*
G01X1277211Y151630D02*
Y148430D01*
G01X1277042Y146106D02*
X1274591D01*
G01X1277211Y155630D02*
Y152430D01*
G01X1285007Y160451D02*
Y163651D01*
G01X1291207Y160451D02*
X1285007D01*
G01Y163651D02*
X1291207D01*
G01X1285007Y164451D02*
Y167651D01*
G01X1291207Y164451D02*
X1285007D01*
G01Y167651D02*
X1291207D01*
G01X1285007Y169951D02*
Y173151D01*
G01X1291207Y169951D02*
X1285007D01*
G01Y173151D02*
X1291207D01*
G01X1285007Y182451D02*
Y185651D01*
G01X1291207Y182451D02*
X1285007D01*
G01Y185651D02*
X1291207D01*
G01X1279519Y235581D02*
X1279711Y235271D01*
X1279941Y235064D01*
X1280209Y234961D01*
X1280516Y235064D01*
X1280746Y235271D01*
X1280976Y235581D01*
X1281053Y235994D01*
Y238061D01*
G01X1283846Y234961D02*
Y238061D01*
X1282428Y235839D01*
X1284344D01*
G01X1286486Y234961D02*
X1286754Y235013D01*
X1287061Y235168D01*
X1287253Y235426D01*
X1287329Y235788D01*
X1287253Y236149D01*
X1287023Y236459D01*
X1286678Y236614D01*
X1286294D01*
X1286064Y236718D01*
X1285873Y236976D01*
X1285796Y237338D01*
X1285911Y237699D01*
X1286179Y237958D01*
X1286486Y238061D01*
X1286793Y237958D01*
X1287061Y237699D01*
X1287176Y237338D01*
X1287099Y236976D01*
X1286908Y236718D01*
X1286678Y236614D01*
X1286294D01*
X1285949Y236459D01*
X1285719Y236149D01*
X1285643Y235788D01*
X1285719Y235426D01*
X1285911Y235168D01*
X1286218Y235013D01*
X1286486Y234961D01*
G01X1284766Y260794D02*
X1281666D01*
Y261560D01*
X1281821Y261867D01*
X1282028Y262097D01*
X1282338Y262289D01*
X1282699Y262442D01*
X1283216Y262480D01*
X1283733Y262442D01*
X1284094Y262289D01*
X1284404Y262097D01*
X1284611Y261867D01*
X1284766Y261560D01*
Y260794D01*
G01Y264660D02*
X1284094Y264737D01*
X1283526Y264852D01*
X1283009Y265005D01*
X1282441Y265197D01*
X1281666Y265504D01*
Y263970D01*
G01X1284301Y266994D02*
X1284559Y267224D01*
X1284714Y267492D01*
X1284766Y267837D01*
X1284663Y268182D01*
X1284456Y268450D01*
X1284094Y268642D01*
X1283681Y268680D01*
X1283268Y268604D01*
X1283009Y268412D01*
X1282803Y268144D01*
X1282751Y267875D01*
X1282803Y267607D01*
X1283009Y267262D01*
X1281666Y267377D01*
Y268412D01*
G01X1276194Y273458D02*
Y280548D01*
G01D02*
X1279994D01*
G01D02*
Y273458D01*
G01X1276194Y272858D02*
Y280048D01*
G01D02*
X1279994D01*
G01D02*
Y272858D01*
G01X1276194Y272458D02*
Y279548D01*
G01D02*
X1279994D01*
G01D02*
Y272408D01*
G01D02*
X1276244D01*
G01X1284194Y273458D02*
Y280548D01*
G01D02*
X1287994D01*
G01D02*
Y273458D01*
G01X1284194Y272858D02*
Y280048D01*
G01D02*
X1287994D01*
G01D02*
Y272858D01*
G01X1284194Y272458D02*
Y279548D01*
G01D02*
X1287994D01*
G01D02*
Y272408D01*
G01D02*
X1284244D01*
G01X1279831Y295375D02*
X1274831D01*
Y296895D01*
X1275081Y297402D01*
X1275664Y297782D01*
X1276331Y297909D01*
X1276998Y297782D01*
X1277498Y297465D01*
X1277748Y296895D01*
Y295375D01*
G01X1274831Y299842D02*
X1279831Y300729D01*
X1274831Y301742D01*
X1279831Y302755D01*
X1274831Y303642D01*
G01X1279831Y305575D02*
X1274831D01*
Y307159D01*
X1275081Y307665D01*
X1275414Y307982D01*
X1276081Y308109D01*
X1276748Y307982D01*
X1277164Y307602D01*
X1277414Y307159D01*
Y305575D01*
G01Y307159D02*
X1279831Y308109D01*
G01X1277331Y312322D02*
Y313589D01*
X1278831D01*
X1279331Y313209D01*
X1279664Y312765D01*
X1279831Y312132D01*
X1279664Y311499D01*
X1279331Y311055D01*
X1278831Y310675D01*
X1278248Y310422D01*
X1277581Y310295D01*
X1276998D01*
X1276498Y310422D01*
X1275914Y310675D01*
X1275414Y311055D01*
X1275081Y311435D01*
X1274831Y311942D01*
Y312385D01*
X1274998Y312892D01*
X1275331Y313272D01*
G01X1279831Y315649D02*
X1274831D01*
Y316915D01*
X1275081Y317422D01*
X1275414Y317802D01*
X1275914Y318119D01*
X1276498Y318372D01*
X1277331Y318435D01*
X1278164Y318372D01*
X1278748Y318119D01*
X1279248Y317802D01*
X1279581Y317422D01*
X1279831Y316915D01*
Y315649D01*
G01X1281498Y320242D02*
Y324042D01*
G01X1279831Y325975D02*
X1274831D01*
Y327495D01*
X1275081Y328002D01*
X1275664Y328382D01*
X1276331Y328509D01*
X1276998Y328382D01*
X1277498Y328065D01*
X1277748Y327495D01*
Y325975D01*
G01X1274831Y330759D02*
X1279831Y332342D01*
X1274831Y333925D01*
G01X1279831Y336049D02*
X1274831D01*
Y337315D01*
X1275081Y337822D01*
X1275414Y338202D01*
X1275914Y338519D01*
X1276498Y338772D01*
X1277331Y338835D01*
X1278164Y338772D01*
X1278748Y338519D01*
X1279248Y338202D01*
X1279581Y337822D01*
X1279831Y337315D01*
Y336049D01*
G01Y341149D02*
X1274831D01*
Y342415D01*
X1275081Y342922D01*
X1275414Y343302D01*
X1275914Y343619D01*
X1276498Y343872D01*
X1277331Y343935D01*
X1278164Y343872D01*
X1278748Y343619D01*
X1279248Y343302D01*
X1279581Y342922D01*
X1279831Y342415D01*
Y341149D01*
G01X1278831Y346249D02*
X1279414Y346629D01*
X1279748Y347135D01*
X1279831Y347705D01*
X1279748Y348212D01*
X1279331Y348719D01*
X1278831Y349035D01*
X1278331Y349099D01*
X1277748Y348972D01*
X1277331Y348529D01*
X1277164Y348085D01*
Y347515D01*
G01Y348085D02*
X1276914Y348465D01*
X1276498Y348782D01*
X1275998Y348909D01*
X1275498Y348782D01*
X1275081Y348465D01*
X1274831Y347895D01*
X1274914Y347325D01*
X1275248Y346755D01*
G01X1278831Y351349D02*
X1279414Y351729D01*
X1279748Y352235D01*
X1279831Y352805D01*
X1279748Y353312D01*
X1279331Y353819D01*
X1278831Y354135D01*
X1278331Y354199D01*
X1277748Y354072D01*
X1277331Y353629D01*
X1277164Y353185D01*
Y352615D01*
G01Y353185D02*
X1276914Y353565D01*
X1276498Y353882D01*
X1275998Y354009D01*
X1275498Y353882D01*
X1275081Y353565D01*
X1274831Y352995D01*
X1274914Y352425D01*
X1275248Y351855D01*
G01X1281498Y355942D02*
Y359742D01*
G01X1279164Y361612D02*
X1279581Y362119D01*
X1279831Y362689D01*
Y363195D01*
X1279581Y363702D01*
X1279164Y364082D01*
X1278581Y364272D01*
X1277998Y364145D01*
X1277498Y363829D01*
X1277164Y363259D01*
X1276998Y362499D01*
X1276664Y362055D01*
X1276081Y361865D01*
X1275498Y361992D01*
X1275081Y362309D01*
X1274831Y362752D01*
Y363195D01*
X1274998Y363639D01*
X1275414Y364019D01*
G01X1279081Y366649D02*
X1279498Y367029D01*
X1279748Y367472D01*
X1279831Y368042D01*
X1279664Y368612D01*
X1279331Y369055D01*
X1278748Y369372D01*
X1278081Y369435D01*
X1277414Y369309D01*
X1276998Y368992D01*
X1276664Y368549D01*
X1276581Y368105D01*
X1276664Y367662D01*
X1276998Y367092D01*
X1274831Y367282D01*
Y368992D01*
G01X1288413Y294392D02*
X1283413D01*
Y295912D01*
X1283663Y296419D01*
X1284246Y296799D01*
X1284913Y296926D01*
X1285580Y296799D01*
X1286080Y296482D01*
X1286330Y295912D01*
Y294392D01*
G01X1283413Y298859D02*
X1288413Y299746D01*
X1283413Y300759D01*
X1288413Y301772D01*
X1283413Y302659D01*
G01X1288413Y304592D02*
X1283413D01*
Y306176D01*
X1283663Y306682D01*
X1283996Y306999D01*
X1284663Y307126D01*
X1285330Y306999D01*
X1285746Y306619D01*
X1285996Y306176D01*
Y304592D01*
G01Y306176D02*
X1288413Y307126D01*
G01X1285913Y311339D02*
Y312606D01*
X1287413D01*
X1287913Y312226D01*
X1288246Y311782D01*
X1288413Y311149D01*
X1288246Y310516D01*
X1287913Y310072D01*
X1287413Y309692D01*
X1286830Y309439D01*
X1286163Y309312D01*
X1285580D01*
X1285080Y309439D01*
X1284496Y309692D01*
X1283996Y310072D01*
X1283663Y310452D01*
X1283413Y310959D01*
Y311402D01*
X1283580Y311909D01*
X1283913Y312289D01*
G01X1288413Y314666D02*
X1283413D01*
Y315932D01*
X1283663Y316439D01*
X1283996Y316819D01*
X1284496Y317136D01*
X1285080Y317389D01*
X1285913Y317452D01*
X1286746Y317389D01*
X1287330Y317136D01*
X1287830Y316819D01*
X1288163Y316439D01*
X1288413Y315932D01*
Y314666D01*
G01X1290080Y319259D02*
Y323059D01*
G01X1288413Y324992D02*
X1283413D01*
Y326512D01*
X1283663Y327019D01*
X1284246Y327399D01*
X1284913Y327526D01*
X1285580Y327399D01*
X1286080Y327082D01*
X1286330Y326512D01*
Y324992D01*
G01X1283413Y329776D02*
X1288413Y331359D01*
X1283413Y332942D01*
G01X1288413Y335066D02*
X1283413D01*
Y336332D01*
X1283663Y336839D01*
X1283996Y337219D01*
X1284496Y337536D01*
X1285080Y337789D01*
X1285913Y337852D01*
X1286746Y337789D01*
X1287330Y337536D01*
X1287830Y337219D01*
X1288163Y336839D01*
X1288413Y336332D01*
Y335066D01*
G01Y340166D02*
X1283413D01*
Y341432D01*
X1283663Y341939D01*
X1283996Y342319D01*
X1284496Y342636D01*
X1285080Y342889D01*
X1285913Y342952D01*
X1286746Y342889D01*
X1287330Y342636D01*
X1287830Y342319D01*
X1288163Y341939D01*
X1288413Y341432D01*
Y340166D01*
G01X1283830Y348052D02*
X1283580Y347672D01*
X1283413Y347229D01*
Y346722D01*
X1283663Y346152D01*
X1284080Y345709D01*
X1284580Y345392D01*
X1285413Y345139D01*
X1286163Y345076D01*
X1286913Y345202D01*
X1287413Y345392D01*
X1287913Y345772D01*
X1288246Y346216D01*
X1288413Y346659D01*
Y347102D01*
X1288246Y347546D01*
X1287996Y347926D01*
X1287663Y348242D01*
G01X1288413Y350492D02*
X1283413D01*
Y352076D01*
X1283663Y352582D01*
X1283996Y352899D01*
X1284663Y353026D01*
X1285330Y352899D01*
X1285746Y352519D01*
X1285996Y352076D01*
Y350492D01*
G01Y352076D02*
X1288413Y353026D01*
G01X1290080Y354959D02*
Y358759D01*
G01X1283830Y363352D02*
X1283580Y362972D01*
X1283413Y362529D01*
Y362022D01*
X1283663Y361452D01*
X1284080Y361009D01*
X1284580Y360692D01*
X1285413Y360439D01*
X1286163Y360376D01*
X1286913Y360502D01*
X1287413Y360692D01*
X1287913Y361072D01*
X1288246Y361516D01*
X1288413Y361959D01*
Y362402D01*
X1288246Y362846D01*
X1287996Y363226D01*
X1287663Y363542D01*
G01X1288413Y365792D02*
X1283413D01*
Y367312D01*
X1283663Y367819D01*
X1284246Y368199D01*
X1284913Y368326D01*
X1285580Y368199D01*
X1286080Y367882D01*
X1286330Y367312D01*
Y365792D01*
G01X1283413Y370766D02*
X1286996D01*
X1287746Y371019D01*
X1288246Y371526D01*
X1288413Y372159D01*
X1288246Y372792D01*
X1287746Y373299D01*
X1286996Y373552D01*
X1283413D01*
G01Y377259D02*
X1283580Y376752D01*
X1283996Y376372D01*
X1284496Y376119D01*
X1285163Y375929D01*
X1285913Y375866D01*
X1286663Y375929D01*
X1287330Y376119D01*
X1287830Y376372D01*
X1288246Y376752D01*
X1288413Y377259D01*
X1288246Y377766D01*
X1287830Y378146D01*
X1287330Y378399D01*
X1286663Y378589D01*
X1285913Y378652D01*
X1285163Y378589D01*
X1284496Y378399D01*
X1283996Y378146D01*
X1283580Y377766D01*
X1283413Y377259D01*
G01X1290080Y380459D02*
Y384259D01*
G01X1288413Y386192D02*
X1283413D01*
Y387712D01*
X1283663Y388219D01*
X1284246Y388599D01*
X1284913Y388726D01*
X1285580Y388599D01*
X1286080Y388282D01*
X1286330Y387712D01*
Y386192D01*
G01X1283413Y392559D02*
X1283580Y392052D01*
X1283996Y391672D01*
X1284496Y391419D01*
X1285163Y391229D01*
X1285913Y391166D01*
X1286663Y391229D01*
X1287330Y391419D01*
X1287830Y391672D01*
X1288246Y392052D01*
X1288413Y392559D01*
X1288246Y393066D01*
X1287830Y393446D01*
X1287330Y393699D01*
X1286663Y393889D01*
X1285913Y393952D01*
X1285163Y393889D01*
X1284496Y393699D01*
X1283996Y393446D01*
X1283580Y393066D01*
X1283413Y392559D01*
G01X1288602Y402025D02*
Y405225D01*
G01X1294802Y402025D02*
X1288602D01*
G01X1282049Y392484D02*
Y389284D01*
G01X1275849Y392484D02*
X1282049D01*
G01X1275849Y389284D02*
Y392484D01*
G01X1282049Y389284D02*
X1275849D01*
G01X1275149Y392484D02*
Y389284D01*
G01X1285808Y400819D02*
X1283855D01*
G01X1285808Y402772D02*
Y400819D01*
G01X1288602Y405225D02*
X1294802D01*
G01X1288602Y406525D02*
Y409725D01*
G01X1294802Y406525D02*
X1288602D01*
G01Y409725D02*
X1294802D01*
G01X1285808Y412631D02*
Y410678D01*
G01X1283855Y412631D02*
X1285808D01*
G01X1275277Y766588D02*
Y760388D01*
G01X1287077Y757388D02*
Y763588D01*
G01X1290277Y757388D02*
X1287077D01*
G01X1276077Y760388D02*
Y766588D01*
G01X1279277Y760388D02*
X1276077D01*
G01X1279277Y766588D02*
Y760388D01*
G01X1280077D02*
Y766588D01*
G01X1283277Y760388D02*
X1280077D01*
G01X1283277Y766588D02*
Y760388D01*
G01X1287077Y763588D02*
X1290277D01*
G01X1276077Y766588D02*
X1279277D01*
G01X1280077D02*
X1283277D01*
G01X1331000Y860721D02*
X1274400D01*
G01X1275071Y870788D02*
Y888300D01*
G01X1479200Y870788D02*
X1275071D01*
G01Y898300D02*
Y911800D01*
G01Y920200D02*
Y932200D01*
G01Y939400D02*
Y951000D01*
G01Y958500D02*
Y969000D01*
G01Y977900D02*
Y1012400D01*
G01Y1016400D02*
Y1064300D01*
G01Y1071800D02*
Y1082200D01*
G01Y1090900D02*
Y1102500D01*
G01Y1109600D02*
Y1121700D01*
G01Y1128900D02*
Y1141100D01*
G01Y1151500D02*
Y1167638D01*
G01D02*
X1358900D01*
G01X1274783Y1308623D02*
Y1305423D01*
G01X1276383Y1307040D02*
Y1309640D01*
G01X1277176Y1307040D02*
X1276383D01*
G01Y1316251D02*
Y1317949D01*
G01X1277220Y1341075D02*
Y1334875D01*
G01X1290815Y1334065D02*
X1287615D01*
G01Y1340265D02*
X1290815D01*
G01X1287615Y1334065D02*
Y1340265D01*
G01X1284190Y1340969D02*
Y1337769D01*
G01X1277990D02*
Y1340969D01*
G01X1284190Y1337769D02*
X1277990D01*
G01Y1340969D02*
X1284190D01*
G01X1276383Y1330662D02*
X1277391D01*
G01X1276383Y1328808D02*
Y1330662D01*
G01X1288309Y1343266D02*
Y1346366D01*
X1289229D01*
X1289536Y1346211D01*
X1289766Y1345849D01*
X1289843Y1345436D01*
X1289766Y1345023D01*
X1289574Y1344713D01*
X1289229Y1344558D01*
X1288309D01*
G01X1291409Y1346366D02*
Y1343266D01*
X1292943D01*
G01X1295276D02*
Y1346366D01*
X1294816Y1345746D01*
G01Y1343266D02*
X1295736D01*
G01X1298376D02*
Y1346366D01*
X1297916Y1345746D01*
G01Y1343266D02*
X1298836D01*
G01X1288383Y1347500D02*
Y1350600D01*
X1289303D01*
X1289610Y1350445D01*
X1289840Y1350083D01*
X1289917Y1349670D01*
X1289840Y1349257D01*
X1289648Y1348947D01*
X1289303Y1348792D01*
X1288383D01*
G01X1291407Y1350600D02*
Y1348378D01*
X1291560Y1347913D01*
X1291867Y1347603D01*
X1292250Y1347500D01*
X1292633Y1347603D01*
X1292940Y1347913D01*
X1293093Y1348378D01*
Y1350600D01*
G01X1294622Y1350083D02*
X1294852Y1350393D01*
X1295120Y1350548D01*
X1295427Y1350600D01*
X1295810Y1350497D01*
X1296078Y1350238D01*
X1296155Y1349928D01*
X1296117Y1349618D01*
X1295963Y1349360D01*
X1295197Y1348843D01*
X1294852Y1348482D01*
X1294622Y1347965D01*
X1294545Y1347500D01*
X1296155D01*
G01X1304532Y1380636D02*
G02I-13386J0D01*
G01D02*
X1277760D01*
G01X1287313Y1457636D02*
Y1424136D01*
G01D02*
X1377313D01*
G01X1286200Y1432400D02*
X1280000D01*
G01D02*
Y1435600D01*
G01X1286200D02*
Y1432400D01*
G01X1280000Y1431600D02*
X1286200D01*
G01X1280000Y1428400D02*
Y1431600D01*
G01X1286200Y1428400D02*
X1280000D01*
G01X1286200Y1431600D02*
Y1428400D01*
G01X1287313Y1437636D02*
X1302313D01*
G01X1280000Y1435600D02*
X1286200D01*
G01X1302313Y1457636D02*
X1287313D01*
G01X1275070Y1575491D02*
Y1540451D01*
G01X1283072Y1550620D02*
X1289072D01*
Y1547620D01*
X1283072D01*
Y1550620D01*
G01X1279870Y1551320D02*
Y1557520D01*
X1283070D01*
Y1551320D01*
X1279870D01*
G01X1285772D02*
Y1557520D01*
X1288972D01*
Y1551320D01*
X1285772D01*
G01X1286022Y1547520D02*
X1279822D01*
Y1550720D01*
X1286022D01*
Y1547520D01*
G01Y1543620D02*
X1279822D01*
Y1546820D01*
X1286022D01*
Y1543620D01*
G01X1289172D02*
X1282972D01*
Y1546820D01*
X1289172D01*
Y1543620D01*
G01X1287010Y1569503D02*
Y1572911D01*
G01X1304726Y1569503D02*
X1287010D01*
G01X1286851Y1591758D02*
Y1588658D01*
X1288385D01*
G01X1290718D02*
Y1591758D01*
X1290258Y1591138D01*
G01Y1588658D02*
X1291178D01*
G01X1294278D02*
Y1591758D01*
X1292860Y1589536D01*
X1294776D01*
G01X1287010Y1587219D02*
X1304726D01*
G01X1287010Y1583811D02*
Y1587219D01*
G01X1289133Y1621978D02*
X1286893D01*
G01X1288106Y1620353D02*
Y1623603D01*
G01X1288976Y1646023D02*
Y1736118D01*
G01X1291600Y1646023D02*
X1288976D01*
G01X1287855Y1655935D02*
X1287183Y1656012D01*
X1286615Y1656127D01*
X1286098Y1656280D01*
X1285530Y1656472D01*
X1284755Y1656779D01*
Y1655245D01*
G01X1278689Y1655284D02*
X1278328Y1655552D01*
X1278121Y1655782D01*
X1278018Y1656089D01*
X1278121Y1656357D01*
X1278328Y1656549D01*
X1278638Y1656702D01*
X1278999Y1656740D01*
X1279309Y1656702D01*
X1279619Y1656549D01*
X1279878Y1656319D01*
X1279981Y1656050D01*
X1279878Y1655744D01*
X1279568Y1655475D01*
X1279103Y1655322D01*
X1278586Y1655284D01*
X1277914Y1655360D01*
X1277553Y1655475D01*
X1277191Y1655667D01*
X1276933Y1655935D01*
X1276881Y1656204D01*
X1276984Y1656472D01*
X1277243Y1656664D01*
G01X1291500Y1646023D02*
X1285000D01*
G01X1285400Y1657834D02*
X1291200D01*
G01X1297800Y66011D02*
Y59811D01*
G01D02*
X1294600D01*
G01D02*
Y66011D01*
G01X1306230Y51711D02*
X1303130D01*
Y52477D01*
X1303285Y52784D01*
X1303492Y53014D01*
X1303802Y53206D01*
X1304163Y53359D01*
X1304680Y53397D01*
X1305197Y53359D01*
X1305558Y53206D01*
X1305868Y53014D01*
X1306075Y52784D01*
X1306230Y52477D01*
Y51711D01*
G01Y55577D02*
X1305558Y55654D01*
X1304990Y55769D01*
X1304473Y55922D01*
X1303905Y56114D01*
X1303130Y56421D01*
Y54887D01*
G01X1300260Y55337D02*
Y57577D01*
G01X1298635Y56364D02*
X1301885D01*
G01X1299510Y58494D02*
Y68894D01*
G01X1303910D02*
Y58494D01*
G01D02*
X1299510D01*
G01X1294600Y66011D02*
X1297800D01*
G01X1298770Y71781D02*
Y74207D01*
G01X1299510Y68894D02*
X1303910D01*
G01X1299510Y69494D02*
X1303910D01*
G01Y70094D02*
X1299510D01*
G01Y70694D02*
X1303910D01*
G01D02*
Y68894D01*
G01X1299510Y70694D02*
Y68894D01*
G01X1294037Y75727D02*
X1293985Y75420D01*
X1293779Y75152D01*
X1293469Y74922D01*
X1293107Y74769D01*
X1292694Y74692D01*
X1292280D01*
X1291867Y74769D01*
X1291505Y74922D01*
X1291195Y75152D01*
X1290989Y75420D01*
X1290937Y75727D01*
X1290989Y76034D01*
X1291195Y76302D01*
X1291505Y76532D01*
X1291867Y76685D01*
X1292280Y76762D01*
X1292694D01*
X1293107Y76685D01*
X1293469Y76532D01*
X1293779Y76302D01*
X1293985Y76034D01*
X1294037Y75727D01*
G01X1293210Y76034D02*
X1294037Y76494D01*
G01X1291454Y78099D02*
X1291144Y78329D01*
X1290989Y78597D01*
X1290937Y78904D01*
X1291040Y79287D01*
X1291299Y79555D01*
X1291609Y79632D01*
X1291919Y79594D01*
X1292177Y79440D01*
X1292694Y78674D01*
X1293055Y78329D01*
X1293572Y78099D01*
X1294037Y78022D01*
Y79632D01*
G01Y81927D02*
X1293985Y82195D01*
X1293830Y82502D01*
X1293572Y82694D01*
X1293210Y82770D01*
X1292849Y82694D01*
X1292539Y82464D01*
X1292384Y82119D01*
Y81735D01*
X1292280Y81505D01*
X1292022Y81314D01*
X1291660Y81237D01*
X1291299Y81352D01*
X1291040Y81620D01*
X1290937Y81927D01*
X1291040Y82234D01*
X1291299Y82502D01*
X1291660Y82617D01*
X1292022Y82540D01*
X1292280Y82349D01*
X1292384Y82119D01*
Y81735D01*
X1292539Y81390D01*
X1292849Y81160D01*
X1293210Y81084D01*
X1293572Y81160D01*
X1293830Y81352D01*
X1293985Y81659D01*
X1294037Y81927D01*
G01X1310692Y75976D02*
X1300198D01*
G01D02*
Y84638D01*
G01D02*
X1303545D01*
G01D02*
X1305445Y82438D01*
G01X1292165Y87734D02*
X1292475Y87926D01*
X1292682Y88156D01*
X1292785Y88424D01*
X1292682Y88731D01*
X1292475Y88961D01*
X1292165Y89191D01*
X1291752Y89268D01*
X1289685D01*
G01X1292785Y90834D02*
X1289685D01*
Y91754D01*
X1289840Y92061D01*
X1290202Y92291D01*
X1290615Y92368D01*
X1291028Y92291D01*
X1291338Y92099D01*
X1291493Y91754D01*
Y90834D01*
G01X1292785Y94701D02*
X1289685D01*
X1290305Y94241D01*
G01X1292785D02*
Y95161D01*
G01X1290202Y97073D02*
X1289892Y97303D01*
X1289737Y97571D01*
X1289685Y97878D01*
X1289788Y98261D01*
X1290047Y98529D01*
X1290357Y98606D01*
X1290667Y98568D01*
X1290925Y98414D01*
X1291442Y97648D01*
X1291803Y97303D01*
X1292320Y97073D01*
X1292785Y96996D01*
Y98606D01*
G01X1304360Y87615D02*
X1294518D01*
G01D02*
Y118009D01*
G01D02*
X1304360D01*
G01X1293593Y132139D02*
Y135339D01*
G01X1299793Y132139D02*
X1293593D01*
G01X1299793Y135339D02*
Y132139D01*
G01X1293593Y135339D02*
X1299793D01*
G01X1293593Y124139D02*
Y127339D01*
G01X1299793Y124139D02*
X1293593D01*
G01X1299793Y127339D02*
Y124139D01*
G01X1293593Y127339D02*
X1299793D01*
G01X1293593Y128139D02*
Y131339D01*
G01X1299793Y128139D02*
X1293593D01*
G01X1299793Y131339D02*
Y128139D01*
G01X1293593Y131339D02*
X1299793D01*
G01X1293593Y144139D02*
Y147339D01*
G01X1299793Y144139D02*
X1293593D01*
G01X1299793Y147339D02*
Y144139D01*
G01X1293593Y147339D02*
X1299793D01*
G01Y143339D02*
Y140139D01*
G01X1293593Y143339D02*
X1299793D01*
G01X1293593Y140139D02*
Y143339D01*
G01X1299793Y140139D02*
X1293593D01*
G01Y139339D02*
X1299793D01*
G01D02*
Y136139D01*
G01X1293593D02*
Y139339D01*
G01X1299793Y136139D02*
X1293593D01*
G01X1292577Y148217D02*
Y154217D01*
G01X1304577Y148217D02*
X1292577D01*
G01X1291207Y163651D02*
Y160451D01*
G01Y167651D02*
Y164451D01*
G01X1300707Y163651D02*
Y160451D01*
G01X1294507Y163651D02*
X1300707D01*
G01X1294507Y160451D02*
Y163651D01*
G01X1300707Y160451D02*
X1294507D01*
G01X1300707Y167651D02*
Y164451D01*
G01X1294507D02*
Y167651D01*
G01X1300707Y164451D02*
X1294507D01*
G01X1292577Y154217D02*
X1304577D01*
G01X1292978Y155195D02*
Y159795D01*
G01X1302978Y155195D02*
Y159795D01*
G01X1292978Y159695D02*
Y159795D01*
X1302978D01*
G01Y155195D02*
X1292978D01*
G01X1300707Y173151D02*
Y169951D01*
G01X1294507Y173151D02*
X1300707D01*
G01X1294507Y169951D02*
Y173151D01*
G01X1300707Y169951D02*
X1294507D01*
G01X1291207Y173151D02*
Y169951D01*
G01X1294507Y167651D02*
X1300707D01*
G01X1291207Y185651D02*
Y182451D01*
G01X1300707Y185651D02*
Y182451D01*
G01X1294507Y185651D02*
X1300707D01*
G01X1294507Y182451D02*
Y185651D01*
G01X1300707Y182451D02*
X1294507D01*
G01X1292766Y260794D02*
X1289666D01*
Y261560D01*
X1289821Y261867D01*
X1290028Y262097D01*
X1290338Y262289D01*
X1290699Y262442D01*
X1291216Y262480D01*
X1291733Y262442D01*
X1292094Y262289D01*
X1292404Y262097D01*
X1292611Y261867D01*
X1292766Y261560D01*
Y260794D01*
G01Y264660D02*
X1292094Y264737D01*
X1291526Y264852D01*
X1291009Y265005D01*
X1290441Y265197D01*
X1289666Y265504D01*
Y263970D01*
G01X1291474Y267109D02*
X1291113Y267377D01*
X1290906Y267607D01*
X1290803Y267914D01*
X1290906Y268182D01*
X1291113Y268374D01*
X1291423Y268527D01*
X1291784Y268565D01*
X1292094Y268527D01*
X1292404Y268374D01*
X1292663Y268144D01*
X1292766Y267875D01*
X1292663Y267569D01*
X1292353Y267300D01*
X1291888Y267147D01*
X1291371Y267109D01*
X1290699Y267185D01*
X1290338Y267300D01*
X1289976Y267492D01*
X1289718Y267760D01*
X1289666Y268029D01*
X1289769Y268297D01*
X1290028Y268489D01*
G01X1300766Y260794D02*
X1297666D01*
Y261560D01*
X1297821Y261867D01*
X1298028Y262097D01*
X1298338Y262289D01*
X1298699Y262442D01*
X1299216Y262480D01*
X1299733Y262442D01*
X1300094Y262289D01*
X1300404Y262097D01*
X1300611Y261867D01*
X1300766Y261560D01*
Y260794D01*
G01Y264660D02*
X1300094Y264737D01*
X1299526Y264852D01*
X1299009Y265005D01*
X1298441Y265197D01*
X1297666Y265504D01*
Y263970D01*
G01X1300766Y267760D02*
X1300094Y267837D01*
X1299526Y267952D01*
X1299009Y268105D01*
X1298441Y268297D01*
X1297666Y268604D01*
Y267070D01*
G01X1292194Y273458D02*
Y280548D01*
G01D02*
X1295994D01*
G01D02*
Y273458D01*
G01X1292194Y272858D02*
Y280048D01*
G01D02*
X1295994D01*
G01D02*
Y272858D01*
G01X1292194Y272458D02*
Y279548D01*
G01D02*
X1295994D01*
G01D02*
Y272408D01*
G01D02*
X1292244D01*
G01X1300194Y273458D02*
Y280548D01*
G01D02*
X1303994D01*
G01D02*
Y273458D01*
G01X1300194Y272858D02*
Y280048D01*
G01D02*
X1303994D01*
G01D02*
Y272858D01*
G01X1300194Y272458D02*
Y279548D01*
G01D02*
X1303994D01*
G01D02*
Y272408D01*
G01D02*
X1300244D01*
G01X1296013Y294392D02*
X1291013D01*
Y295912D01*
X1291263Y296419D01*
X1291846Y296799D01*
X1292513Y296926D01*
X1293180Y296799D01*
X1293680Y296482D01*
X1293930Y295912D01*
Y294392D01*
G01X1291013Y298859D02*
X1296013Y299746D01*
X1291013Y300759D01*
X1296013Y301772D01*
X1291013Y302659D01*
G01X1296013Y304592D02*
X1291013D01*
Y306176D01*
X1291263Y306682D01*
X1291596Y306999D01*
X1292263Y307126D01*
X1292930Y306999D01*
X1293346Y306619D01*
X1293596Y306176D01*
Y304592D01*
G01Y306176D02*
X1296013Y307126D01*
G01X1293513Y311339D02*
Y312606D01*
X1295013D01*
X1295513Y312226D01*
X1295846Y311782D01*
X1296013Y311149D01*
X1295846Y310516D01*
X1295513Y310072D01*
X1295013Y309692D01*
X1294430Y309439D01*
X1293763Y309312D01*
X1293180D01*
X1292680Y309439D01*
X1292096Y309692D01*
X1291596Y310072D01*
X1291263Y310452D01*
X1291013Y310959D01*
Y311402D01*
X1291180Y311909D01*
X1291513Y312289D01*
G01X1296013Y314666D02*
X1291013D01*
Y315932D01*
X1291263Y316439D01*
X1291596Y316819D01*
X1292096Y317136D01*
X1292680Y317389D01*
X1293513Y317452D01*
X1294346Y317389D01*
X1294930Y317136D01*
X1295430Y316819D01*
X1295763Y316439D01*
X1296013Y315932D01*
Y314666D01*
G01X1297680Y319259D02*
Y323059D01*
G01X1296013Y324992D02*
X1291013D01*
Y326512D01*
X1291263Y327019D01*
X1291846Y327399D01*
X1292513Y327526D01*
X1293180Y327399D01*
X1293680Y327082D01*
X1293930Y326512D01*
Y324992D01*
G01X1291013Y329776D02*
X1296013Y331359D01*
X1291013Y332942D01*
G01X1296013Y335066D02*
X1291013D01*
Y336332D01*
X1291263Y336839D01*
X1291596Y337219D01*
X1292096Y337536D01*
X1292680Y337789D01*
X1293513Y337852D01*
X1294346Y337789D01*
X1294930Y337536D01*
X1295430Y337219D01*
X1295763Y336839D01*
X1296013Y336332D01*
Y335066D01*
G01Y340166D02*
X1291013D01*
Y341432D01*
X1291263Y341939D01*
X1291596Y342319D01*
X1292096Y342636D01*
X1292680Y342889D01*
X1293513Y342952D01*
X1294346Y342889D01*
X1294930Y342636D01*
X1295430Y342319D01*
X1295763Y341939D01*
X1296013Y341432D01*
Y340166D01*
G01X1291430Y348052D02*
X1291180Y347672D01*
X1291013Y347229D01*
Y346722D01*
X1291263Y346152D01*
X1291680Y345709D01*
X1292180Y345392D01*
X1293013Y345139D01*
X1293763Y345076D01*
X1294513Y345202D01*
X1295013Y345392D01*
X1295513Y345772D01*
X1295846Y346216D01*
X1296013Y346659D01*
Y347102D01*
X1295846Y347546D01*
X1295596Y347926D01*
X1295263Y348242D01*
G01X1296013Y350492D02*
X1291013D01*
Y352076D01*
X1291263Y352582D01*
X1291596Y352899D01*
X1292263Y353026D01*
X1292930Y352899D01*
X1293346Y352519D01*
X1293596Y352076D01*
Y350492D01*
G01Y352076D02*
X1296013Y353026D01*
G01X1297680Y354959D02*
Y358759D01*
G01X1295346Y360629D02*
X1295763Y361136D01*
X1296013Y361706D01*
Y362212D01*
X1295763Y362719D01*
X1295346Y363099D01*
X1294763Y363289D01*
X1294180Y363162D01*
X1293680Y362846D01*
X1293346Y362276D01*
X1293180Y361516D01*
X1292846Y361072D01*
X1292263Y360882D01*
X1291680Y361009D01*
X1291263Y361326D01*
X1291013Y361769D01*
Y362212D01*
X1291180Y362656D01*
X1291596Y363036D01*
G01X1296013Y367059D02*
X1295930Y366552D01*
X1295596Y366109D01*
X1295096Y365729D01*
X1294513Y365476D01*
X1293846Y365349D01*
X1293180D01*
X1292513Y365476D01*
X1291930Y365729D01*
X1291430Y366109D01*
X1291096Y366552D01*
X1291013Y367059D01*
X1291096Y367566D01*
X1291430Y368009D01*
X1291930Y368389D01*
X1292513Y368642D01*
X1293180Y368769D01*
X1293846D01*
X1294513Y368642D01*
X1295096Y368389D01*
X1295596Y368009D01*
X1295930Y367566D01*
X1296013Y367059D01*
G01X1291430Y373552D02*
X1291180Y373172D01*
X1291013Y372729D01*
Y372222D01*
X1291263Y371652D01*
X1291680Y371209D01*
X1292180Y370892D01*
X1293013Y370639D01*
X1293763Y370576D01*
X1294513Y370702D01*
X1295013Y370892D01*
X1295513Y371272D01*
X1295846Y371716D01*
X1296013Y372159D01*
Y372602D01*
X1295846Y373046D01*
X1295596Y373426D01*
X1295263Y373742D01*
G01X1297680Y375359D02*
Y379159D01*
G01X1296013Y381092D02*
X1291013D01*
Y382612D01*
X1291263Y383119D01*
X1291846Y383499D01*
X1292513Y383626D01*
X1293180Y383499D01*
X1293680Y383182D01*
X1293930Y382612D01*
Y381092D01*
G01X1291013Y387459D02*
X1291180Y386952D01*
X1291596Y386572D01*
X1292096Y386319D01*
X1292763Y386129D01*
X1293513Y386066D01*
X1294263Y386129D01*
X1294930Y386319D01*
X1295430Y386572D01*
X1295846Y386952D01*
X1296013Y387459D01*
X1295846Y387966D01*
X1295430Y388346D01*
X1294930Y388599D01*
X1294263Y388789D01*
X1293513Y388852D01*
X1292763Y388789D01*
X1292096Y388599D01*
X1291596Y388346D01*
X1291180Y387966D01*
X1291013Y387459D01*
G01X1303613Y294392D02*
X1298613D01*
Y295912D01*
X1298863Y296419D01*
X1299446Y296799D01*
X1300113Y296926D01*
X1300780Y296799D01*
X1301280Y296482D01*
X1301530Y295912D01*
Y294392D01*
G01X1298613Y298859D02*
X1303613Y299746D01*
X1298613Y300759D01*
X1303613Y301772D01*
X1298613Y302659D01*
G01X1303613Y304592D02*
X1298613D01*
Y306176D01*
X1298863Y306682D01*
X1299196Y306999D01*
X1299863Y307126D01*
X1300530Y306999D01*
X1300946Y306619D01*
X1301196Y306176D01*
Y304592D01*
G01Y306176D02*
X1303613Y307126D01*
G01X1301113Y311339D02*
Y312606D01*
X1302613D01*
X1303113Y312226D01*
X1303446Y311782D01*
X1303613Y311149D01*
X1303446Y310516D01*
X1303113Y310072D01*
X1302613Y309692D01*
X1302030Y309439D01*
X1301363Y309312D01*
X1300780D01*
X1300280Y309439D01*
X1299696Y309692D01*
X1299196Y310072D01*
X1298863Y310452D01*
X1298613Y310959D01*
Y311402D01*
X1298780Y311909D01*
X1299113Y312289D01*
G01X1303613Y314666D02*
X1298613D01*
Y315932D01*
X1298863Y316439D01*
X1299196Y316819D01*
X1299696Y317136D01*
X1300280Y317389D01*
X1301113Y317452D01*
X1301946Y317389D01*
X1302530Y317136D01*
X1303030Y316819D01*
X1303363Y316439D01*
X1303613Y315932D01*
Y314666D01*
G01X1305280Y319259D02*
Y323059D01*
G01X1303613Y324992D02*
X1298613D01*
Y326512D01*
X1298863Y327019D01*
X1299446Y327399D01*
X1300113Y327526D01*
X1300780Y327399D01*
X1301280Y327082D01*
X1301530Y326512D01*
Y324992D01*
G01X1298613Y329776D02*
X1303613Y331359D01*
X1298613Y332942D01*
G01X1303613Y335066D02*
X1298613D01*
Y336332D01*
X1298863Y336839D01*
X1299196Y337219D01*
X1299696Y337536D01*
X1300280Y337789D01*
X1301113Y337852D01*
X1301946Y337789D01*
X1302530Y337536D01*
X1303030Y337219D01*
X1303363Y336839D01*
X1303613Y336332D01*
Y335066D01*
G01Y340166D02*
X1298613D01*
Y341432D01*
X1298863Y341939D01*
X1299196Y342319D01*
X1299696Y342636D01*
X1300280Y342889D01*
X1301113Y342952D01*
X1301946Y342889D01*
X1302530Y342636D01*
X1303030Y342319D01*
X1303363Y341939D01*
X1303613Y341432D01*
Y340166D01*
G01X1299030Y348052D02*
X1298780Y347672D01*
X1298613Y347229D01*
Y346722D01*
X1298863Y346152D01*
X1299280Y345709D01*
X1299780Y345392D01*
X1300613Y345139D01*
X1301363Y345076D01*
X1302113Y345202D01*
X1302613Y345392D01*
X1303113Y345772D01*
X1303446Y346216D01*
X1303613Y346659D01*
Y347102D01*
X1303446Y347546D01*
X1303196Y347926D01*
X1302863Y348242D01*
G01X1303613Y350492D02*
X1298613D01*
Y352076D01*
X1298863Y352582D01*
X1299196Y352899D01*
X1299863Y353026D01*
X1300530Y352899D01*
X1300946Y352519D01*
X1301196Y352076D01*
Y350492D01*
G01Y352076D02*
X1303613Y353026D01*
G01X1305280Y354959D02*
Y358759D01*
G01X1299030Y363352D02*
X1298780Y362972D01*
X1298613Y362529D01*
Y362022D01*
X1298863Y361452D01*
X1299280Y361009D01*
X1299780Y360692D01*
X1300613Y360439D01*
X1301363Y360376D01*
X1302113Y360502D01*
X1302613Y360692D01*
X1303113Y361072D01*
X1303446Y361516D01*
X1303613Y361959D01*
Y362402D01*
X1303446Y362846D01*
X1303196Y363226D01*
X1302863Y363542D01*
G01X1303613Y365792D02*
X1298613D01*
Y367312D01*
X1298863Y367819D01*
X1299446Y368199D01*
X1300113Y368326D01*
X1300780Y368199D01*
X1301280Y367882D01*
X1301530Y367312D01*
Y365792D01*
G01X1298613Y370766D02*
X1302196D01*
X1302946Y371019D01*
X1303446Y371526D01*
X1303613Y372159D01*
X1303446Y372792D01*
X1302946Y373299D01*
X1302196Y373552D01*
X1298613D01*
G01X1303613Y377259D02*
X1298613D01*
X1299613Y376499D01*
G01X1303613D02*
Y378019D01*
G01X1305280Y380459D02*
Y384259D01*
G01X1303613Y386192D02*
X1298613D01*
Y387712D01*
X1298863Y388219D01*
X1299446Y388599D01*
X1300113Y388726D01*
X1300780Y388599D01*
X1301280Y388282D01*
X1301530Y387712D01*
Y386192D01*
G01X1298613Y392559D02*
X1298780Y392052D01*
X1299196Y391672D01*
X1299696Y391419D01*
X1300363Y391229D01*
X1301113Y391166D01*
X1301863Y391229D01*
X1302530Y391419D01*
X1303030Y391672D01*
X1303446Y392052D01*
X1303613Y392559D01*
X1303446Y393066D01*
X1303030Y393446D01*
X1302530Y393699D01*
X1301863Y393889D01*
X1301113Y393952D01*
X1300363Y393889D01*
X1299696Y393699D01*
X1299196Y393446D01*
X1298780Y393066D01*
X1298613Y392559D01*
G01X1294802Y405225D02*
Y402025D01*
G01Y409725D02*
Y406525D01*
G01X1303751Y525818D02*
X1297551D01*
G01D02*
Y529018D01*
G01D02*
X1303751D01*
G01D02*
Y525818D01*
G01X1308742Y535699D02*
X1302542D01*
G01D02*
Y538899D01*
G01X1294786Y543723D02*
Y549923D01*
G01D02*
X1297986D01*
G01D02*
Y543723D01*
G01D02*
X1294786D01*
G01X1301832Y540034D02*
X1295632D01*
G01D02*
Y543234D01*
G01D02*
X1301832D01*
G01D02*
Y540034D01*
G01X1305366Y551213D02*
X1299166D01*
G01D02*
Y554413D01*
G01X1297856Y553747D02*
Y550547D01*
G01D02*
X1291656D01*
G01D02*
Y553747D01*
G01X1294386Y549923D02*
Y543723D01*
G01D02*
X1291186D01*
G01D02*
Y549923D01*
G01D02*
X1294386D01*
G01X1298386Y543723D02*
Y549923D01*
G01D02*
X1301586D01*
G01D02*
Y543723D01*
G01D02*
X1298386D01*
G01X1302163Y543715D02*
X1302169Y549915D01*
G01D02*
X1305369Y549911D01*
G01X1305363Y543711D02*
X1302163Y543715D01*
G01X1302542Y538899D02*
X1308742D01*
G01X1299166Y554413D02*
X1305366D01*
G01X1303587Y564171D02*
Y570371D01*
G01X1306787Y564171D02*
X1303587D01*
G01X1291656Y553747D02*
X1297856D01*
G01X1308823Y558609D02*
X1302623D01*
G01D02*
Y561809D01*
G01D02*
X1308823D01*
G01X1294556Y554348D02*
Y560548D01*
G01D02*
X1297756D01*
G01D02*
Y554348D01*
G01D02*
X1294556D01*
G01X1302658Y558145D02*
X1308858D01*
G01Y554945D02*
X1302658D01*
G01D02*
Y558145D01*
G01X1303587Y570371D02*
X1306787D01*
G01X1300665Y573636D02*
X1297565D01*
Y574556D01*
X1297720Y574863D01*
X1298082Y575093D01*
X1298495Y575170D01*
X1298908Y575093D01*
X1299218Y574901D01*
X1299373Y574556D01*
Y573636D01*
G01X1297565Y576736D02*
X1300665D01*
Y578270D01*
G01Y580526D02*
X1299993Y580603D01*
X1299425Y580718D01*
X1298908Y580871D01*
X1298340Y581063D01*
X1297565Y581370D01*
Y579836D01*
G01X1300665Y583703D02*
X1300613Y583971D01*
X1300458Y584278D01*
X1300200Y584470D01*
X1299838Y584546D01*
X1299477Y584470D01*
X1299167Y584240D01*
X1299012Y583895D01*
Y583511D01*
X1298908Y583281D01*
X1298650Y583090D01*
X1298288Y583013D01*
X1297927Y583128D01*
X1297668Y583396D01*
X1297565Y583703D01*
X1297668Y584010D01*
X1297927Y584278D01*
X1298288Y584393D01*
X1298650Y584316D01*
X1298908Y584125D01*
X1299012Y583895D01*
Y583511D01*
X1299167Y583166D01*
X1299477Y582936D01*
X1299838Y582860D01*
X1300200Y582936D01*
X1300458Y583128D01*
X1300613Y583435D01*
X1300665Y583703D01*
G01X1302086Y573153D02*
X1314765D01*
G01X1302086Y613353D02*
Y573153D01*
G01X1300486Y598155D02*
Y591955D01*
G01D02*
X1297286D01*
G01D02*
Y598155D01*
G01X1296466Y598613D02*
Y595413D01*
G01D02*
X1290266D01*
G01D02*
Y598613D01*
G01X1296434Y591271D02*
X1290234D01*
G01D02*
Y594471D01*
G01D02*
X1296434D01*
G01D02*
Y591271D01*
G01X1297286Y598155D02*
X1300486D01*
G01X1290266Y598613D02*
X1296466D01*
G01X1302673Y644327D02*
Y625673D01*
G01D02*
X1305673Y622673D01*
G01X1314765Y613353D02*
X1302086D01*
G01X1301000Y630383D02*
X1297900D01*
Y631303D01*
X1298055Y631610D01*
X1298417Y631840D01*
X1298830Y631917D01*
X1299243Y631840D01*
X1299553Y631648D01*
X1299708Y631303D01*
Y630383D01*
G01X1298158Y635093D02*
X1298003Y634863D01*
X1297900Y634595D01*
Y634288D01*
X1298055Y633943D01*
X1298313Y633675D01*
X1298623Y633483D01*
X1299140Y633330D01*
X1299605Y633292D01*
X1300070Y633368D01*
X1300380Y633483D01*
X1300690Y633713D01*
X1300897Y633982D01*
X1301000Y634250D01*
Y634518D01*
X1300897Y634787D01*
X1300742Y635017D01*
X1300535Y635208D01*
G01X1301000Y637350D02*
X1297900D01*
X1298520Y636890D01*
G01X1301000D02*
Y637810D01*
G01Y640450D02*
X1297900D01*
X1298520Y639990D01*
G01X1301000D02*
Y640910D01*
G01X1300535Y642707D02*
X1300793Y642937D01*
X1300948Y643205D01*
X1301000Y643550D01*
X1300897Y643895D01*
X1300690Y644163D01*
X1300328Y644355D01*
X1299915Y644393D01*
X1299502Y644317D01*
X1299243Y644125D01*
X1299037Y643857D01*
X1298985Y643588D01*
X1299037Y643320D01*
X1299243Y642975D01*
X1297900Y643090D01*
Y644125D01*
G01X1309800Y644327D02*
X1302673D01*
G01X1291077Y760888D02*
Y767088D01*
G01X1294277Y760888D02*
X1291077D01*
G01X1294277Y767088D02*
Y760888D01*
G01X1295077D02*
Y767088D01*
G01X1298277Y760888D02*
X1295077D01*
G01X1298277Y767088D02*
Y760888D01*
G01X1299077Y757388D02*
Y763588D01*
G01X1302277Y757388D02*
X1299077D01*
G01X1302277Y763588D02*
Y757388D01*
G01X1290277Y763588D02*
Y757388D01*
G01X1291077Y767088D02*
X1294277D01*
G01X1295077D02*
X1298277D01*
G01X1299077Y763588D02*
X1302277D01*
G01X1301454Y1260458D02*
Y1303766D01*
G01X1296113Y1260458D02*
X1301454D01*
G01X1301487Y1308566D02*
X1307687D01*
G01X1301487Y1305366D02*
Y1308566D01*
G01X1307687Y1305366D02*
X1301487D01*
G01X1306253Y1308866D02*
X1303053D01*
G01D02*
Y1315066D01*
G01X1296069Y1307040D02*
X1295276D01*
G01X1296069Y1309640D02*
Y1307040D01*
G01X1301454Y1303766D02*
X1296113D01*
G01X1299086Y1322508D02*
X1302286D01*
G01X1299086Y1316308D02*
Y1322508D01*
G01X1302286Y1316308D02*
X1299086D01*
G01X1302286Y1322508D02*
Y1316308D01*
G01X1306230Y1326187D02*
X1303030D01*
G01D02*
Y1332387D01*
G01Y1321887D02*
X1306230D01*
G01X1303030Y1315687D02*
Y1321887D01*
G01X1306230Y1315687D02*
X1303030D01*
G01X1303053Y1315066D02*
X1306253D01*
G01X1291657Y1340265D02*
X1294857D01*
G01X1291657Y1334065D02*
Y1340265D01*
G01X1294857Y1334065D02*
X1291657D01*
G01X1294857Y1340265D02*
Y1334065D01*
G01X1303030Y1332387D02*
X1306230D01*
G01X1299746Y1334455D02*
Y1337655D01*
G01X1305946Y1334455D02*
X1299746D01*
G01Y1337655D02*
X1305946D01*
G01X1290815Y1340265D02*
Y1334065D01*
G01X1296069Y1330662D02*
Y1328471D01*
G01X1295336Y1330662D02*
X1296069D01*
G01X1292315Y1362752D02*
Y1365852D01*
X1293235D01*
X1293542Y1365697D01*
X1293772Y1365335D01*
X1293849Y1364922D01*
X1293772Y1364509D01*
X1293580Y1364199D01*
X1293235Y1364044D01*
X1292315D01*
G01X1297025Y1365594D02*
X1296795Y1365749D01*
X1296527Y1365852D01*
X1296220D01*
X1295875Y1365697D01*
X1295607Y1365439D01*
X1295415Y1365129D01*
X1295262Y1364612D01*
X1295224Y1364147D01*
X1295300Y1363682D01*
X1295415Y1363372D01*
X1295645Y1363062D01*
X1295914Y1362855D01*
X1296182Y1362752D01*
X1296450D01*
X1296719Y1362855D01*
X1296949Y1363010D01*
X1297140Y1363217D01*
G01X1299282Y1362752D02*
Y1365852D01*
X1298822Y1365232D01*
G01Y1362752D02*
X1299742D01*
G01X1302382Y1365852D02*
X1302075Y1365749D01*
X1301845Y1365490D01*
X1301692Y1365180D01*
X1301577Y1364767D01*
X1301539Y1364302D01*
X1301577Y1363837D01*
X1301692Y1363424D01*
X1301845Y1363114D01*
X1302075Y1362855D01*
X1302382Y1362752D01*
X1302689Y1362855D01*
X1302919Y1363114D01*
X1303072Y1363424D01*
X1303187Y1363837D01*
X1303225Y1364302D01*
X1303187Y1364767D01*
X1303072Y1365180D01*
X1302919Y1365490D01*
X1302689Y1365749D01*
X1302382Y1365852D01*
G01X1305482Y1362752D02*
Y1365852D01*
X1305022Y1365232D01*
G01Y1362752D02*
X1305942D01*
G01X1298356Y1441599D02*
X1290856Y1443932D01*
X1298356Y1446265D01*
G01X1295731Y1445425D02*
Y1442439D01*
G01X1297231Y1449379D02*
X1297856Y1449939D01*
X1298231Y1450592D01*
X1298356Y1451432D01*
X1298106Y1452272D01*
X1297606Y1452925D01*
X1296731Y1453392D01*
X1295731Y1453485D01*
X1294731Y1453299D01*
X1294106Y1452832D01*
X1293606Y1452179D01*
X1293481Y1451525D01*
X1293606Y1450872D01*
X1294106Y1450032D01*
X1290856Y1450312D01*
Y1452832D01*
G01X1317313Y1437636D02*
X1302313D01*
G01D02*
Y1457636D01*
G01Y1437636D02*
Y1457636D01*
G01D02*
X1317313D01*
G01X1292960Y1621152D02*
X1298960D01*
Y1609152D01*
X1292960D01*
Y1621152D01*
G01X1299908Y1621164D02*
X1305908D01*
Y1609164D01*
X1299908D01*
Y1621164D01*
G01X1295015Y1606869D02*
X1294785Y1607024D01*
X1294517Y1607127D01*
X1294210D01*
X1293865Y1606972D01*
X1293597Y1606714D01*
X1293405Y1606404D01*
X1293252Y1605887D01*
X1293214Y1605422D01*
X1293290Y1604957D01*
X1293405Y1604647D01*
X1293635Y1604337D01*
X1293904Y1604130D01*
X1294172Y1604027D01*
X1294440D01*
X1294709Y1604130D01*
X1294939Y1604285D01*
X1295130Y1604492D01*
G01X1297195Y1604027D02*
X1297272Y1604699D01*
X1297387Y1605267D01*
X1297540Y1605784D01*
X1297732Y1606352D01*
X1298039Y1607127D01*
X1296505D01*
G01X1300372D02*
X1300065Y1607024D01*
X1299835Y1606765D01*
X1299682Y1606455D01*
X1299567Y1606042D01*
X1299529Y1605577D01*
X1299567Y1605112D01*
X1299682Y1604699D01*
X1299835Y1604389D01*
X1300065Y1604130D01*
X1300372Y1604027D01*
X1300679Y1604130D01*
X1300909Y1604389D01*
X1301062Y1604699D01*
X1301177Y1605112D01*
X1301215Y1605577D01*
X1301177Y1606042D01*
X1301062Y1606455D01*
X1300909Y1606765D01*
X1300679Y1607024D01*
X1300372Y1607127D01*
G01X1303472D02*
X1303165Y1607024D01*
X1302935Y1606765D01*
X1302782Y1606455D01*
X1302667Y1606042D01*
X1302629Y1605577D01*
X1302667Y1605112D01*
X1302782Y1604699D01*
X1302935Y1604389D01*
X1303165Y1604130D01*
X1303472Y1604027D01*
X1303779Y1604130D01*
X1304009Y1604389D01*
X1304162Y1604699D01*
X1304277Y1605112D01*
X1304315Y1605577D01*
X1304277Y1606042D01*
X1304162Y1606455D01*
X1304009Y1606765D01*
X1303779Y1607024D01*
X1303472Y1607127D01*
G01X1306572D02*
X1306265Y1607024D01*
X1306035Y1606765D01*
X1305882Y1606455D01*
X1305767Y1606042D01*
X1305729Y1605577D01*
X1305767Y1605112D01*
X1305882Y1604699D01*
X1306035Y1604389D01*
X1306265Y1604130D01*
X1306572Y1604027D01*
X1306879Y1604130D01*
X1307109Y1604389D01*
X1307262Y1604699D01*
X1307377Y1605112D01*
X1307415Y1605577D01*
X1307377Y1606042D01*
X1307262Y1606455D01*
X1307109Y1606765D01*
X1306879Y1607024D01*
X1306572Y1607127D01*
G01X1292198Y1602363D02*
X1290998D01*
G01X1292198D02*
X1292192Y1619346D01*
G01X1291598Y1602363D02*
X1291602Y1619338D01*
G01X1290998Y1602363D02*
X1291001Y1619303D01*
G01X1292148Y1619296D02*
X1290639Y1619292D01*
G01X1302472Y1655552D02*
X1299372D01*
X1299992Y1655092D01*
G01X1302472D02*
Y1656012D01*
G01X1303500Y1646023D02*
X1296700D01*
G01X1298742Y1652888D02*
X1298690Y1653156D01*
X1298535Y1653463D01*
X1298277Y1653655D01*
X1297915Y1653731D01*
X1297554Y1653655D01*
X1297244Y1653425D01*
X1297089Y1653080D01*
Y1652696D01*
X1296985Y1652466D01*
X1296727Y1652275D01*
X1296365Y1652198D01*
X1296004Y1652313D01*
X1295745Y1652581D01*
X1295642Y1652888D01*
X1295745Y1653195D01*
X1296004Y1653463D01*
X1296365Y1653578D01*
X1296727Y1653501D01*
X1296985Y1653310D01*
X1297089Y1653080D01*
Y1652696D01*
X1297244Y1652351D01*
X1297554Y1652121D01*
X1297915Y1652045D01*
X1298277Y1652121D01*
X1298535Y1652313D01*
X1298690Y1652620D01*
X1298742Y1652888D01*
G01X1303500Y1646023D02*
X1296900D01*
G01X1300787Y1657834D02*
X1303000D01*
G01X1300787Y1668000D02*
Y1657834D01*
G01X1300392D02*
Y1668000D01*
G01X1297500Y1657834D02*
X1300392D01*
G01X1300787Y1740118D02*
X1367322D01*
G01X1321620Y59879D02*
X1318420D01*
G01D02*
Y66079D01*
G01X1309710Y66011D02*
Y59811D01*
G01D02*
X1306510D01*
G01D02*
Y66011D01*
G01X1315771Y55758D02*
Y57998D01*
G01X1314146Y56785D02*
X1317396D01*
G01X1314179Y50266D02*
X1311079D01*
Y51032D01*
X1311234Y51339D01*
X1311441Y51569D01*
X1311751Y51761D01*
X1312112Y51914D01*
X1312629Y51952D01*
X1313146Y51914D01*
X1313507Y51761D01*
X1313817Y51569D01*
X1314024Y51339D01*
X1314179Y51032D01*
Y50266D01*
G01Y54209D02*
X1314127Y54477D01*
X1313972Y54784D01*
X1313714Y54976D01*
X1313352Y55052D01*
X1312991Y54976D01*
X1312681Y54746D01*
X1312526Y54401D01*
Y54017D01*
X1312422Y53787D01*
X1312164Y53596D01*
X1311802Y53519D01*
X1311441Y53634D01*
X1311182Y53902D01*
X1311079Y54209D01*
X1311182Y54516D01*
X1311441Y54784D01*
X1311802Y54899D01*
X1312164Y54822D01*
X1312422Y54631D01*
X1312526Y54401D01*
Y54017D01*
X1312681Y53672D01*
X1312991Y53442D01*
X1313352Y53366D01*
X1313714Y53442D01*
X1313972Y53634D01*
X1314127Y53941D01*
X1314179Y54209D01*
G01X1311420Y58494D02*
Y68894D01*
G01X1315820D02*
Y58494D01*
G01D02*
X1311420D01*
G01X1318420Y66079D02*
X1321620D01*
G01X1306510Y66011D02*
X1309710D01*
G01X1311100Y71781D02*
Y74207D01*
G01X1311420Y68894D02*
X1315820D01*
G01X1311420Y69494D02*
X1315820D01*
G01Y70094D02*
X1311420D01*
G01Y70694D02*
X1315820D01*
G01D02*
Y68894D01*
G01X1311420Y70694D02*
Y68894D01*
G01X1310692Y84638D02*
Y75976D01*
G01X1330104Y71878D02*
X1317104D01*
G01D02*
Y86678D01*
G01X1305445Y82438D02*
X1307345Y84638D01*
G01D02*
X1310692D01*
G01X1315709Y78372D02*
X1315657Y78065D01*
X1315451Y77797D01*
X1315141Y77567D01*
X1314779Y77414D01*
X1314366Y77337D01*
X1313952D01*
X1313539Y77414D01*
X1313177Y77567D01*
X1312867Y77797D01*
X1312661Y78065D01*
X1312609Y78372D01*
X1312661Y78679D01*
X1312867Y78947D01*
X1313177Y79177D01*
X1313539Y79330D01*
X1313952Y79407D01*
X1314366D01*
X1314779Y79330D01*
X1315141Y79177D01*
X1315451Y78947D01*
X1315657Y78679D01*
X1315709Y78372D01*
G01X1314882Y78679D02*
X1315709Y79139D01*
G01X1313126Y80744D02*
X1312816Y80974D01*
X1312661Y81242D01*
X1312609Y81549D01*
X1312712Y81932D01*
X1312971Y82200D01*
X1313281Y82277D01*
X1313591Y82239D01*
X1313849Y82085D01*
X1314366Y81319D01*
X1314727Y80974D01*
X1315244Y80744D01*
X1315709Y80667D01*
Y82277D01*
G01X1315347Y83920D02*
X1315606Y84189D01*
X1315709Y84495D01*
X1315606Y84802D01*
X1315296Y85070D01*
X1314831Y85262D01*
X1314366Y85339D01*
X1313797D01*
X1313332Y85262D01*
X1312919Y85070D01*
X1312712Y84840D01*
X1312609Y84572D01*
X1312712Y84265D01*
X1312919Y84035D01*
X1313229Y83882D01*
X1313642Y83805D01*
X1314004Y83882D01*
X1314366Y84074D01*
X1314572Y84304D01*
X1314624Y84572D01*
X1314521Y84879D01*
X1314262Y85109D01*
X1313797Y85339D01*
G01X1317104Y86678D02*
X1330104D01*
G01Y89518D02*
X1317104D01*
G01D02*
Y104318D01*
G01X1304360Y118009D02*
Y87615D01*
G01X1306257Y104253D02*
Y110453D01*
G01X1309457D02*
Y104253D01*
G01D02*
X1306257D01*
G01X1317104Y104318D02*
X1330104D01*
G01X1315506Y91527D02*
X1309506D01*
G01D02*
Y103527D01*
G01D02*
X1315506D01*
G01D02*
Y91527D01*
G01X1308500Y115500D02*
X1306500Y117500D01*
G01X1308500Y119500D02*
Y115500D01*
G01X1306500Y117500D02*
X1308500Y119500D01*
G01X1321500Y117500D02*
X1306500D01*
G01X1306257Y110453D02*
X1309457D01*
G01X1307282Y113792D02*
X1307052Y114154D01*
X1306746Y114360D01*
X1306401Y114412D01*
X1306094Y114360D01*
X1305787Y114102D01*
X1305596Y113792D01*
X1305557Y113482D01*
X1305634Y113120D01*
X1305902Y112862D01*
X1306171Y112759D01*
X1306516D01*
G01X1306171D02*
X1305941Y112604D01*
X1305749Y112345D01*
X1305672Y112035D01*
X1305749Y111725D01*
X1305941Y111467D01*
X1306286Y111312D01*
X1306631Y111364D01*
X1306976Y111570D01*
G01X1304577Y154217D02*
Y148217D01*
G01X1308766Y260794D02*
X1305666D01*
Y261560D01*
X1305821Y261867D01*
X1306028Y262097D01*
X1306338Y262289D01*
X1306699Y262442D01*
X1307216Y262480D01*
X1307733Y262442D01*
X1308094Y262289D01*
X1308404Y262097D01*
X1308611Y261867D01*
X1308766Y261560D01*
Y260794D01*
G01Y264660D02*
X1308094Y264737D01*
X1307526Y264852D01*
X1307009Y265005D01*
X1306441Y265197D01*
X1305666Y265504D01*
Y263970D01*
G01X1308766Y267837D02*
X1308714Y268105D01*
X1308559Y268412D01*
X1308301Y268604D01*
X1307939Y268680D01*
X1307578Y268604D01*
X1307268Y268374D01*
X1307113Y268029D01*
Y267645D01*
X1307009Y267415D01*
X1306751Y267224D01*
X1306389Y267147D01*
X1306028Y267262D01*
X1305769Y267530D01*
X1305666Y267837D01*
X1305769Y268144D01*
X1306028Y268412D01*
X1306389Y268527D01*
X1306751Y268450D01*
X1307009Y268259D01*
X1307113Y268029D01*
Y267645D01*
X1307268Y267300D01*
X1307578Y267070D01*
X1307939Y266994D01*
X1308301Y267070D01*
X1308559Y267262D01*
X1308714Y267569D01*
X1308766Y267837D01*
G01X1316766Y260794D02*
X1313666D01*
Y261560D01*
X1313821Y261867D01*
X1314028Y262097D01*
X1314338Y262289D01*
X1314699Y262442D01*
X1315216Y262480D01*
X1315733Y262442D01*
X1316094Y262289D01*
X1316404Y262097D01*
X1316611Y261867D01*
X1316766Y261560D01*
Y260794D01*
G01Y264660D02*
X1316094Y264737D01*
X1315526Y264852D01*
X1315009Y265005D01*
X1314441Y265197D01*
X1313666Y265504D01*
Y263970D01*
G01X1316404Y267185D02*
X1316663Y267454D01*
X1316766Y267760D01*
X1316663Y268067D01*
X1316353Y268335D01*
X1315888Y268527D01*
X1315423Y268604D01*
X1314854D01*
X1314389Y268527D01*
X1313976Y268335D01*
X1313769Y268105D01*
X1313666Y267837D01*
X1313769Y267530D01*
X1313976Y267300D01*
X1314286Y267147D01*
X1314699Y267070D01*
X1315061Y267147D01*
X1315423Y267339D01*
X1315629Y267569D01*
X1315681Y267837D01*
X1315578Y268144D01*
X1315319Y268374D01*
X1314854Y268604D01*
G01X1308194Y273458D02*
Y280548D01*
G01D02*
X1311994D01*
G01D02*
Y273458D01*
G01X1308194Y272858D02*
Y280048D01*
G01D02*
X1311994D01*
G01D02*
Y272858D01*
G01X1308194Y272458D02*
Y279548D01*
G01D02*
X1311994D01*
G01D02*
Y272408D01*
G01D02*
X1308244D01*
G01X1316194Y273458D02*
Y280548D01*
G01D02*
X1319994D01*
G01X1316194Y272858D02*
Y280048D01*
G01D02*
X1319994D01*
G01X1316194Y272458D02*
Y279548D01*
G01D02*
X1319994D01*
G01Y272408D02*
X1316244D01*
G01X1312213Y294392D02*
X1307213D01*
Y295912D01*
X1307463Y296419D01*
X1308046Y296799D01*
X1308713Y296926D01*
X1309380Y296799D01*
X1309880Y296482D01*
X1310130Y295912D01*
Y294392D01*
G01X1307213Y298859D02*
X1312213Y299746D01*
X1307213Y300759D01*
X1312213Y301772D01*
X1307213Y302659D01*
G01X1312213Y304592D02*
X1307213D01*
Y306176D01*
X1307463Y306682D01*
X1307796Y306999D01*
X1308463Y307126D01*
X1309130Y306999D01*
X1309546Y306619D01*
X1309796Y306176D01*
Y304592D01*
G01Y306176D02*
X1312213Y307126D01*
G01X1309713Y311339D02*
Y312606D01*
X1311213D01*
X1311713Y312226D01*
X1312046Y311782D01*
X1312213Y311149D01*
X1312046Y310516D01*
X1311713Y310072D01*
X1311213Y309692D01*
X1310630Y309439D01*
X1309963Y309312D01*
X1309380D01*
X1308880Y309439D01*
X1308296Y309692D01*
X1307796Y310072D01*
X1307463Y310452D01*
X1307213Y310959D01*
Y311402D01*
X1307380Y311909D01*
X1307713Y312289D01*
G01X1312213Y314666D02*
X1307213D01*
Y315932D01*
X1307463Y316439D01*
X1307796Y316819D01*
X1308296Y317136D01*
X1308880Y317389D01*
X1309713Y317452D01*
X1310546Y317389D01*
X1311130Y317136D01*
X1311630Y316819D01*
X1311963Y316439D01*
X1312213Y315932D01*
Y314666D01*
G01X1313880Y319259D02*
Y323059D01*
G01X1312213Y324992D02*
X1307213D01*
Y326512D01*
X1307463Y327019D01*
X1308046Y327399D01*
X1308713Y327526D01*
X1309380Y327399D01*
X1309880Y327082D01*
X1310130Y326512D01*
Y324992D01*
G01X1307213Y329776D02*
X1312213Y331359D01*
X1307213Y332942D01*
G01X1312213Y335066D02*
X1307213D01*
Y336332D01*
X1307463Y336839D01*
X1307796Y337219D01*
X1308296Y337536D01*
X1308880Y337789D01*
X1309713Y337852D01*
X1310546Y337789D01*
X1311130Y337536D01*
X1311630Y337219D01*
X1311963Y336839D01*
X1312213Y336332D01*
Y335066D01*
G01Y340166D02*
X1307213D01*
Y341432D01*
X1307463Y341939D01*
X1307796Y342319D01*
X1308296Y342636D01*
X1308880Y342889D01*
X1309713Y342952D01*
X1310546Y342889D01*
X1311130Y342636D01*
X1311630Y342319D01*
X1311963Y341939D01*
X1312213Y341432D01*
Y340166D01*
G01X1307213Y345899D02*
Y347419D01*
G01Y346659D02*
X1312213D01*
G01Y345899D02*
Y347419D01*
G01Y351759D02*
X1312130Y351252D01*
X1311796Y350809D01*
X1311296Y350429D01*
X1310713Y350176D01*
X1310046Y350049D01*
X1309380D01*
X1308713Y350176D01*
X1308130Y350429D01*
X1307630Y350809D01*
X1307296Y351252D01*
X1307213Y351759D01*
X1307296Y352266D01*
X1307630Y352709D01*
X1308130Y353089D01*
X1308713Y353342D01*
X1309380Y353469D01*
X1310046D01*
X1310713Y353342D01*
X1311296Y353089D01*
X1311796Y352709D01*
X1312130Y352266D01*
X1312213Y351759D01*
G01X1313880Y354959D02*
Y358759D01*
G01X1312213Y360692D02*
X1307213D01*
Y362212D01*
X1307463Y362719D01*
X1308046Y363099D01*
X1308713Y363226D01*
X1309380Y363099D01*
X1309880Y362782D01*
X1310130Y362212D01*
Y360692D01*
G01X1307213Y367059D02*
X1307380Y366552D01*
X1307796Y366172D01*
X1308296Y365919D01*
X1308963Y365729D01*
X1309713Y365666D01*
X1310463Y365729D01*
X1311130Y365919D01*
X1311630Y366172D01*
X1312046Y366552D01*
X1312213Y367059D01*
X1312046Y367566D01*
X1311630Y367946D01*
X1311130Y368199D01*
X1310463Y368389D01*
X1309713Y368452D01*
X1308963Y368389D01*
X1308296Y368199D01*
X1307796Y367946D01*
X1307380Y367566D01*
X1307213Y367059D01*
G01X1320813Y294392D02*
X1315813D01*
Y295912D01*
X1316063Y296419D01*
X1316646Y296799D01*
X1317313Y296926D01*
X1317980Y296799D01*
X1318480Y296482D01*
X1318730Y295912D01*
Y294392D01*
G01X1315813Y298859D02*
X1320813Y299746D01*
X1315813Y300759D01*
X1320813Y301772D01*
X1315813Y302659D01*
G01X1320813Y304592D02*
X1315813D01*
Y306176D01*
X1316063Y306682D01*
X1316396Y306999D01*
X1317063Y307126D01*
X1317730Y306999D01*
X1318146Y306619D01*
X1318396Y306176D01*
Y304592D01*
G01Y306176D02*
X1320813Y307126D01*
G01X1318313Y311339D02*
Y312606D01*
X1319813D01*
X1320313Y312226D01*
X1320646Y311782D01*
X1320813Y311149D01*
X1320646Y310516D01*
X1320313Y310072D01*
X1319813Y309692D01*
X1319230Y309439D01*
X1318563Y309312D01*
X1317980D01*
X1317480Y309439D01*
X1316896Y309692D01*
X1316396Y310072D01*
X1316063Y310452D01*
X1315813Y310959D01*
Y311402D01*
X1315980Y311909D01*
X1316313Y312289D01*
G01X1320813Y314666D02*
X1315813D01*
Y315932D01*
X1316063Y316439D01*
X1316396Y316819D01*
X1316896Y317136D01*
X1317480Y317389D01*
X1318313Y317452D01*
X1319146Y317389D01*
X1319730Y317136D01*
X1320230Y316819D01*
X1320563Y316439D01*
X1320813Y315932D01*
Y314666D01*
G01X1322480Y319259D02*
Y323059D01*
G01X1320813Y324992D02*
X1315813D01*
Y326512D01*
X1316063Y327019D01*
X1316646Y327399D01*
X1317313Y327526D01*
X1317980Y327399D01*
X1318480Y327082D01*
X1318730Y326512D01*
Y324992D01*
G01X1315813Y329776D02*
X1320813Y331359D01*
X1315813Y332942D01*
G01X1320813Y335066D02*
X1315813D01*
Y336332D01*
X1316063Y336839D01*
X1316396Y337219D01*
X1316896Y337536D01*
X1317480Y337789D01*
X1318313Y337852D01*
X1319146Y337789D01*
X1319730Y337536D01*
X1320230Y337219D01*
X1320563Y336839D01*
X1320813Y336332D01*
Y335066D01*
G01Y340166D02*
X1315813D01*
Y341432D01*
X1316063Y341939D01*
X1316396Y342319D01*
X1316896Y342636D01*
X1317480Y342889D01*
X1318313Y342952D01*
X1319146Y342889D01*
X1319730Y342636D01*
X1320230Y342319D01*
X1320563Y341939D01*
X1320813Y341432D01*
Y340166D01*
G01Y346659D02*
X1315813D01*
X1316813Y345899D01*
G01X1320813D02*
Y347419D01*
G01Y351759D02*
X1315813D01*
X1316813Y350999D01*
G01X1320813D02*
Y352519D01*
G01X1322480Y354959D02*
Y358759D01*
G01X1320146Y360629D02*
X1320563Y361136D01*
X1320813Y361706D01*
Y362212D01*
X1320563Y362719D01*
X1320146Y363099D01*
X1319563Y363289D01*
X1318980Y363162D01*
X1318480Y362846D01*
X1318146Y362276D01*
X1317980Y361516D01*
X1317646Y361072D01*
X1317063Y360882D01*
X1316480Y361009D01*
X1316063Y361326D01*
X1315813Y361769D01*
Y362212D01*
X1315980Y362656D01*
X1316396Y363036D01*
G01X1319813Y365666D02*
X1320396Y366046D01*
X1320730Y366552D01*
X1320813Y367122D01*
X1320730Y367629D01*
X1320313Y368136D01*
X1319813Y368452D01*
X1319313Y368516D01*
X1318730Y368389D01*
X1318313Y367946D01*
X1318146Y367502D01*
Y366932D01*
G01Y367502D02*
X1317896Y367882D01*
X1317480Y368199D01*
X1316980Y368326D01*
X1316480Y368199D01*
X1316063Y367882D01*
X1315813Y367312D01*
X1315896Y366742D01*
X1316230Y366172D01*
G01X1322480Y370259D02*
Y374059D01*
G01X1320813Y375992D02*
X1315813D01*
Y377512D01*
X1316063Y378019D01*
X1316646Y378399D01*
X1317313Y378526D01*
X1317980Y378399D01*
X1318480Y378082D01*
X1318730Y377512D01*
Y375992D01*
G01X1315813Y382359D02*
X1315980Y381852D01*
X1316396Y381472D01*
X1316896Y381219D01*
X1317563Y381029D01*
X1318313Y380966D01*
X1319063Y381029D01*
X1319730Y381219D01*
X1320230Y381472D01*
X1320646Y381852D01*
X1320813Y382359D01*
X1320646Y382866D01*
X1320230Y383246D01*
X1319730Y383499D01*
X1319063Y383689D01*
X1318313Y383752D01*
X1317563Y383689D01*
X1316896Y383499D01*
X1316396Y383246D01*
X1315980Y382866D01*
X1315813Y382359D01*
G01X1317514Y522675D02*
X1329514D01*
G01X1317514Y516675D02*
Y522675D01*
G01X1329514Y516675D02*
X1317514D01*
G01X1305600Y516423D02*
Y521023D01*
G01X1315600Y516423D02*
Y521023D01*
G01X1305600Y520923D02*
Y521023D01*
G01D02*
X1315600D01*
G01Y516423D02*
X1305600D01*
G01X1308742Y538899D02*
Y535699D01*
G01X1304266Y535113D02*
X1316266D01*
G01X1304266Y529113D02*
Y535113D01*
G01X1316266D02*
Y529113D01*
G01D02*
X1304266D01*
G01X1329514Y537375D02*
X1317514D01*
G01D02*
Y543375D01*
G01Y536475D02*
X1329514D01*
G01Y530475D02*
X1317514D01*
G01D02*
Y536475D01*
G01X1329514Y523575D02*
X1317514D01*
G01D02*
Y529575D01*
G01D02*
X1329514D01*
G01X1308966Y554313D02*
Y548113D01*
G01D02*
X1305766D01*
G01D02*
Y554313D01*
G01X1305366Y554413D02*
Y551213D01*
G01X1305369Y549911D02*
X1305363Y543711D01*
G01X1314821Y546809D02*
Y546538D01*
G01D02*
X1318623D01*
G01X1317514Y543375D02*
X1329514D01*
G01X1305766Y554313D02*
X1308966D01*
G01X1320941Y565548D02*
X1314741D01*
G01D02*
Y568748D01*
G01X1306787Y570371D02*
Y564171D01*
G01X1308823Y561809D02*
Y558609D01*
G01X1308858Y558145D02*
Y554945D01*
G01X1313787Y567371D02*
Y564171D01*
G01X1307587Y567371D02*
X1313787D01*
G01X1307587Y564171D02*
Y567371D01*
G01X1313787Y564171D02*
X1307587D01*
G01X1318623Y562680D02*
X1314821D01*
G01D02*
Y562409D01*
G01X1314741Y568748D02*
X1320941D01*
G01X1305673Y622673D02*
X1309800D01*
G01X1317200D02*
X1321327D01*
G01X1324327Y644327D02*
X1317200D01*
G01X1308535Y857796D02*
G03X1310504Y855827I1969J0D01*
G01X1308535Y857796D02*
Y870788D01*
G01X1322315Y855827D02*
X1310504D01*
G01X1314244Y1180630D02*
Y1167638D01*
G01X1328023Y1182599D02*
X1316212D01*
G01D02*
G03X1314244Y1180630I0J-1968D01*
G01X1304830Y1260458D02*
Y1303766D01*
G01X1310171Y1260458D02*
X1304830D01*
G01X1307687Y1308566D02*
Y1305366D01*
G01X1306253Y1315066D02*
Y1308866D01*
G01X1309287Y1306983D02*
Y1309583D01*
G01X1310080Y1306983D02*
X1309287D01*
G01X1304830Y1303766D02*
X1310171D01*
G01X1306230Y1328400D02*
Y1326187D01*
G01Y1321887D02*
Y1315687D01*
G01X1309287Y1316194D02*
Y1317892D01*
G01X1306230Y1332387D02*
Y1331000D01*
G01X1310124Y1334818D02*
X1306924D01*
G01X1310124Y1341018D02*
Y1334818D01*
G01X1306924Y1341018D02*
X1310124D01*
G01X1306924Y1334818D02*
Y1341018D01*
G01X1305946Y1337655D02*
Y1334455D01*
G01X1317094Y1340912D02*
Y1337712D01*
G01X1310894D02*
Y1340912D01*
G01X1317094Y1337712D02*
X1310894D01*
G01Y1340912D02*
X1317094D01*
G01X1309287Y1330605D02*
X1310295D01*
G01X1309287Y1328751D02*
Y1330605D01*
G01X1307713Y1343266D02*
Y1346366D01*
X1308633D01*
X1308940Y1346211D01*
X1309170Y1345849D01*
X1309247Y1345436D01*
X1309170Y1345023D01*
X1308978Y1344713D01*
X1308633Y1344558D01*
X1307713D01*
G01X1310813Y1346366D02*
Y1343266D01*
X1312347D01*
G01X1314680D02*
Y1346366D01*
X1314220Y1345746D01*
G01Y1343266D02*
X1315140D01*
G01X1317780Y1346366D02*
X1317473Y1346263D01*
X1317243Y1346004D01*
X1317090Y1345694D01*
X1316975Y1345281D01*
X1316937Y1344816D01*
X1316975Y1344351D01*
X1317090Y1343938D01*
X1317243Y1343628D01*
X1317473Y1343369D01*
X1317780Y1343266D01*
X1318087Y1343369D01*
X1318317Y1343628D01*
X1318470Y1343938D01*
X1318585Y1344351D01*
X1318623Y1344816D01*
X1318585Y1345281D01*
X1318470Y1345694D01*
X1318317Y1346004D01*
X1318087Y1346263D01*
X1317780Y1346366D01*
G01X1307883Y1348000D02*
Y1351100D01*
X1308803D01*
X1309110Y1350945D01*
X1309340Y1350583D01*
X1309417Y1350170D01*
X1309340Y1349757D01*
X1309148Y1349447D01*
X1308803Y1349292D01*
X1307883D01*
G01X1310907Y1351100D02*
Y1348878D01*
X1311060Y1348413D01*
X1311367Y1348103D01*
X1311750Y1348000D01*
X1312133Y1348103D01*
X1312440Y1348413D01*
X1312593Y1348878D01*
Y1351100D01*
G01X1314850Y1348000D02*
Y1351100D01*
X1314390Y1350480D01*
G01Y1348000D02*
X1315310D01*
G01X1317107Y1348620D02*
X1317337Y1348258D01*
X1317643Y1348052D01*
X1317988Y1348000D01*
X1318295Y1348052D01*
X1318602Y1348310D01*
X1318793Y1348620D01*
X1318832Y1348930D01*
X1318755Y1349292D01*
X1318487Y1349550D01*
X1318218Y1349653D01*
X1317873D01*
G01X1318218D02*
X1318448Y1349808D01*
X1318640Y1350067D01*
X1318717Y1350377D01*
X1318640Y1350687D01*
X1318448Y1350945D01*
X1318103Y1351100D01*
X1317758Y1351048D01*
X1317413Y1350842D01*
G01X1333902Y1380636D02*
G02I-13386J0D01*
G01D02*
X1307130D01*
G01X1323038Y1406682D02*
X1316838D01*
G01D02*
Y1409882D01*
G01D02*
X1323038D01*
G01X1318556Y1426993D02*
Y1434493D01*
X1320422D01*
X1321169Y1434118D01*
X1321729Y1433618D01*
X1322196Y1432868D01*
X1322569Y1431993D01*
X1322662Y1430743D01*
X1322569Y1429493D01*
X1322196Y1428618D01*
X1321729Y1427868D01*
X1321169Y1427368D01*
X1320422Y1426993D01*
X1318556D01*
G01X1326989Y1434493D02*
X1329229D01*
G01X1328109D02*
Y1426993D01*
G01X1326989D02*
X1329229D01*
G01X1333182D02*
Y1434493D01*
X1335609Y1428243D01*
X1338036Y1434493D01*
Y1426993D01*
G01X1340682D02*
Y1434493D01*
X1343109Y1428243D01*
X1345536Y1434493D01*
Y1426993D01*
G01X1313356Y1441599D02*
X1305856Y1443932D01*
X1313356Y1446265D01*
G01X1310731Y1445425D02*
Y1442439D01*
G01X1313356Y1452552D02*
X1305856D01*
X1311231Y1449099D01*
Y1453765D01*
G01X1332313Y1437636D02*
X1317313D01*
G01D02*
Y1457636D01*
G01D02*
Y1437636D01*
G01Y1457636D02*
X1332313D01*
G01X1313368Y1540451D02*
Y1557400D01*
G01X1318700Y1540451D02*
X1313368D01*
G01Y1561700D02*
Y1575491D01*
G01X1304726Y1572911D02*
Y1569503D01*
G01X1313368Y1575491D02*
X1319700D01*
G01X1304726Y1587219D02*
Y1583811D01*
G01X1312832Y1655284D02*
X1312522Y1655514D01*
X1312367Y1655782D01*
X1312315Y1656089D01*
X1312418Y1656472D01*
X1312677Y1656740D01*
X1312987Y1656817D01*
X1313297Y1656779D01*
X1313555Y1656625D01*
X1314072Y1655859D01*
X1314433Y1655514D01*
X1314950Y1655284D01*
X1315415Y1655207D01*
Y1656817D01*
G01X1315300Y1646023D02*
X1309000D01*
G01X1312203D02*
X1309000D01*
G01X1312203Y1653500D02*
Y1646023D01*
G01X1309200Y1657834D02*
X1310000D01*
G01X1312203Y1667720D02*
Y1660000D01*
G01X1315891Y1736629D02*
X1314825D01*
Y1739129D01*
X1315891D01*
G01X1315465Y1737921D02*
X1314825D01*
G01X1316971Y1736629D02*
Y1739129D01*
X1317505D01*
X1317718Y1739004D01*
X1317878Y1738837D01*
X1318011Y1738587D01*
X1318118Y1738296D01*
X1318145Y1737879D01*
X1318118Y1737462D01*
X1318011Y1737171D01*
X1317878Y1736921D01*
X1317718Y1736754D01*
X1317505Y1736629D01*
X1316971D01*
G01X1319918Y1737879D02*
X1320451D01*
Y1737129D01*
X1320291Y1736879D01*
X1320105Y1736712D01*
X1319838Y1736629D01*
X1319571Y1736712D01*
X1319385Y1736879D01*
X1319225Y1737129D01*
X1319118Y1737421D01*
X1319065Y1737754D01*
Y1738046D01*
X1319118Y1738296D01*
X1319225Y1738587D01*
X1319385Y1738837D01*
X1319545Y1739004D01*
X1319758Y1739129D01*
X1319945D01*
X1320158Y1739046D01*
X1320318Y1738879D01*
G01X1322491Y1736629D02*
X1321425D01*
Y1739129D01*
X1322491D01*
G01X1322065Y1737921D02*
X1321425D01*
G01X1326358Y1736629D02*
X1326145Y1736671D01*
X1325958Y1736837D01*
X1325798Y1737087D01*
X1325691Y1737379D01*
X1325638Y1737712D01*
Y1738046D01*
X1325691Y1738379D01*
X1325798Y1738671D01*
X1325958Y1738921D01*
X1326145Y1739087D01*
X1326358Y1739129D01*
X1326571Y1739087D01*
X1326758Y1738921D01*
X1326918Y1738671D01*
X1327025Y1738379D01*
X1327078Y1738046D01*
Y1737712D01*
X1327025Y1737379D01*
X1326918Y1737087D01*
X1326758Y1736837D01*
X1326571Y1736671D01*
X1326358Y1736629D01*
G01X1328051D02*
Y1739129D01*
X1329065D01*
G01X1328691Y1737921D02*
X1328051D01*
G01X1332371Y1736629D02*
Y1739129D01*
X1332905D01*
X1333118Y1739004D01*
X1333278Y1738837D01*
X1333411Y1738587D01*
X1333518Y1738296D01*
X1333545Y1737879D01*
X1333518Y1737462D01*
X1333411Y1737171D01*
X1333278Y1736921D01*
X1333118Y1736754D01*
X1332905Y1736629D01*
X1332371D01*
G01X1334491D02*
X1335158Y1739129D01*
X1335825Y1736629D01*
G01X1335585Y1737504D02*
X1334731D01*
G01X1336771Y1739129D02*
Y1737337D01*
X1336878Y1736962D01*
X1337091Y1736712D01*
X1337358Y1736629D01*
X1337625Y1736712D01*
X1337838Y1736962D01*
X1337945Y1737337D01*
Y1739129D01*
G01X1339718Y1737879D02*
X1340251D01*
Y1737129D01*
X1340091Y1736879D01*
X1339905Y1736712D01*
X1339638Y1736629D01*
X1339371Y1736712D01*
X1339185Y1736879D01*
X1339025Y1737129D01*
X1338918Y1737421D01*
X1338865Y1737754D01*
Y1738046D01*
X1338918Y1738296D01*
X1339025Y1738587D01*
X1339185Y1738837D01*
X1339345Y1739004D01*
X1339558Y1739129D01*
X1339745D01*
X1339958Y1739046D01*
X1340118Y1738879D01*
G01X1341198Y1736629D02*
Y1739129D01*
G01X1342318D02*
Y1736629D01*
G01Y1737879D02*
X1341198D01*
G01X1343958Y1739129D02*
Y1736629D01*
G01X1343345Y1739129D02*
X1344571D01*
G01X1346691Y1736629D02*
X1345625D01*
Y1739129D01*
X1346691D01*
G01X1346265Y1737921D02*
X1345625D01*
G01X1347825Y1736629D02*
Y1739129D01*
X1348491D01*
X1348705Y1739004D01*
X1348838Y1738837D01*
X1348891Y1738504D01*
X1348838Y1738171D01*
X1348678Y1737962D01*
X1348491Y1737837D01*
X1347825D01*
G01X1348491D02*
X1348891Y1736629D01*
G01X1353345Y1738921D02*
X1353185Y1739046D01*
X1352998Y1739129D01*
X1352785D01*
X1352545Y1739004D01*
X1352358Y1738796D01*
X1352225Y1738546D01*
X1352118Y1738129D01*
X1352091Y1737754D01*
X1352145Y1737379D01*
X1352225Y1737129D01*
X1352385Y1736879D01*
X1352571Y1736712D01*
X1352758Y1736629D01*
X1352945D01*
X1353131Y1736712D01*
X1353291Y1736837D01*
X1353425Y1737004D01*
G01X1354291Y1736629D02*
X1354958Y1739129D01*
X1355625Y1736629D01*
G01X1355385Y1737504D02*
X1354531D01*
G01X1356625Y1736629D02*
Y1739129D01*
X1357291D01*
X1357505Y1739004D01*
X1357638Y1738837D01*
X1357691Y1738504D01*
X1357638Y1738171D01*
X1357478Y1737962D01*
X1357291Y1737837D01*
X1356625D01*
G01X1357291D02*
X1357691Y1736629D01*
G01X1358771D02*
Y1739129D01*
X1359305D01*
X1359518Y1739004D01*
X1359678Y1738837D01*
X1359811Y1738587D01*
X1359918Y1738296D01*
X1359945Y1737879D01*
X1359918Y1737462D01*
X1359811Y1737171D01*
X1359678Y1736921D01*
X1359518Y1736754D01*
X1359305Y1736629D01*
X1358771D01*
G01X1312808Y1736412D02*
X1313708Y1737312D01*
G01X1307808Y1736412D02*
X1312808D01*
G01X1307808Y1739812D02*
Y1736412D01*
G01X1309808Y1737812D02*
X1307808Y1739812D01*
G01X1305808Y1737812D02*
X1309808D01*
G01X1307808Y1739812D02*
X1305808Y1737812D01*
G01X1321620Y66079D02*
Y59879D01*
G01X1330330Y59845D02*
Y66045D01*
G01X1333530D02*
Y59845D01*
G01D02*
X1330330D01*
G01X1326963Y51391D02*
X1323863D01*
Y52157D01*
X1324018Y52464D01*
X1324225Y52694D01*
X1324535Y52886D01*
X1324896Y53039D01*
X1325413Y53077D01*
X1325930Y53039D01*
X1326291Y52886D01*
X1326601Y52694D01*
X1326808Y52464D01*
X1326963Y52157D01*
Y51391D01*
G01X1326601Y54682D02*
X1326860Y54951D01*
X1326963Y55257D01*
X1326860Y55564D01*
X1326550Y55832D01*
X1326085Y56024D01*
X1325620Y56101D01*
X1325051D01*
X1324586Y56024D01*
X1324173Y55832D01*
X1323966Y55602D01*
X1323863Y55334D01*
X1323966Y55027D01*
X1324173Y54797D01*
X1324483Y54644D01*
X1324896Y54567D01*
X1325258Y54644D01*
X1325620Y54836D01*
X1325826Y55066D01*
X1325878Y55334D01*
X1325775Y55641D01*
X1325516Y55871D01*
X1325051Y56101D01*
G01X1323630Y59174D02*
Y66264D01*
G01X1327430D02*
Y59124D01*
G01D02*
X1323680D01*
G01X1323630Y59574D02*
Y66764D01*
G01X1327430D02*
Y59574D01*
G01X1323630Y60174D02*
Y67264D01*
G01X1327430D02*
Y60174D01*
G01X1335721Y102214D02*
Y100214D01*
X1335772Y100163D01*
Y99547D01*
X1331258D01*
Y71951D01*
X1334745Y68464D01*
G01X1335006Y68300D02*
X1332178D01*
G01D02*
X1335006Y71128D01*
G01X1330330Y66045D02*
X1333530D01*
G01X1330104Y86678D02*
Y71878D01*
G01X1323630Y66264D02*
X1327430D01*
G01X1323630Y66764D02*
X1327430D01*
G01X1323630Y67264D02*
X1327430D01*
G01X1336900Y80350D02*
X1336848Y80043D01*
X1336642Y79775D01*
X1336332Y79545D01*
X1335970Y79392D01*
X1335557Y79315D01*
X1335143D01*
X1334730Y79392D01*
X1334368Y79545D01*
X1334058Y79775D01*
X1333852Y80043D01*
X1333800Y80350D01*
X1333852Y80657D01*
X1334058Y80925D01*
X1334368Y81155D01*
X1334730Y81308D01*
X1335143Y81385D01*
X1335557D01*
X1335970Y81308D01*
X1336332Y81155D01*
X1336642Y80925D01*
X1336848Y80657D01*
X1336900Y80350D01*
G01X1336073Y80657D02*
X1336900Y81117D01*
G01X1334317Y82722D02*
X1334007Y82952D01*
X1333852Y83220D01*
X1333800Y83527D01*
X1333903Y83910D01*
X1334162Y84178D01*
X1334472Y84255D01*
X1334782Y84217D01*
X1335040Y84063D01*
X1335557Y83297D01*
X1335918Y82952D01*
X1336435Y82722D01*
X1336900Y82645D01*
Y84255D01*
G01X1330104Y104318D02*
Y89518D01*
G01X1334999Y90984D02*
X1331799D01*
G01D02*
Y97184D01*
G01D02*
X1334999D01*
G01X1321002Y106661D02*
X1320695Y106713D01*
X1320427Y106919D01*
X1320197Y107229D01*
X1320044Y107591D01*
X1319967Y108004D01*
Y108418D01*
X1320044Y108831D01*
X1320197Y109193D01*
X1320427Y109503D01*
X1320695Y109709D01*
X1321002Y109761D01*
X1321309Y109709D01*
X1321577Y109503D01*
X1321807Y109193D01*
X1321960Y108831D01*
X1322037Y108418D01*
Y108004D01*
X1321960Y107591D01*
X1321807Y107229D01*
X1321577Y106919D01*
X1321309Y106713D01*
X1321002Y106661D01*
G01X1321309Y107488D02*
X1321769Y106661D01*
G01X1323259Y107281D02*
X1323489Y106919D01*
X1323795Y106713D01*
X1324140Y106661D01*
X1324447Y106713D01*
X1324754Y106971D01*
X1324945Y107281D01*
X1324984Y107591D01*
X1324907Y107953D01*
X1324639Y108211D01*
X1324370Y108314D01*
X1324025D01*
G01X1324370D02*
X1324600Y108469D01*
X1324792Y108728D01*
X1324869Y109038D01*
X1324792Y109348D01*
X1324600Y109606D01*
X1324255Y109761D01*
X1323910Y109709D01*
X1323565Y109503D01*
G01X1327202Y109761D02*
X1326895Y109658D01*
X1326665Y109399D01*
X1326512Y109089D01*
X1326397Y108676D01*
X1326359Y108211D01*
X1326397Y107746D01*
X1326512Y107333D01*
X1326665Y107023D01*
X1326895Y106764D01*
X1327202Y106661D01*
X1327509Y106764D01*
X1327739Y107023D01*
X1327892Y107333D01*
X1328007Y107746D01*
X1328045Y108211D01*
X1328007Y108676D01*
X1327892Y109089D01*
X1327739Y109399D01*
X1327509Y109658D01*
X1327202Y109761D01*
G01X1321500Y126000D02*
Y117500D01*
G01X1323918Y129740D02*
X1324148Y130050D01*
X1324416Y130205D01*
X1324723Y130257D01*
X1325106Y130154D01*
X1325374Y129895D01*
X1325451Y129585D01*
X1325413Y129275D01*
X1325259Y129017D01*
X1324493Y128500D01*
X1324148Y128139D01*
X1323918Y127622D01*
X1323841Y127157D01*
X1325451D01*
G01X1327248Y128190D02*
X1328244D01*
G01X1330003Y127777D02*
X1330233Y127415D01*
X1330539Y127209D01*
X1330884Y127157D01*
X1331191Y127209D01*
X1331498Y127467D01*
X1331689Y127777D01*
X1331728Y128087D01*
X1331651Y128449D01*
X1331383Y128707D01*
X1331114Y128810D01*
X1330769D01*
G01X1331114D02*
X1331344Y128965D01*
X1331536Y129224D01*
X1331613Y129534D01*
X1331536Y129844D01*
X1331344Y130102D01*
X1330999Y130257D01*
X1330654Y130205D01*
X1330309Y129999D01*
G01X1337353Y128810D02*
X1337506Y128965D01*
X1337621Y129224D01*
X1337698Y129585D01*
X1337621Y129895D01*
X1337468Y130102D01*
X1337199Y130257D01*
X1336164D01*
Y127157D01*
X1337429D01*
X1337698Y127364D01*
X1337851Y127674D01*
X1337928Y128035D01*
X1337851Y128397D01*
X1337621Y128707D01*
X1337353Y128810D01*
X1336164D01*
G01X1339686Y130257D02*
X1340606D01*
G01X1340146D02*
Y127157D01*
G01X1339686D02*
X1340606D01*
G01X1343246D02*
X1342939Y127209D01*
X1342671Y127415D01*
X1342441Y127725D01*
X1342288Y128087D01*
X1342211Y128500D01*
Y128914D01*
X1342288Y129327D01*
X1342441Y129689D01*
X1342671Y129999D01*
X1342939Y130205D01*
X1343246Y130257D01*
X1343553Y130205D01*
X1343821Y129999D01*
X1344051Y129689D01*
X1344204Y129327D01*
X1344281Y128914D01*
Y128500D01*
X1344204Y128087D01*
X1344051Y127725D01*
X1343821Y127415D01*
X1343553Y127209D01*
X1343246Y127157D01*
G01X1345541Y127570D02*
X1345848Y127312D01*
X1346193Y127157D01*
X1346499D01*
X1346806Y127312D01*
X1347036Y127570D01*
X1347151Y127932D01*
X1347074Y128294D01*
X1346883Y128604D01*
X1346538Y128810D01*
X1346078Y128914D01*
X1345809Y129120D01*
X1345694Y129482D01*
X1345771Y129844D01*
X1345963Y130102D01*
X1346231Y130257D01*
X1346499D01*
X1346768Y130154D01*
X1346998Y129895D01*
G01X1351779Y130257D02*
Y127157D01*
X1353313D01*
G01X1355646D02*
X1355339Y127209D01*
X1355071Y127415D01*
X1354841Y127725D01*
X1354688Y128087D01*
X1354611Y128500D01*
Y128914D01*
X1354688Y129327D01*
X1354841Y129689D01*
X1355071Y129999D01*
X1355339Y130205D01*
X1355646Y130257D01*
X1355953Y130205D01*
X1356221Y129999D01*
X1356451Y129689D01*
X1356604Y129327D01*
X1356681Y128914D01*
Y128500D01*
X1356604Y128087D01*
X1356451Y127725D01*
X1356221Y127415D01*
X1355953Y127209D01*
X1355646Y127157D01*
G01X1357788D02*
X1358746Y130257D01*
X1359704Y127157D01*
G01X1359359Y128242D02*
X1358133D01*
G01X1361003Y127157D02*
Y130257D01*
X1361769D01*
X1362076Y130102D01*
X1362306Y129895D01*
X1362498Y129585D01*
X1362651Y129224D01*
X1362689Y128707D01*
X1362651Y128190D01*
X1362498Y127829D01*
X1362306Y127519D01*
X1362076Y127312D01*
X1361769Y127157D01*
X1361003D01*
G01X1367203D02*
Y130257D01*
X1367969D01*
X1368276Y130102D01*
X1368506Y129895D01*
X1368698Y129585D01*
X1368851Y129224D01*
X1368889Y128707D01*
X1368851Y128190D01*
X1368698Y127829D01*
X1368506Y127519D01*
X1368276Y127312D01*
X1367969Y127157D01*
X1367203D01*
G01X1371913D02*
X1370379D01*
Y130257D01*
X1371913D01*
G01X1371299Y128759D02*
X1370379D01*
G01X1373518Y127157D02*
Y130257D01*
X1374974D01*
G01X1374438Y128759D02*
X1373518D01*
G01X1376388Y127157D02*
X1377346Y130257D01*
X1378304Y127157D01*
G01X1377959Y128242D02*
X1376733D01*
G01X1379603Y130257D02*
Y128035D01*
X1379756Y127570D01*
X1380063Y127260D01*
X1380446Y127157D01*
X1380829Y127260D01*
X1381136Y127570D01*
X1381289Y128035D01*
Y130257D01*
G01X1382779D02*
Y127157D01*
X1384313D01*
G01X1386646Y130257D02*
Y127157D01*
G01X1385764Y130257D02*
X1387528D01*
G01X1324646Y134757D02*
Y137857D01*
X1324186Y137237D01*
G01Y134757D02*
X1325106D01*
G01X1327248Y135790D02*
X1328244D01*
G01X1330118Y137340D02*
X1330348Y137650D01*
X1330616Y137805D01*
X1330923Y137857D01*
X1331306Y137754D01*
X1331574Y137495D01*
X1331651Y137185D01*
X1331613Y136875D01*
X1331459Y136617D01*
X1330693Y136100D01*
X1330348Y135739D01*
X1330118Y135222D01*
X1330041Y134757D01*
X1331651D01*
G01X1336164D02*
Y137857D01*
X1337928Y134757D01*
Y137857D01*
G01X1340146Y134757D02*
X1339839Y134809D01*
X1339571Y135015D01*
X1339341Y135325D01*
X1339188Y135687D01*
X1339111Y136100D01*
Y136514D01*
X1339188Y136927D01*
X1339341Y137289D01*
X1339571Y137599D01*
X1339839Y137805D01*
X1340146Y137857D01*
X1340453Y137805D01*
X1340721Y137599D01*
X1340951Y137289D01*
X1341104Y136927D01*
X1341181Y136514D01*
Y136100D01*
X1341104Y135687D01*
X1340951Y135325D01*
X1340721Y135015D01*
X1340453Y134809D01*
X1340146Y134757D01*
G01X1342479D02*
Y137857D01*
X1343438D01*
X1343744Y137702D01*
X1343936Y137495D01*
X1344013Y137082D01*
X1343936Y136669D01*
X1343706Y136410D01*
X1343438Y136255D01*
X1342479D01*
G01X1343438D02*
X1344013Y134757D01*
G01X1345349D02*
Y137857D01*
X1346346Y135274D01*
X1347343Y137857D01*
Y134757D01*
G01X1348488D02*
X1349446Y137857D01*
X1350404Y134757D01*
G01X1350059Y135842D02*
X1348833D01*
G01X1351779Y137857D02*
Y134757D01*
X1353313D01*
G01X1358746D02*
X1358439Y134809D01*
X1358171Y135015D01*
X1357941Y135325D01*
X1357788Y135687D01*
X1357711Y136100D01*
Y136514D01*
X1357788Y136927D01*
X1357941Y137289D01*
X1358171Y137599D01*
X1358439Y137805D01*
X1358746Y137857D01*
X1359053Y137805D01*
X1359321Y137599D01*
X1359551Y137289D01*
X1359704Y136927D01*
X1359781Y136514D01*
Y136100D01*
X1359704Y135687D01*
X1359551Y135325D01*
X1359321Y135015D01*
X1359053Y134809D01*
X1358746Y134757D01*
G01X1361079D02*
Y137857D01*
X1361999D01*
X1362306Y137702D01*
X1362536Y137340D01*
X1362613Y136927D01*
X1362536Y136514D01*
X1362344Y136204D01*
X1361999Y136049D01*
X1361079D01*
G01X1365713Y134757D02*
X1364179D01*
Y137857D01*
X1365713D01*
G01X1365099Y136359D02*
X1364179D01*
G01X1367279Y134757D02*
Y137857D01*
X1368238D01*
X1368544Y137702D01*
X1368736Y137495D01*
X1368813Y137082D01*
X1368736Y136669D01*
X1368506Y136410D01*
X1368238Y136255D01*
X1367279D01*
G01X1368238D02*
X1368813Y134757D01*
G01X1370188D02*
X1371146Y137857D01*
X1372104Y134757D01*
G01X1371759Y135842D02*
X1370533D01*
G01X1374246Y137857D02*
Y134757D01*
G01X1373364Y137857D02*
X1375128D01*
G01X1376886D02*
X1377806D01*
G01X1377346D02*
Y134757D01*
G01X1376886D02*
X1377806D01*
G01X1380446D02*
X1380139Y134809D01*
X1379871Y135015D01*
X1379641Y135325D01*
X1379488Y135687D01*
X1379411Y136100D01*
Y136514D01*
X1379488Y136927D01*
X1379641Y137289D01*
X1379871Y137599D01*
X1380139Y137805D01*
X1380446Y137857D01*
X1380753Y137805D01*
X1381021Y137599D01*
X1381251Y137289D01*
X1381404Y136927D01*
X1381481Y136514D01*
Y136100D01*
X1381404Y135687D01*
X1381251Y135325D01*
X1381021Y135015D01*
X1380753Y134809D01*
X1380446Y134757D01*
G01X1382664D02*
Y137857D01*
X1384428Y134757D01*
Y137857D01*
G01X1386454Y133724D02*
X1386071Y134240D01*
X1385879Y134757D01*
Y136824D01*
X1386071Y137340D01*
X1386454Y137857D01*
G01X1388903Y134757D02*
Y137857D01*
X1389669D01*
X1389976Y137702D01*
X1390206Y137495D01*
X1390398Y137185D01*
X1390551Y136824D01*
X1390589Y136307D01*
X1390551Y135790D01*
X1390398Y135429D01*
X1390206Y135119D01*
X1389976Y134912D01*
X1389669Y134757D01*
X1388903D01*
G01X1393613D02*
X1392079D01*
Y137857D01*
X1393613D01*
G01X1392999Y136359D02*
X1392079D01*
G01X1395218Y134757D02*
Y137857D01*
X1396674D01*
G01X1396138Y136359D02*
X1395218D01*
G01X1398088Y134757D02*
X1399046Y137857D01*
X1400004Y134757D01*
G01X1399659Y135842D02*
X1398433D01*
G01X1401303Y137857D02*
Y135635D01*
X1401456Y135170D01*
X1401763Y134860D01*
X1402146Y134757D01*
X1402529Y134860D01*
X1402836Y135170D01*
X1402989Y135635D01*
Y137857D01*
G01X1404479D02*
Y134757D01*
X1406013D01*
G01X1408346Y137857D02*
Y134757D01*
G01X1407464Y137857D02*
X1409228D01*
G01X1411638Y133724D02*
X1412021Y134240D01*
X1412213Y134757D01*
Y136824D01*
X1412021Y137340D01*
X1411638Y137857D01*
G01X1321500Y126000D02*
Y147000D01*
G01X1413500Y126000D02*
X1321500D01*
G01X1325489Y145199D02*
X1325259Y145354D01*
X1324991Y145457D01*
X1324684D01*
X1324339Y145302D01*
X1324071Y145044D01*
X1323879Y144734D01*
X1323726Y144217D01*
X1323688Y143752D01*
X1323764Y143287D01*
X1323879Y142977D01*
X1324109Y142667D01*
X1324378Y142460D01*
X1324646Y142357D01*
X1324914D01*
X1325183Y142460D01*
X1325413Y142615D01*
X1325604Y142822D01*
G01X1326979Y145457D02*
Y142357D01*
X1328513D01*
G01X1331613D02*
X1330079D01*
Y145457D01*
X1331613D01*
G01X1330999Y143959D02*
X1330079D01*
G01X1332988Y142357D02*
X1333946Y145457D01*
X1334904Y142357D01*
G01X1334559Y143442D02*
X1333333D01*
G01X1336279Y142357D02*
Y145457D01*
X1337238D01*
X1337544Y145302D01*
X1337736Y145095D01*
X1337813Y144682D01*
X1337736Y144269D01*
X1337506Y144010D01*
X1337238Y143855D01*
X1336279D01*
G01X1337238D02*
X1337813Y142357D01*
G01X1344089Y145199D02*
X1343859Y145354D01*
X1343591Y145457D01*
X1343284D01*
X1342939Y145302D01*
X1342671Y145044D01*
X1342479Y144734D01*
X1342326Y144217D01*
X1342288Y143752D01*
X1342364Y143287D01*
X1342479Y142977D01*
X1342709Y142667D01*
X1342978Y142460D01*
X1343246Y142357D01*
X1343514D01*
X1343783Y142460D01*
X1344013Y142615D01*
X1344204Y142822D01*
G01X1345349Y142357D02*
Y145457D01*
X1346346Y142874D01*
X1347343Y145457D01*
Y142357D01*
G01X1349446D02*
X1349139Y142409D01*
X1348871Y142615D01*
X1348641Y142925D01*
X1348488Y143287D01*
X1348411Y143700D01*
Y144114D01*
X1348488Y144527D01*
X1348641Y144889D01*
X1348871Y145199D01*
X1349139Y145405D01*
X1349446Y145457D01*
X1349753Y145405D01*
X1350021Y145199D01*
X1350251Y144889D01*
X1350404Y144527D01*
X1350481Y144114D01*
Y143700D01*
X1350404Y143287D01*
X1350251Y142925D01*
X1350021Y142615D01*
X1349753Y142409D01*
X1349446Y142357D01*
G01X1351741Y142770D02*
X1352048Y142512D01*
X1352393Y142357D01*
X1352699D01*
X1353006Y142512D01*
X1353236Y142770D01*
X1353351Y143132D01*
X1353274Y143494D01*
X1353083Y143804D01*
X1352738Y144010D01*
X1352278Y144114D01*
X1352009Y144320D01*
X1351894Y144682D01*
X1351971Y145044D01*
X1352163Y145302D01*
X1352431Y145457D01*
X1352699D01*
X1352968Y145354D01*
X1353198Y145095D01*
G01X1357979Y142977D02*
X1358171Y142667D01*
X1358401Y142460D01*
X1358669Y142357D01*
X1358976Y142460D01*
X1359206Y142667D01*
X1359436Y142977D01*
X1359513Y143390D01*
Y145457D01*
G01X1361003D02*
Y143235D01*
X1361156Y142770D01*
X1361463Y142460D01*
X1361846Y142357D01*
X1362229Y142460D01*
X1362536Y142770D01*
X1362689Y143235D01*
Y145457D01*
G01X1363949Y142357D02*
Y145457D01*
X1364946Y142874D01*
X1365943Y145457D01*
Y142357D01*
G01X1367279D02*
Y145457D01*
X1368199D01*
X1368506Y145302D01*
X1368736Y144940D01*
X1368813Y144527D01*
X1368736Y144114D01*
X1368544Y143804D01*
X1368199Y143649D01*
X1367279D01*
G01X1371913Y142357D02*
X1370379D01*
Y145457D01*
X1371913D01*
G01X1371299Y143959D02*
X1370379D01*
G01X1373479Y142357D02*
Y145457D01*
X1374438D01*
X1374744Y145302D01*
X1374936Y145095D01*
X1375013Y144682D01*
X1374936Y144269D01*
X1374706Y144010D01*
X1374438Y143855D01*
X1373479D01*
G01X1374438D02*
X1375013Y142357D01*
G01X1321500Y147000D02*
X1413500D01*
G01X1328307Y235343D02*
X1328499Y235033D01*
X1328729Y234826D01*
X1328997Y234723D01*
X1329304Y234826D01*
X1329534Y235033D01*
X1329764Y235343D01*
X1329841Y235756D01*
Y237823D01*
G01X1331331Y235188D02*
X1331561Y234930D01*
X1331829Y234775D01*
X1332174Y234723D01*
X1332519Y234826D01*
X1332787Y235033D01*
X1332979Y235395D01*
X1333017Y235808D01*
X1332941Y236221D01*
X1332749Y236480D01*
X1332481Y236686D01*
X1332212Y236738D01*
X1331944Y236686D01*
X1331599Y236480D01*
X1331714Y237823D01*
X1332749D01*
G01X1324766Y260794D02*
X1321666D01*
Y261560D01*
X1321821Y261867D01*
X1322028Y262097D01*
X1322338Y262289D01*
X1322699Y262442D01*
X1323216Y262480D01*
X1323733Y262442D01*
X1324094Y262289D01*
X1324404Y262097D01*
X1324611Y261867D01*
X1324766Y261560D01*
Y260794D01*
G01Y264737D02*
X1324714Y265005D01*
X1324559Y265312D01*
X1324301Y265504D01*
X1323939Y265580D01*
X1323578Y265504D01*
X1323268Y265274D01*
X1323113Y264929D01*
Y264545D01*
X1323009Y264315D01*
X1322751Y264124D01*
X1322389Y264047D01*
X1322028Y264162D01*
X1321769Y264430D01*
X1321666Y264737D01*
X1321769Y265044D01*
X1322028Y265312D01*
X1322389Y265427D01*
X1322751Y265350D01*
X1323009Y265159D01*
X1323113Y264929D01*
Y264545D01*
X1323268Y264200D01*
X1323578Y263970D01*
X1323939Y263894D01*
X1324301Y263970D01*
X1324559Y264162D01*
X1324714Y264469D01*
X1324766Y264737D01*
G01X1321666Y267837D02*
X1321769Y267530D01*
X1322028Y267300D01*
X1322338Y267147D01*
X1322751Y267032D01*
X1323216Y266994D01*
X1323681Y267032D01*
X1324094Y267147D01*
X1324404Y267300D01*
X1324663Y267530D01*
X1324766Y267837D01*
X1324663Y268144D01*
X1324404Y268374D01*
X1324094Y268527D01*
X1323681Y268642D01*
X1323216Y268680D01*
X1322751Y268642D01*
X1322338Y268527D01*
X1322028Y268374D01*
X1321769Y268144D01*
X1321666Y267837D01*
G01X1332766Y260794D02*
X1329666D01*
Y261560D01*
X1329821Y261867D01*
X1330028Y262097D01*
X1330338Y262289D01*
X1330699Y262442D01*
X1331216Y262480D01*
X1331733Y262442D01*
X1332094Y262289D01*
X1332404Y262097D01*
X1332611Y261867D01*
X1332766Y261560D01*
Y260794D01*
G01Y264737D02*
X1332714Y265005D01*
X1332559Y265312D01*
X1332301Y265504D01*
X1331939Y265580D01*
X1331578Y265504D01*
X1331268Y265274D01*
X1331113Y264929D01*
Y264545D01*
X1331009Y264315D01*
X1330751Y264124D01*
X1330389Y264047D01*
X1330028Y264162D01*
X1329769Y264430D01*
X1329666Y264737D01*
X1329769Y265044D01*
X1330028Y265312D01*
X1330389Y265427D01*
X1330751Y265350D01*
X1331009Y265159D01*
X1331113Y264929D01*
Y264545D01*
X1331268Y264200D01*
X1331578Y263970D01*
X1331939Y263894D01*
X1332301Y263970D01*
X1332559Y264162D01*
X1332714Y264469D01*
X1332766Y264737D01*
G01Y267837D02*
X1329666D01*
X1330286Y267377D01*
G01X1332766D02*
Y268297D01*
G01X1324194Y273458D02*
Y280548D01*
G01D02*
X1327994D01*
G01D02*
Y273458D01*
G01X1324194Y272858D02*
Y280048D01*
G01D02*
X1327994D01*
G01D02*
Y272858D01*
G01X1324194Y272458D02*
Y279548D01*
G01D02*
X1327994D01*
G01D02*
Y272408D01*
G01D02*
X1324244D01*
G01X1332194Y273458D02*
Y280548D01*
G01D02*
X1335994D01*
G01X1332194Y272858D02*
Y280048D01*
G01D02*
X1335994D01*
G01X1332194Y272458D02*
Y279548D01*
G01D02*
X1335994D01*
G01Y272408D02*
X1332244D01*
G01X1319994Y280548D02*
Y273458D01*
G01Y280048D02*
Y272858D01*
G01Y279548D02*
Y272408D01*
G01X1328413Y294392D02*
X1323413D01*
Y295912D01*
X1323663Y296419D01*
X1324246Y296799D01*
X1324913Y296926D01*
X1325580Y296799D01*
X1326080Y296482D01*
X1326330Y295912D01*
Y294392D01*
G01X1323413Y298859D02*
X1328413Y299746D01*
X1323413Y300759D01*
X1328413Y301772D01*
X1323413Y302659D01*
G01X1328413Y304592D02*
X1323413D01*
Y306176D01*
X1323663Y306682D01*
X1323996Y306999D01*
X1324663Y307126D01*
X1325330Y306999D01*
X1325746Y306619D01*
X1325996Y306176D01*
Y304592D01*
G01Y306176D02*
X1328413Y307126D01*
G01X1325913Y311339D02*
Y312606D01*
X1327413D01*
X1327913Y312226D01*
X1328246Y311782D01*
X1328413Y311149D01*
X1328246Y310516D01*
X1327913Y310072D01*
X1327413Y309692D01*
X1326830Y309439D01*
X1326163Y309312D01*
X1325580D01*
X1325080Y309439D01*
X1324496Y309692D01*
X1323996Y310072D01*
X1323663Y310452D01*
X1323413Y310959D01*
Y311402D01*
X1323580Y311909D01*
X1323913Y312289D01*
G01X1328413Y314666D02*
X1323413D01*
Y315932D01*
X1323663Y316439D01*
X1323996Y316819D01*
X1324496Y317136D01*
X1325080Y317389D01*
X1325913Y317452D01*
X1326746Y317389D01*
X1327330Y317136D01*
X1327830Y316819D01*
X1328163Y316439D01*
X1328413Y315932D01*
Y314666D01*
G01X1330080Y319259D02*
Y323059D01*
G01X1328413Y324992D02*
X1323413D01*
Y326512D01*
X1323663Y327019D01*
X1324246Y327399D01*
X1324913Y327526D01*
X1325580Y327399D01*
X1326080Y327082D01*
X1326330Y326512D01*
Y324992D01*
G01X1323413Y329776D02*
X1328413Y331359D01*
X1323413Y332942D01*
G01X1328413Y335066D02*
X1323413D01*
Y336332D01*
X1323663Y336839D01*
X1323996Y337219D01*
X1324496Y337536D01*
X1325080Y337789D01*
X1325913Y337852D01*
X1326746Y337789D01*
X1327330Y337536D01*
X1327830Y337219D01*
X1328163Y336839D01*
X1328413Y336332D01*
Y335066D01*
G01Y340166D02*
X1323413D01*
Y341432D01*
X1323663Y341939D01*
X1323996Y342319D01*
X1324496Y342636D01*
X1325080Y342889D01*
X1325913Y342952D01*
X1326746Y342889D01*
X1327330Y342636D01*
X1327830Y342319D01*
X1328163Y341939D01*
X1328413Y341432D01*
Y340166D01*
G01Y346659D02*
X1323413D01*
X1324413Y345899D01*
G01X1328413D02*
Y347419D01*
G01Y351759D02*
X1328330Y352202D01*
X1328080Y352709D01*
X1327663Y353026D01*
X1327080Y353152D01*
X1326496Y353026D01*
X1325996Y352646D01*
X1325746Y352076D01*
Y351442D01*
X1325580Y351062D01*
X1325163Y350746D01*
X1324580Y350619D01*
X1323996Y350809D01*
X1323580Y351252D01*
X1323413Y351759D01*
X1323580Y352266D01*
X1323996Y352709D01*
X1324580Y352899D01*
X1325163Y352772D01*
X1325580Y352456D01*
X1325746Y352076D01*
Y351442D01*
X1325996Y350872D01*
X1326496Y350492D01*
X1327080Y350366D01*
X1327663Y350492D01*
X1328080Y350809D01*
X1328330Y351316D01*
X1328413Y351759D01*
G01X1330080Y354959D02*
Y358759D01*
G01X1327746Y360629D02*
X1328163Y361136D01*
X1328413Y361706D01*
Y362212D01*
X1328163Y362719D01*
X1327746Y363099D01*
X1327163Y363289D01*
X1326580Y363162D01*
X1326080Y362846D01*
X1325746Y362276D01*
X1325580Y361516D01*
X1325246Y361072D01*
X1324663Y360882D01*
X1324080Y361009D01*
X1323663Y361326D01*
X1323413Y361769D01*
Y362212D01*
X1323580Y362656D01*
X1323996Y363036D01*
G01X1327663Y365666D02*
X1328080Y366046D01*
X1328330Y366489D01*
X1328413Y367059D01*
X1328246Y367629D01*
X1327913Y368072D01*
X1327330Y368389D01*
X1326663Y368452D01*
X1325996Y368326D01*
X1325580Y368009D01*
X1325246Y367566D01*
X1325163Y367122D01*
X1325246Y366679D01*
X1325580Y366109D01*
X1323413Y366299D01*
Y368009D01*
G01X1330080Y370259D02*
Y374059D01*
G01X1328413Y375992D02*
X1323413D01*
Y377512D01*
X1323663Y378019D01*
X1324246Y378399D01*
X1324913Y378526D01*
X1325580Y378399D01*
X1326080Y378082D01*
X1326330Y377512D01*
Y375992D01*
G01X1323413Y382359D02*
X1323580Y381852D01*
X1323996Y381472D01*
X1324496Y381219D01*
X1325163Y381029D01*
X1325913Y380966D01*
X1326663Y381029D01*
X1327330Y381219D01*
X1327830Y381472D01*
X1328246Y381852D01*
X1328413Y382359D01*
X1328246Y382866D01*
X1327830Y383246D01*
X1327330Y383499D01*
X1326663Y383689D01*
X1325913Y383752D01*
X1325163Y383689D01*
X1324496Y383499D01*
X1323996Y383246D01*
X1323580Y382866D01*
X1323413Y382359D01*
G01X1336013Y294392D02*
X1331013D01*
Y295912D01*
X1331263Y296419D01*
X1331846Y296799D01*
X1332513Y296926D01*
X1333180Y296799D01*
X1333680Y296482D01*
X1333930Y295912D01*
Y294392D01*
G01X1331013Y298859D02*
X1336013Y299746D01*
X1331013Y300759D01*
X1336013Y301772D01*
X1331013Y302659D01*
G01X1336013Y304592D02*
X1331013D01*
Y306176D01*
X1331263Y306682D01*
X1331596Y306999D01*
X1332263Y307126D01*
X1332930Y306999D01*
X1333346Y306619D01*
X1333596Y306176D01*
Y304592D01*
G01Y306176D02*
X1336013Y307126D01*
G01X1333513Y311339D02*
Y312606D01*
X1335013D01*
X1335513Y312226D01*
X1335846Y311782D01*
X1336013Y311149D01*
X1335846Y310516D01*
X1335513Y310072D01*
X1335013Y309692D01*
X1334430Y309439D01*
X1333763Y309312D01*
X1333180D01*
X1332680Y309439D01*
X1332096Y309692D01*
X1331596Y310072D01*
X1331263Y310452D01*
X1331013Y310959D01*
Y311402D01*
X1331180Y311909D01*
X1331513Y312289D01*
G01X1336013Y314666D02*
X1331013D01*
Y315932D01*
X1331263Y316439D01*
X1331596Y316819D01*
X1332096Y317136D01*
X1332680Y317389D01*
X1333513Y317452D01*
X1334346Y317389D01*
X1334930Y317136D01*
X1335430Y316819D01*
X1335763Y316439D01*
X1336013Y315932D01*
Y314666D01*
G01X1337680Y319259D02*
Y323059D01*
G01X1336013Y324992D02*
X1331013D01*
Y326512D01*
X1331263Y327019D01*
X1331846Y327399D01*
X1332513Y327526D01*
X1333180Y327399D01*
X1333680Y327082D01*
X1333930Y326512D01*
Y324992D01*
G01X1331013Y329776D02*
X1336013Y331359D01*
X1331013Y332942D01*
G01X1336013Y335066D02*
X1331013D01*
Y336332D01*
X1331263Y336839D01*
X1331596Y337219D01*
X1332096Y337536D01*
X1332680Y337789D01*
X1333513Y337852D01*
X1334346Y337789D01*
X1334930Y337536D01*
X1335430Y337219D01*
X1335763Y336839D01*
X1336013Y336332D01*
Y335066D01*
G01Y340166D02*
X1331013D01*
Y341432D01*
X1331263Y341939D01*
X1331596Y342319D01*
X1332096Y342636D01*
X1332680Y342889D01*
X1333513Y342952D01*
X1334346Y342889D01*
X1334930Y342636D01*
X1335430Y342319D01*
X1335763Y341939D01*
X1336013Y341432D01*
Y340166D01*
G01X1331430Y348052D02*
X1331180Y347672D01*
X1331013Y347229D01*
Y346722D01*
X1331263Y346152D01*
X1331680Y345709D01*
X1332180Y345392D01*
X1333013Y345139D01*
X1333763Y345076D01*
X1334513Y345202D01*
X1335013Y345392D01*
X1335513Y345772D01*
X1335846Y346216D01*
X1336013Y346659D01*
Y347102D01*
X1335846Y347546D01*
X1335596Y347926D01*
X1335263Y348242D01*
G01X1336013Y350492D02*
X1331013D01*
Y352076D01*
X1331263Y352582D01*
X1331596Y352899D01*
X1332263Y353026D01*
X1332930Y352899D01*
X1333346Y352519D01*
X1333596Y352076D01*
Y350492D01*
G01Y352076D02*
X1336013Y353026D01*
G01X1337680Y354959D02*
Y358759D01*
G01X1331430Y363352D02*
X1331180Y362972D01*
X1331013Y362529D01*
Y362022D01*
X1331263Y361452D01*
X1331680Y361009D01*
X1332180Y360692D01*
X1333013Y360439D01*
X1333763Y360376D01*
X1334513Y360502D01*
X1335013Y360692D01*
X1335513Y361072D01*
X1335846Y361516D01*
X1336013Y361959D01*
Y362402D01*
X1335846Y362846D01*
X1335596Y363226D01*
X1335263Y363542D01*
G01X1336013Y365792D02*
X1331013D01*
Y367312D01*
X1331263Y367819D01*
X1331846Y368199D01*
X1332513Y368326D01*
X1333180Y368199D01*
X1333680Y367882D01*
X1333930Y367312D01*
Y365792D01*
G01X1331013Y370766D02*
X1334596D01*
X1335346Y371019D01*
X1335846Y371526D01*
X1336013Y372159D01*
X1335846Y372792D01*
X1335346Y373299D01*
X1334596Y373552D01*
X1331013D01*
G01Y377259D02*
X1331180Y376752D01*
X1331596Y376372D01*
X1332096Y376119D01*
X1332763Y375929D01*
X1333513Y375866D01*
X1334263Y375929D01*
X1334930Y376119D01*
X1335430Y376372D01*
X1335846Y376752D01*
X1336013Y377259D01*
X1335846Y377766D01*
X1335430Y378146D01*
X1334930Y378399D01*
X1334263Y378589D01*
X1333513Y378652D01*
X1332763Y378589D01*
X1332096Y378399D01*
X1331596Y378146D01*
X1331180Y377766D01*
X1331013Y377259D01*
G01X1337680Y380459D02*
Y384259D01*
G01X1336013Y386192D02*
X1331013D01*
Y387712D01*
X1331263Y388219D01*
X1331846Y388599D01*
X1332513Y388726D01*
X1333180Y388599D01*
X1333680Y388282D01*
X1333930Y387712D01*
Y386192D01*
G01X1336013Y392559D02*
X1331013D01*
X1332013Y391799D01*
G01X1336013D02*
Y393319D01*
G01X1329514Y522675D02*
Y516675D01*
G01Y543375D02*
Y537375D01*
G01Y536475D02*
Y530475D01*
G01Y529575D02*
Y523575D01*
G01X1320923Y546538D02*
X1327025D01*
G01X1333960Y563295D02*
Y557095D01*
G01D02*
X1330760D01*
G01D02*
Y563295D01*
G01D02*
X1333960D01*
G01X1320941Y568748D02*
Y565548D01*
G01X1323406Y565396D02*
Y568496D01*
X1324326D01*
X1324633Y568341D01*
X1324863Y567979D01*
X1324940Y567566D01*
X1324863Y567153D01*
X1324671Y566843D01*
X1324326Y566688D01*
X1323406D01*
G01X1326430Y568496D02*
Y566274D01*
X1326583Y565809D01*
X1326890Y565499D01*
X1327273Y565396D01*
X1327656Y565499D01*
X1327963Y565809D01*
X1328116Y566274D01*
Y568496D01*
G01X1329530Y565861D02*
X1329760Y565603D01*
X1330028Y565448D01*
X1330373Y565396D01*
X1330718Y565499D01*
X1330986Y565706D01*
X1331178Y566068D01*
X1331216Y566481D01*
X1331140Y566894D01*
X1330948Y567153D01*
X1330680Y567359D01*
X1330411Y567411D01*
X1330143Y567359D01*
X1329798Y567153D01*
X1329913Y568496D01*
X1330948D01*
G01X1333396Y565396D02*
X1333473Y566068D01*
X1333588Y566636D01*
X1333741Y567153D01*
X1333933Y567721D01*
X1334240Y568496D01*
X1332706D01*
G01X1327025Y562409D02*
Y562680D01*
G01D02*
X1323223D01*
G01X1329565Y573153D02*
X1342244D01*
G01X1321327Y622673D02*
X1324327Y625673D01*
G01D02*
Y644327D01*
G01X1342244Y613353D02*
X1329565D01*
G01X1330422Y639976D02*
X1326427D01*
G01D02*
Y665566D01*
G01X1324500Y654883D02*
X1321400D01*
Y655803D01*
X1321555Y656110D01*
X1321917Y656340D01*
X1322330Y656417D01*
X1322743Y656340D01*
X1323053Y656148D01*
X1323208Y655803D01*
Y654883D01*
G01X1321400Y657983D02*
X1324500D01*
Y659517D01*
G01X1324035Y661007D02*
X1324293Y661237D01*
X1324448Y661505D01*
X1324500Y661850D01*
X1324397Y662195D01*
X1324190Y662463D01*
X1323828Y662655D01*
X1323415Y662693D01*
X1323002Y662617D01*
X1322743Y662425D01*
X1322537Y662157D01*
X1322485Y661888D01*
X1322537Y661620D01*
X1322743Y661275D01*
X1321400Y661390D01*
Y662425D01*
G01Y664950D02*
X1321503Y664643D01*
X1321762Y664413D01*
X1322072Y664260D01*
X1322485Y664145D01*
X1322950Y664107D01*
X1323415Y664145D01*
X1323828Y664260D01*
X1324138Y664413D01*
X1324397Y664643D01*
X1324500Y664950D01*
X1324397Y665257D01*
X1324138Y665487D01*
X1323828Y665640D01*
X1323415Y665755D01*
X1322950Y665793D01*
X1322485Y665755D01*
X1322072Y665640D01*
X1321762Y665487D01*
X1321503Y665257D01*
X1321400Y664950D01*
G01X1326427Y665566D02*
X1330422D01*
G01X1326384Y680470D02*
Y677370D01*
G01X1325502Y680470D02*
X1327266D01*
G01X1328717Y677370D02*
Y680470D01*
X1329637D01*
X1329944Y680315D01*
X1330174Y679953D01*
X1330251Y679540D01*
X1330174Y679127D01*
X1329982Y678817D01*
X1329637Y678662D01*
X1328717D01*
G01X1332507Y677370D02*
X1332584Y678042D01*
X1332699Y678610D01*
X1332852Y679127D01*
X1333044Y679695D01*
X1333351Y680470D01*
X1331817D01*
G01X1322315Y855827D02*
G03X1324283Y857796I-1J1969D01*
G01Y870788D02*
Y857796D01*
G01X1329992Y1167638D02*
Y1180630D01*
G01D02*
G03X1328023Y1182599I-1969J0D01*
G01X1329017Y1260458D02*
X1334358D01*
G01X1328973Y1306983D02*
X1328180D01*
G01X1328973Y1309583D02*
Y1306983D01*
G01X1334358Y1303766D02*
X1329017D01*
G01X1331839Y1322485D02*
X1335039D01*
G01X1331839Y1316285D02*
Y1322485D01*
G01X1335039Y1316285D02*
X1331839D01*
G01X1332546Y1334655D02*
Y1337855D01*
G01X1338746Y1334655D02*
X1332546D01*
G01Y1337855D02*
X1338746D01*
G01X1327761Y1340208D02*
Y1334008D01*
G01X1324561Y1340208D02*
X1327761D01*
G01X1324561Y1334008D02*
Y1340208D01*
G01X1327761Y1334008D02*
X1324561D01*
G01X1323719D02*
X1320519D01*
G01X1323719Y1340208D02*
Y1334008D01*
G01X1320519Y1340208D02*
X1323719D01*
G01X1320519Y1334008D02*
Y1340208D01*
G01X1328973Y1330605D02*
Y1328414D01*
G01X1328240Y1330605D02*
X1328973D01*
G01X1320445Y1362752D02*
Y1365852D01*
X1321365D01*
X1321672Y1365697D01*
X1321902Y1365335D01*
X1321979Y1364922D01*
X1321902Y1364509D01*
X1321710Y1364199D01*
X1321365Y1364044D01*
X1320445D01*
G01X1325155Y1365594D02*
X1324925Y1365749D01*
X1324657Y1365852D01*
X1324350D01*
X1324005Y1365697D01*
X1323737Y1365439D01*
X1323545Y1365129D01*
X1323392Y1364612D01*
X1323354Y1364147D01*
X1323430Y1363682D01*
X1323545Y1363372D01*
X1323775Y1363062D01*
X1324044Y1362855D01*
X1324312Y1362752D01*
X1324580D01*
X1324849Y1362855D01*
X1325079Y1363010D01*
X1325270Y1363217D01*
G01X1327412Y1362752D02*
Y1365852D01*
X1326952Y1365232D01*
G01Y1362752D02*
X1327872D01*
G01X1330512Y1365852D02*
X1330205Y1365749D01*
X1329975Y1365490D01*
X1329822Y1365180D01*
X1329707Y1364767D01*
X1329669Y1364302D01*
X1329707Y1363837D01*
X1329822Y1363424D01*
X1329975Y1363114D01*
X1330205Y1362855D01*
X1330512Y1362752D01*
X1330819Y1362855D01*
X1331049Y1363114D01*
X1331202Y1363424D01*
X1331317Y1363837D01*
X1331355Y1364302D01*
X1331317Y1364767D01*
X1331202Y1365180D01*
X1331049Y1365490D01*
X1330819Y1365749D01*
X1330512Y1365852D01*
G01X1334072Y1362752D02*
Y1365852D01*
X1332654Y1363630D01*
X1334570D01*
G01X1333262Y1389777D02*
X1339373D01*
G01X1333262Y1413793D02*
Y1389777D01*
G01X1323038Y1409882D02*
Y1406682D01*
G01X1339373Y1413793D02*
X1333262D01*
G01X1328356Y1441599D02*
X1320856Y1443932D01*
X1328356Y1446265D01*
G01X1325731Y1445425D02*
Y1442439D01*
G01X1326856Y1449379D02*
X1327731Y1449939D01*
X1328231Y1450685D01*
X1328356Y1451525D01*
X1328231Y1452272D01*
X1327606Y1453019D01*
X1326856Y1453485D01*
X1326106Y1453579D01*
X1325231Y1453392D01*
X1324606Y1452739D01*
X1324356Y1452085D01*
Y1451245D01*
G01Y1452085D02*
X1323981Y1452645D01*
X1323356Y1453112D01*
X1322606Y1453299D01*
X1321856Y1453112D01*
X1321231Y1452645D01*
X1320856Y1451805D01*
X1320981Y1450965D01*
X1321481Y1450125D01*
G01X1347313Y1437636D02*
X1332313D01*
G01D02*
Y1457636D01*
G01D02*
Y1437636D01*
G01Y1457636D02*
X1347313D01*
G01X1326597Y1589308D02*
Y1587086D01*
X1326750Y1586621D01*
X1327057Y1586311D01*
X1327440Y1586208D01*
X1327823Y1586311D01*
X1328130Y1586621D01*
X1328283Y1587086D01*
Y1589308D01*
G01X1329812Y1587500D02*
X1330080Y1587861D01*
X1330310Y1588068D01*
X1330617Y1588171D01*
X1330885Y1588068D01*
X1331077Y1587861D01*
X1331230Y1587551D01*
X1331268Y1587190D01*
X1331230Y1586880D01*
X1331077Y1586570D01*
X1330847Y1586311D01*
X1330578Y1586208D01*
X1330272Y1586311D01*
X1330003Y1586621D01*
X1329850Y1587086D01*
X1329812Y1587603D01*
X1329888Y1588275D01*
X1330003Y1588636D01*
X1330195Y1588998D01*
X1330463Y1589256D01*
X1330732Y1589308D01*
X1331000Y1589205D01*
X1331192Y1588946D01*
G01X1333640Y1589308D02*
X1333333Y1589205D01*
X1333103Y1588946D01*
X1332950Y1588636D01*
X1332835Y1588223D01*
X1332797Y1587758D01*
X1332835Y1587293D01*
X1332950Y1586880D01*
X1333103Y1586570D01*
X1333333Y1586311D01*
X1333640Y1586208D01*
X1333947Y1586311D01*
X1334177Y1586570D01*
X1334330Y1586880D01*
X1334445Y1587293D01*
X1334483Y1587758D01*
X1334445Y1588223D01*
X1334330Y1588636D01*
X1334177Y1588946D01*
X1333947Y1589205D01*
X1333640Y1589308D01*
G01X1336740Y1586208D02*
Y1589308D01*
X1336280Y1588688D01*
G01Y1586208D02*
X1337200D01*
G01X1339840D02*
Y1589308D01*
X1339380Y1588688D01*
G01Y1586208D02*
X1340300D01*
G01X1327331Y1655716D02*
X1324231D01*
X1326453Y1654298D01*
Y1656214D01*
G01X1322669Y1655169D02*
X1323031Y1655399D01*
X1323237Y1655705D01*
X1323289Y1656050D01*
X1323237Y1656357D01*
X1322979Y1656664D01*
X1322669Y1656855D01*
X1322359Y1656894D01*
X1321997Y1656817D01*
X1321739Y1656549D01*
X1321636Y1656280D01*
Y1655935D01*
G01Y1656280D02*
X1321481Y1656510D01*
X1321222Y1656702D01*
X1320912Y1656779D01*
X1320602Y1656702D01*
X1320344Y1656510D01*
X1320189Y1656165D01*
X1320241Y1655820D01*
X1320447Y1655475D01*
G01X1327800Y1646023D02*
X1321100D01*
G01X1339800D02*
X1333100D01*
G01X1321500Y1657834D02*
X1327100D01*
G01X1342240Y59811D02*
Y66011D01*
G01X1345440D02*
Y59811D01*
G01D02*
X1342240D01*
G01X1347651Y55150D02*
Y57390D01*
G01X1346026Y56177D02*
X1349276D01*
G01X1344853Y48421D02*
X1341753D01*
Y49187D01*
X1341908Y49494D01*
X1342115Y49724D01*
X1342425Y49916D01*
X1342786Y50069D01*
X1343303Y50107D01*
X1343820Y50069D01*
X1344181Y49916D01*
X1344491Y49724D01*
X1344698Y49494D01*
X1344853Y49187D01*
Y48421D01*
G01X1343561Y51636D02*
X1343200Y51904D01*
X1342993Y52134D01*
X1342890Y52441D01*
X1342993Y52709D01*
X1343200Y52901D01*
X1343510Y53054D01*
X1343871Y53092D01*
X1344181Y53054D01*
X1344491Y52901D01*
X1344750Y52671D01*
X1344853Y52402D01*
X1344750Y52096D01*
X1344440Y51827D01*
X1343975Y51674D01*
X1343458Y51636D01*
X1342786Y51712D01*
X1342425Y51827D01*
X1342063Y52019D01*
X1341805Y52287D01*
X1341753Y52556D01*
X1341856Y52824D01*
X1342115Y53016D01*
G01X1347150Y58494D02*
Y68894D01*
G01X1351550Y58494D02*
X1347150D01*
G01X1338523Y51301D02*
X1335423D01*
Y52067D01*
X1335578Y52374D01*
X1335785Y52604D01*
X1336095Y52796D01*
X1336456Y52949D01*
X1336973Y52987D01*
X1337490Y52949D01*
X1337851Y52796D01*
X1338161Y52604D01*
X1338368Y52374D01*
X1338523Y52067D01*
Y51301D01*
G01X1338058Y54401D02*
X1338316Y54631D01*
X1338471Y54899D01*
X1338523Y55244D01*
X1338420Y55589D01*
X1338213Y55857D01*
X1337851Y56049D01*
X1337438Y56087D01*
X1337025Y56011D01*
X1336766Y55819D01*
X1336560Y55551D01*
X1336508Y55282D01*
X1336560Y55014D01*
X1336766Y54669D01*
X1335423Y54784D01*
Y55819D01*
G01X1335540Y59174D02*
Y66264D01*
G01X1339340D02*
Y59124D01*
G01D02*
X1335590D01*
G01X1335540Y59574D02*
Y66764D01*
G01X1339340D02*
Y59574D01*
G01X1335540Y60174D02*
Y67264D01*
G01X1339340D02*
Y60174D01*
G01X1335006Y71128D02*
Y68300D01*
G01X1342240Y66011D02*
X1345440D01*
G01X1349350Y71781D02*
Y74207D01*
G01X1347150Y68894D02*
X1351550D01*
G01X1347150Y69494D02*
X1351550D01*
G01Y70094D02*
X1347150D01*
G01Y70694D02*
X1351550D01*
G01X1347150D02*
Y68894D01*
G01X1346730Y77209D02*
Y73862D01*
G01D02*
X1338068D01*
G01D02*
Y84356D01*
G01X1335540Y66264D02*
X1339340D01*
G01X1335540Y66764D02*
X1339340D01*
G01X1335540Y67264D02*
X1339340D01*
G01X1346730Y84356D02*
Y81009D01*
G01D02*
X1344530Y79109D01*
G01D02*
X1346730Y77209D01*
G01X1338068Y84356D02*
X1346730D01*
G01X1335437Y103334D02*
X1335312Y103441D01*
X1335103Y103521D01*
X1334812Y103574D01*
X1334562Y103521D01*
X1334395Y103414D01*
X1334270Y103228D01*
Y102508D01*
X1336770D01*
Y103388D01*
X1336603Y103574D01*
X1336353Y103681D01*
X1336062Y103734D01*
X1335770Y103681D01*
X1335520Y103521D01*
X1335437Y103334D01*
Y102508D01*
G01X1336770Y105321D02*
X1336728Y105108D01*
X1336562Y104921D01*
X1336312Y104761D01*
X1336020Y104654D01*
X1335687Y104601D01*
X1335353D01*
X1335020Y104654D01*
X1334728Y104761D01*
X1334478Y104921D01*
X1334312Y105108D01*
X1334270Y105321D01*
X1334312Y105534D01*
X1334478Y105721D01*
X1334728Y105881D01*
X1335020Y105988D01*
X1335353Y106041D01*
X1335687D01*
X1336020Y105988D01*
X1336312Y105881D01*
X1336562Y105721D01*
X1336728Y105534D01*
X1336770Y105321D01*
G01Y107521D02*
X1336728Y107308D01*
X1336562Y107121D01*
X1336312Y106961D01*
X1336020Y106854D01*
X1335687Y106801D01*
X1335353D01*
X1335020Y106854D01*
X1334728Y106961D01*
X1334478Y107121D01*
X1334312Y107308D01*
X1334270Y107521D01*
X1334312Y107734D01*
X1334478Y107921D01*
X1334728Y108081D01*
X1335020Y108188D01*
X1335353Y108241D01*
X1335687D01*
X1336020Y108188D01*
X1336312Y108081D01*
X1336562Y107921D01*
X1336728Y107734D01*
X1336770Y107521D01*
G01X1334270Y109721D02*
X1336770D01*
G01X1334270Y109108D02*
Y110334D01*
G01X1336770Y113588D02*
X1334270D01*
Y114254D01*
X1334395Y114468D01*
X1334562Y114601D01*
X1334895Y114654D01*
X1335228Y114601D01*
X1335437Y114441D01*
X1335562Y114254D01*
Y113588D01*
G01Y114254D02*
X1336770Y114654D01*
G01Y116854D02*
Y115788D01*
X1334270D01*
Y116854D01*
G01X1335478Y116428D02*
Y115788D01*
G01X1336770Y117854D02*
X1334270Y118521D01*
X1336770Y119188D01*
G01X1335895Y118948D02*
Y118094D01*
G01X1336770Y120134D02*
X1334270D01*
Y120668D01*
X1334395Y120881D01*
X1334562Y121041D01*
X1334812Y121174D01*
X1335103Y121281D01*
X1335520Y121308D01*
X1335937Y121281D01*
X1336228Y121174D01*
X1336478Y121041D01*
X1336645Y120881D01*
X1336770Y120668D01*
Y120134D01*
G01Y122921D02*
X1335645D01*
X1334270Y122388D01*
G01Y123454D02*
X1335645Y122921D01*
G01X1338999Y97184D02*
Y90984D01*
G01D02*
X1335799D01*
G01D02*
Y97184D01*
G01D02*
X1338999D01*
G01X1334999D02*
Y90984D01*
G01X1342999Y97184D02*
Y90984D01*
G01D02*
X1339799D01*
G01D02*
Y97184D01*
G01D02*
X1342999D01*
G01X1349799Y90984D02*
X1346599D01*
G01D02*
Y97184D01*
G01D02*
X1349799D01*
G01X1346004Y159410D02*
X1396516D01*
G01X1346004Y179016D02*
Y159410D01*
G01X1396516Y179016D02*
X1346004D01*
G01X1356299Y233307D02*
X1342913D01*
G01D02*
Y234544D01*
G01Y238644D02*
Y239544D01*
G01Y243644D02*
Y244544D01*
G01Y248644D02*
Y249544D01*
G01Y253644D02*
Y254881D01*
G01D02*
X1356299D01*
G01X1340766Y260794D02*
X1337666D01*
Y261560D01*
X1337821Y261867D01*
X1338028Y262097D01*
X1338338Y262289D01*
X1338699Y262442D01*
X1339216Y262480D01*
X1339733Y262442D01*
X1340094Y262289D01*
X1340404Y262097D01*
X1340611Y261867D01*
X1340766Y261560D01*
Y260794D01*
G01Y264737D02*
X1340714Y265005D01*
X1340559Y265312D01*
X1340301Y265504D01*
X1339939Y265580D01*
X1339578Y265504D01*
X1339268Y265274D01*
X1339113Y264929D01*
Y264545D01*
X1339009Y264315D01*
X1338751Y264124D01*
X1338389Y264047D01*
X1338028Y264162D01*
X1337769Y264430D01*
X1337666Y264737D01*
X1337769Y265044D01*
X1338028Y265312D01*
X1338389Y265427D01*
X1338751Y265350D01*
X1339009Y265159D01*
X1339113Y264929D01*
Y264545D01*
X1339268Y264200D01*
X1339578Y263970D01*
X1339939Y263894D01*
X1340301Y263970D01*
X1340559Y264162D01*
X1340714Y264469D01*
X1340766Y264737D01*
G01X1338183Y267109D02*
X1337873Y267339D01*
X1337718Y267607D01*
X1337666Y267914D01*
X1337769Y268297D01*
X1338028Y268565D01*
X1338338Y268642D01*
X1338648Y268604D01*
X1338906Y268450D01*
X1339423Y267684D01*
X1339784Y267339D01*
X1340301Y267109D01*
X1340766Y267032D01*
Y268642D01*
G01X1348766Y260794D02*
X1345666D01*
Y261560D01*
X1345821Y261867D01*
X1346028Y262097D01*
X1346338Y262289D01*
X1346699Y262442D01*
X1347216Y262480D01*
X1347733Y262442D01*
X1348094Y262289D01*
X1348404Y262097D01*
X1348611Y261867D01*
X1348766Y261560D01*
Y260794D01*
G01Y264737D02*
X1348714Y265005D01*
X1348559Y265312D01*
X1348301Y265504D01*
X1347939Y265580D01*
X1347578Y265504D01*
X1347268Y265274D01*
X1347113Y264929D01*
Y264545D01*
X1347009Y264315D01*
X1346751Y264124D01*
X1346389Y264047D01*
X1346028Y264162D01*
X1345769Y264430D01*
X1345666Y264737D01*
X1345769Y265044D01*
X1346028Y265312D01*
X1346389Y265427D01*
X1346751Y265350D01*
X1347009Y265159D01*
X1347113Y264929D01*
Y264545D01*
X1347268Y264200D01*
X1347578Y263970D01*
X1347939Y263894D01*
X1348301Y263970D01*
X1348559Y264162D01*
X1348714Y264469D01*
X1348766Y264737D01*
G01X1348146Y266994D02*
X1348508Y267224D01*
X1348714Y267530D01*
X1348766Y267875D01*
X1348714Y268182D01*
X1348456Y268489D01*
X1348146Y268680D01*
X1347836Y268719D01*
X1347474Y268642D01*
X1347216Y268374D01*
X1347113Y268105D01*
Y267760D01*
G01Y268105D02*
X1346958Y268335D01*
X1346699Y268527D01*
X1346389Y268604D01*
X1346079Y268527D01*
X1345821Y268335D01*
X1345666Y267990D01*
X1345718Y267645D01*
X1345924Y267300D01*
G01X1340194Y273458D02*
Y280548D01*
G01D02*
X1343994D01*
G01D02*
Y273458D01*
G01X1340194Y272858D02*
Y280048D01*
G01D02*
X1343994D01*
G01D02*
Y272858D01*
G01X1340194Y272458D02*
Y279548D01*
G01D02*
X1343994D01*
G01D02*
Y272408D01*
G01D02*
X1340244D01*
G01X1348194Y273458D02*
Y280548D01*
G01D02*
X1351994D01*
G01X1348194Y272858D02*
Y280048D01*
G01D02*
X1351994D01*
G01X1348194Y272458D02*
Y279548D01*
G01D02*
X1351994D01*
G01Y272408D02*
X1348244D01*
G01X1335994Y280548D02*
Y273458D01*
G01Y280048D02*
Y272858D01*
G01Y279548D02*
Y272408D01*
G01X1344613Y294392D02*
X1339613D01*
Y295912D01*
X1339863Y296419D01*
X1340446Y296799D01*
X1341113Y296926D01*
X1341780Y296799D01*
X1342280Y296482D01*
X1342530Y295912D01*
Y294392D01*
G01X1339613Y298859D02*
X1344613Y299746D01*
X1339613Y300759D01*
X1344613Y301772D01*
X1339613Y302659D01*
G01X1344613Y304592D02*
X1339613D01*
Y306176D01*
X1339863Y306682D01*
X1340196Y306999D01*
X1340863Y307126D01*
X1341530Y306999D01*
X1341946Y306619D01*
X1342196Y306176D01*
Y304592D01*
G01Y306176D02*
X1344613Y307126D01*
G01X1342113Y311339D02*
Y312606D01*
X1343613D01*
X1344113Y312226D01*
X1344446Y311782D01*
X1344613Y311149D01*
X1344446Y310516D01*
X1344113Y310072D01*
X1343613Y309692D01*
X1343030Y309439D01*
X1342363Y309312D01*
X1341780D01*
X1341280Y309439D01*
X1340696Y309692D01*
X1340196Y310072D01*
X1339863Y310452D01*
X1339613Y310959D01*
Y311402D01*
X1339780Y311909D01*
X1340113Y312289D01*
G01X1344613Y314666D02*
X1339613D01*
Y315932D01*
X1339863Y316439D01*
X1340196Y316819D01*
X1340696Y317136D01*
X1341280Y317389D01*
X1342113Y317452D01*
X1342946Y317389D01*
X1343530Y317136D01*
X1344030Y316819D01*
X1344363Y316439D01*
X1344613Y315932D01*
Y314666D01*
G01X1346280Y319259D02*
Y323059D01*
G01X1344613Y324992D02*
X1339613D01*
Y326512D01*
X1339863Y327019D01*
X1340446Y327399D01*
X1341113Y327526D01*
X1341780Y327399D01*
X1342280Y327082D01*
X1342530Y326512D01*
Y324992D01*
G01X1339613Y329776D02*
X1344613Y331359D01*
X1339613Y332942D01*
G01X1344613Y335066D02*
X1339613D01*
Y336332D01*
X1339863Y336839D01*
X1340196Y337219D01*
X1340696Y337536D01*
X1341280Y337789D01*
X1342113Y337852D01*
X1342946Y337789D01*
X1343530Y337536D01*
X1344030Y337219D01*
X1344363Y336839D01*
X1344613Y336332D01*
Y335066D01*
G01Y340166D02*
X1339613D01*
Y341432D01*
X1339863Y341939D01*
X1340196Y342319D01*
X1340696Y342636D01*
X1341280Y342889D01*
X1342113Y342952D01*
X1342946Y342889D01*
X1343530Y342636D01*
X1344030Y342319D01*
X1344363Y341939D01*
X1344613Y341432D01*
Y340166D01*
G01X1340030Y348052D02*
X1339780Y347672D01*
X1339613Y347229D01*
Y346722D01*
X1339863Y346152D01*
X1340280Y345709D01*
X1340780Y345392D01*
X1341613Y345139D01*
X1342363Y345076D01*
X1343113Y345202D01*
X1343613Y345392D01*
X1344113Y345772D01*
X1344446Y346216D01*
X1344613Y346659D01*
Y347102D01*
X1344446Y347546D01*
X1344196Y347926D01*
X1343863Y348242D01*
G01X1344613Y350492D02*
X1339613D01*
Y352076D01*
X1339863Y352582D01*
X1340196Y352899D01*
X1340863Y353026D01*
X1341530Y352899D01*
X1341946Y352519D01*
X1342196Y352076D01*
Y350492D01*
G01Y352076D02*
X1344613Y353026D01*
G01X1346280Y354959D02*
Y358759D01*
G01X1343946Y360629D02*
X1344363Y361136D01*
X1344613Y361706D01*
Y362212D01*
X1344363Y362719D01*
X1343946Y363099D01*
X1343363Y363289D01*
X1342780Y363162D01*
X1342280Y362846D01*
X1341946Y362276D01*
X1341780Y361516D01*
X1341446Y361072D01*
X1340863Y360882D01*
X1340280Y361009D01*
X1339863Y361326D01*
X1339613Y361769D01*
Y362212D01*
X1339780Y362656D01*
X1340196Y363036D01*
G01X1344613Y367059D02*
X1344530Y366552D01*
X1344196Y366109D01*
X1343696Y365729D01*
X1343113Y365476D01*
X1342446Y365349D01*
X1341780D01*
X1341113Y365476D01*
X1340530Y365729D01*
X1340030Y366109D01*
X1339696Y366552D01*
X1339613Y367059D01*
X1339696Y367566D01*
X1340030Y368009D01*
X1340530Y368389D01*
X1341113Y368642D01*
X1341780Y368769D01*
X1342446D01*
X1343113Y368642D01*
X1343696Y368389D01*
X1344196Y368009D01*
X1344530Y367566D01*
X1344613Y367059D01*
G01X1340030Y373552D02*
X1339780Y373172D01*
X1339613Y372729D01*
Y372222D01*
X1339863Y371652D01*
X1340280Y371209D01*
X1340780Y370892D01*
X1341613Y370639D01*
X1342363Y370576D01*
X1343113Y370702D01*
X1343613Y370892D01*
X1344113Y371272D01*
X1344446Y371716D01*
X1344613Y372159D01*
Y372602D01*
X1344446Y373046D01*
X1344196Y373426D01*
X1343863Y373742D01*
G01X1346280Y375359D02*
Y379159D01*
G01X1344613Y381092D02*
X1339613D01*
Y382612D01*
X1339863Y383119D01*
X1340446Y383499D01*
X1341113Y383626D01*
X1341780Y383499D01*
X1342280Y383182D01*
X1342530Y382612D01*
Y381092D01*
G01X1344613Y387459D02*
X1339613D01*
X1340613Y386699D01*
G01X1344613D02*
Y388219D01*
G01X1352213Y294392D02*
X1347213D01*
Y295912D01*
X1347463Y296419D01*
X1348046Y296799D01*
X1348713Y296926D01*
X1349380Y296799D01*
X1349880Y296482D01*
X1350130Y295912D01*
Y294392D01*
G01X1347213Y298859D02*
X1352213Y299746D01*
X1347213Y300759D01*
X1352213Y301772D01*
X1347213Y302659D01*
G01X1352213Y304592D02*
X1347213D01*
Y306176D01*
X1347463Y306682D01*
X1347796Y306999D01*
X1348463Y307126D01*
X1349130Y306999D01*
X1349546Y306619D01*
X1349796Y306176D01*
Y304592D01*
G01Y306176D02*
X1352213Y307126D01*
G01X1349713Y311339D02*
Y312606D01*
X1351213D01*
X1351713Y312226D01*
X1352046Y311782D01*
X1352213Y311149D01*
X1352046Y310516D01*
X1351713Y310072D01*
X1351213Y309692D01*
X1350630Y309439D01*
X1349963Y309312D01*
X1349380D01*
X1348880Y309439D01*
X1348296Y309692D01*
X1347796Y310072D01*
X1347463Y310452D01*
X1347213Y310959D01*
Y311402D01*
X1347380Y311909D01*
X1347713Y312289D01*
G01X1352213Y314666D02*
X1347213D01*
Y315932D01*
X1347463Y316439D01*
X1347796Y316819D01*
X1348296Y317136D01*
X1348880Y317389D01*
X1349713Y317452D01*
X1350546Y317389D01*
X1351130Y317136D01*
X1351630Y316819D01*
X1351963Y316439D01*
X1352213Y315932D01*
Y314666D01*
G01X1353880Y319259D02*
Y323059D01*
G01X1352213Y324992D02*
X1347213D01*
Y326512D01*
X1347463Y327019D01*
X1348046Y327399D01*
X1348713Y327526D01*
X1349380Y327399D01*
X1349880Y327082D01*
X1350130Y326512D01*
Y324992D01*
G01X1347213Y329776D02*
X1352213Y331359D01*
X1347213Y332942D01*
G01X1352213Y335066D02*
X1347213D01*
Y336332D01*
X1347463Y336839D01*
X1347796Y337219D01*
X1348296Y337536D01*
X1348880Y337789D01*
X1349713Y337852D01*
X1350546Y337789D01*
X1351130Y337536D01*
X1351630Y337219D01*
X1351963Y336839D01*
X1352213Y336332D01*
Y335066D01*
G01Y340166D02*
X1347213D01*
Y341432D01*
X1347463Y341939D01*
X1347796Y342319D01*
X1348296Y342636D01*
X1348880Y342889D01*
X1349713Y342952D01*
X1350546Y342889D01*
X1351130Y342636D01*
X1351630Y342319D01*
X1351963Y341939D01*
X1352213Y341432D01*
Y340166D01*
G01X1347630Y348052D02*
X1347380Y347672D01*
X1347213Y347229D01*
Y346722D01*
X1347463Y346152D01*
X1347880Y345709D01*
X1348380Y345392D01*
X1349213Y345139D01*
X1349963Y345076D01*
X1350713Y345202D01*
X1351213Y345392D01*
X1351713Y345772D01*
X1352046Y346216D01*
X1352213Y346659D01*
Y347102D01*
X1352046Y347546D01*
X1351796Y347926D01*
X1351463Y348242D01*
G01X1352213Y350492D02*
X1347213D01*
Y352076D01*
X1347463Y352582D01*
X1347796Y352899D01*
X1348463Y353026D01*
X1349130Y352899D01*
X1349546Y352519D01*
X1349796Y352076D01*
Y350492D01*
G01Y352076D02*
X1352213Y353026D01*
G01X1353880Y354959D02*
Y358759D01*
G01X1347630Y363352D02*
X1347380Y362972D01*
X1347213Y362529D01*
Y362022D01*
X1347463Y361452D01*
X1347880Y361009D01*
X1348380Y360692D01*
X1349213Y360439D01*
X1349963Y360376D01*
X1350713Y360502D01*
X1351213Y360692D01*
X1351713Y361072D01*
X1352046Y361516D01*
X1352213Y361959D01*
Y362402D01*
X1352046Y362846D01*
X1351796Y363226D01*
X1351463Y363542D01*
G01X1352213Y365792D02*
X1347213D01*
Y367312D01*
X1347463Y367819D01*
X1348046Y368199D01*
X1348713Y368326D01*
X1349380Y368199D01*
X1349880Y367882D01*
X1350130Y367312D01*
Y365792D01*
G01X1347213Y370766D02*
X1350796D01*
X1351546Y371019D01*
X1352046Y371526D01*
X1352213Y372159D01*
X1352046Y372792D01*
X1351546Y373299D01*
X1350796Y373552D01*
X1347213D01*
G01X1352213Y377259D02*
X1347213D01*
X1348213Y376499D01*
G01X1352213D02*
Y378019D01*
G01X1353880Y380459D02*
Y384259D01*
G01X1352213Y386192D02*
X1347213D01*
Y387712D01*
X1347463Y388219D01*
X1348046Y388599D01*
X1348713Y388726D01*
X1349380Y388599D01*
X1349880Y388282D01*
X1350130Y387712D01*
Y386192D01*
G01X1352213Y392559D02*
X1347213D01*
X1348213Y391799D01*
G01X1352213D02*
Y393319D01*
G01X1342244Y573153D02*
Y613353D01*
G01X1345396Y627033D02*
Y630133D01*
X1346316D01*
X1346623Y629978D01*
X1346853Y629616D01*
X1346930Y629203D01*
X1346853Y628790D01*
X1346661Y628480D01*
X1346316Y628325D01*
X1345396D01*
G01X1348420Y630133D02*
Y627911D01*
X1348573Y627446D01*
X1348880Y627136D01*
X1349263Y627033D01*
X1349646Y627136D01*
X1349953Y627446D01*
X1350106Y627911D01*
Y630133D01*
G01X1352363Y627033D02*
Y630133D01*
X1351903Y629513D01*
G01Y627033D02*
X1352823D01*
G01X1355463Y630133D02*
X1355156Y630030D01*
X1354926Y629771D01*
X1354773Y629461D01*
X1354658Y629048D01*
X1354620Y628583D01*
X1354658Y628118D01*
X1354773Y627705D01*
X1354926Y627395D01*
X1355156Y627136D01*
X1355463Y627033D01*
X1355770Y627136D01*
X1356000Y627395D01*
X1356153Y627705D01*
X1356268Y628118D01*
X1356306Y628583D01*
X1356268Y629048D01*
X1356153Y629461D01*
X1356000Y629771D01*
X1355770Y630030D01*
X1355463Y630133D01*
G01X1348661Y630981D02*
Y637181D01*
G01D02*
X1351861D01*
G01Y630981D02*
X1348661D01*
G01X1352017Y639976D02*
X1348022D01*
G01Y665566D02*
X1352017D01*
G01X1347896Y676793D02*
X1341696D01*
G01D02*
Y679993D01*
G01D02*
X1347896D01*
G01D02*
Y676793D01*
G01X1341660Y676043D02*
X1347860D01*
G01D02*
Y672843D01*
G01D02*
X1341660D01*
G01D02*
Y676043D01*
G01X1561400Y860721D02*
X1345300D01*
G01X1344100Y1177705D02*
X1375800D01*
G01X1337326Y1260515D02*
Y1303823D01*
G01X1342667Y1260515D02*
X1337326D01*
G01X1334358Y1260458D02*
Y1303766D01*
G01X1340487Y1308766D02*
Y1305566D01*
G01X1334287Y1308766D02*
X1340487D01*
G01X1334287Y1305566D02*
Y1308766D01*
G01X1340487Y1305566D02*
X1334287D01*
G01X1339053Y1309066D02*
X1335853D01*
G01X1339053Y1315266D02*
Y1309066D01*
G01X1335853D02*
Y1315266D01*
G01X1342087Y1307183D02*
Y1309783D01*
G01X1342880Y1307183D02*
X1342087D01*
G01X1337326Y1303823D02*
X1342667D01*
G01X1335039Y1322485D02*
Y1316285D01*
G01X1339030Y1326387D02*
X1335830D01*
G01D02*
Y1332587D01*
G01X1339030Y1328800D02*
Y1326387D01*
G01X1335830Y1322087D02*
X1339030D01*
G01X1335830Y1315887D02*
Y1322087D01*
G01X1339030Y1315887D02*
X1335830D01*
G01X1339030Y1322087D02*
Y1315887D01*
G01X1335853Y1315266D02*
X1339053D01*
G01X1342087Y1316394D02*
Y1318092D01*
G01X1339030Y1332587D02*
Y1331200D01*
G01X1335830Y1332587D02*
X1339030D01*
G01X1342924Y1341218D02*
Y1335018D01*
G01D02*
X1339724D01*
G01Y1341218D02*
X1342924D01*
G01X1339724Y1335018D02*
Y1341218D01*
G01X1338746Y1337855D02*
Y1334655D01*
G01X1343694Y1337912D02*
Y1341112D01*
G01X1349894Y1337912D02*
X1343694D01*
G01Y1341112D02*
X1349894D01*
G01X1342087Y1330805D02*
X1343095D01*
G01X1342087Y1328951D02*
Y1330805D01*
G01X1340209Y1343823D02*
Y1346923D01*
X1341129D01*
X1341436Y1346768D01*
X1341666Y1346406D01*
X1341743Y1345993D01*
X1341666Y1345580D01*
X1341474Y1345270D01*
X1341129Y1345115D01*
X1340209D01*
G01X1343309Y1346923D02*
Y1343823D01*
X1344843D01*
G01X1347176D02*
Y1346923D01*
X1346716Y1346303D01*
G01Y1343823D02*
X1347636D01*
G01X1349433Y1344288D02*
X1349663Y1344030D01*
X1349931Y1343875D01*
X1350276Y1343823D01*
X1350621Y1343926D01*
X1350889Y1344133D01*
X1351081Y1344495D01*
X1351119Y1344908D01*
X1351043Y1345321D01*
X1350851Y1345580D01*
X1350583Y1345786D01*
X1350314Y1345838D01*
X1350046Y1345786D01*
X1349701Y1345580D01*
X1349816Y1346923D01*
X1350851D01*
G01X1340383Y1348500D02*
Y1351600D01*
X1341303D01*
X1341610Y1351445D01*
X1341840Y1351083D01*
X1341917Y1350670D01*
X1341840Y1350257D01*
X1341648Y1349947D01*
X1341303Y1349792D01*
X1340383D01*
G01X1343407Y1351600D02*
Y1349378D01*
X1343560Y1348913D01*
X1343867Y1348603D01*
X1344250Y1348500D01*
X1344633Y1348603D01*
X1344940Y1348913D01*
X1345093Y1349378D01*
Y1351600D01*
G01X1347350Y1348500D02*
Y1351600D01*
X1346890Y1350980D01*
G01Y1348500D02*
X1347810D01*
G01X1349722Y1349792D02*
X1349990Y1350153D01*
X1350220Y1350360D01*
X1350527Y1350463D01*
X1350795Y1350360D01*
X1350987Y1350153D01*
X1351140Y1349843D01*
X1351178Y1349482D01*
X1351140Y1349172D01*
X1350987Y1348862D01*
X1350757Y1348603D01*
X1350488Y1348500D01*
X1350182Y1348603D01*
X1349913Y1348913D01*
X1349760Y1349378D01*
X1349722Y1349895D01*
X1349798Y1350567D01*
X1349913Y1350928D01*
X1350105Y1351290D01*
X1350373Y1351548D01*
X1350642Y1351600D01*
X1350910Y1351497D01*
X1351102Y1351238D01*
G01X1343356Y1441599D02*
X1335856Y1443932D01*
X1343356Y1446265D01*
G01X1340731Y1445425D02*
Y1442439D01*
G01X1337106Y1449659D02*
X1336356Y1450219D01*
X1335981Y1450872D01*
X1335856Y1451619D01*
X1336106Y1452552D01*
X1336731Y1453205D01*
X1337481Y1453392D01*
X1338231Y1453299D01*
X1338856Y1452925D01*
X1340106Y1451059D01*
X1340981Y1450219D01*
X1342231Y1449659D01*
X1343356Y1449472D01*
Y1453392D01*
G01X1362313Y1437636D02*
X1347313D01*
G01D02*
Y1457636D01*
G01D02*
Y1437636D01*
G01Y1457636D02*
X1362313D01*
G01X1346814Y1654764D02*
X1346453Y1655032D01*
X1346246Y1655262D01*
X1346143Y1655569D01*
X1346246Y1655837D01*
X1346453Y1656029D01*
X1346763Y1656182D01*
X1347124Y1656220D01*
X1347434Y1656182D01*
X1347744Y1656029D01*
X1348003Y1655799D01*
X1348106Y1655530D01*
X1348003Y1655224D01*
X1347693Y1654955D01*
X1347228Y1654802D01*
X1346711Y1654764D01*
X1346039Y1654840D01*
X1345678Y1654955D01*
X1345316Y1655147D01*
X1345058Y1655415D01*
X1345006Y1655684D01*
X1345109Y1655952D01*
X1345368Y1656144D01*
G01X1338572Y1655169D02*
X1338830Y1655399D01*
X1338985Y1655667D01*
X1339037Y1656012D01*
X1338934Y1656357D01*
X1338727Y1656625D01*
X1338365Y1656817D01*
X1337952Y1656855D01*
X1337539Y1656779D01*
X1337280Y1656587D01*
X1337074Y1656319D01*
X1337022Y1656050D01*
X1337074Y1655782D01*
X1337280Y1655437D01*
X1335937Y1655552D01*
Y1656587D01*
G01X1351800Y1646023D02*
X1345200D01*
G01X1345800Y1657834D02*
X1351300D01*
G01X1334000D02*
X1339200D01*
G01X1354150Y59811D02*
Y66011D01*
G01X1357350D02*
Y59811D01*
G01D02*
X1354150D01*
G01X1351550Y68894D02*
Y58494D01*
G01X1363853Y50601D02*
X1360753D01*
Y51367D01*
X1360908Y51674D01*
X1361115Y51904D01*
X1361425Y52096D01*
X1361786Y52249D01*
X1362303Y52287D01*
X1362820Y52249D01*
X1363181Y52096D01*
X1363491Y51904D01*
X1363698Y51674D01*
X1363853Y51367D01*
Y50601D01*
G01Y55004D02*
X1360753D01*
X1362975Y53586D01*
Y55502D01*
G01X1363491Y56992D02*
X1363750Y57261D01*
X1363853Y57567D01*
X1363750Y57874D01*
X1363440Y58142D01*
X1362975Y58334D01*
X1362510Y58411D01*
X1361941D01*
X1361476Y58334D01*
X1361063Y58142D01*
X1360856Y57912D01*
X1360753Y57644D01*
X1360856Y57337D01*
X1361063Y57107D01*
X1361373Y56954D01*
X1361786Y56877D01*
X1362148Y56954D01*
X1362510Y57146D01*
X1362716Y57376D01*
X1362768Y57644D01*
X1362665Y57951D01*
X1362406Y58181D01*
X1361941Y58411D01*
G01X1359650Y59174D02*
Y66264D01*
G01X1363450D02*
Y59124D01*
G01D02*
X1359700D01*
G01X1359650Y59574D02*
Y66764D01*
G01X1363450D02*
Y59574D01*
G01X1359650Y60174D02*
Y67264D01*
G01X1363450D02*
Y60174D01*
G01X1361826Y70647D02*
X1362034Y70860D01*
X1362159Y71100D01*
Y71314D01*
X1362034Y71527D01*
X1361826Y71687D01*
X1361534Y71767D01*
X1361242Y71714D01*
X1360992Y71580D01*
X1360826Y71340D01*
X1360742Y71020D01*
X1360576Y70834D01*
X1360284Y70754D01*
X1359992Y70807D01*
X1359784Y70940D01*
X1359659Y71127D01*
Y71314D01*
X1359742Y71500D01*
X1359951Y71660D01*
G01X1362159Y72714D02*
X1359659D01*
X1361742Y73407D01*
X1359659Y74100D01*
X1362159D01*
G01Y76140D02*
Y75074D01*
X1359659D01*
Y76140D01*
G01X1360867Y75714D02*
Y75074D01*
G01X1362159Y77274D02*
X1359659D01*
Y77940D01*
X1359784Y78154D01*
X1359951Y78287D01*
X1360284Y78340D01*
X1360617Y78287D01*
X1360826Y78127D01*
X1360951Y77940D01*
Y77274D01*
G01Y77940D02*
X1362159Y78340D01*
G01Y79474D02*
X1359659D01*
Y80140D01*
X1359784Y80354D01*
X1359951Y80487D01*
X1360284Y80540D01*
X1360617Y80487D01*
X1360826Y80327D01*
X1360951Y80140D01*
Y79474D01*
G01Y80140D02*
X1362159Y80540D01*
G01X1359079Y72372D02*
X1355488D01*
X1353231Y70115D01*
G01X1352827Y69643D02*
X1352796Y72471D01*
G01D02*
X1355655Y69674D01*
G01D02*
X1352827Y69643D01*
G01X1354150Y66011D02*
X1357350D01*
G01X1351550Y70694D02*
Y68894D01*
G01X1358640Y77175D02*
Y73828D01*
G01D02*
X1349978D01*
G01D02*
Y84322D01*
G01X1359650Y66264D02*
X1363450D01*
G01X1359650Y66764D02*
X1363450D01*
G01X1359650Y67264D02*
X1363450D01*
G01X1366767Y87572D02*
X1366715Y87265D01*
X1366509Y86997D01*
X1366199Y86767D01*
X1365837Y86614D01*
X1365424Y86537D01*
X1365010D01*
X1364597Y86614D01*
X1364235Y86767D01*
X1363925Y86997D01*
X1363719Y87265D01*
X1363667Y87572D01*
X1363719Y87879D01*
X1363925Y88147D01*
X1364235Y88377D01*
X1364597Y88530D01*
X1365010Y88607D01*
X1365424D01*
X1365837Y88530D01*
X1366199Y88377D01*
X1366509Y88147D01*
X1366715Y87879D01*
X1366767Y87572D01*
G01X1365940Y87879D02*
X1366767Y88339D01*
G01Y90672D02*
X1363667D01*
X1364287Y90212D01*
G01X1366767D02*
Y91132D01*
G01Y93772D02*
X1363667D01*
X1364287Y93312D01*
G01X1366767D02*
Y94232D01*
G01X1358640Y84322D02*
Y80975D01*
G01D02*
X1356440Y79075D01*
G01D02*
X1358640Y77175D01*
G01X1349978Y84322D02*
X1358640D01*
G01X1357799Y97150D02*
Y90950D01*
G01D02*
X1354599D01*
G01D02*
Y97150D01*
G01D02*
X1357799D01*
G01X1353799D02*
Y90950D01*
G01D02*
X1350599D01*
G01D02*
Y97150D01*
G01D02*
X1353799D01*
G01X1349799Y97184D02*
Y90984D01*
G01X1361709Y97150D02*
Y90950D01*
G01D02*
X1358509D01*
G01D02*
Y97150D01*
G01D02*
X1361709D01*
G01X1370869Y103282D02*
X1357869D01*
G01D02*
Y119482D01*
G01D02*
X1370869D01*
G01X1356299Y234544D02*
Y233307D01*
G01Y239544D02*
Y238644D01*
G01Y244544D02*
Y243644D01*
G01Y249544D02*
Y248644D01*
G01Y254881D02*
Y253644D01*
G01X1364766Y260794D02*
X1361666D01*
Y261560D01*
X1361821Y261867D01*
X1362028Y262097D01*
X1362338Y262289D01*
X1362699Y262442D01*
X1363216Y262480D01*
X1363733Y262442D01*
X1364094Y262289D01*
X1364404Y262097D01*
X1364611Y261867D01*
X1364766Y261560D01*
Y260794D01*
G01Y264737D02*
X1364714Y265005D01*
X1364559Y265312D01*
X1364301Y265504D01*
X1363939Y265580D01*
X1363578Y265504D01*
X1363268Y265274D01*
X1363113Y264929D01*
Y264545D01*
X1363009Y264315D01*
X1362751Y264124D01*
X1362389Y264047D01*
X1362028Y264162D01*
X1361769Y264430D01*
X1361666Y264737D01*
X1361769Y265044D01*
X1362028Y265312D01*
X1362389Y265427D01*
X1362751Y265350D01*
X1363009Y265159D01*
X1363113Y264929D01*
Y264545D01*
X1363268Y264200D01*
X1363578Y263970D01*
X1363939Y263894D01*
X1364301Y263970D01*
X1364559Y264162D01*
X1364714Y264469D01*
X1364766Y264737D01*
G01X1364301Y266994D02*
X1364559Y267224D01*
X1364714Y267492D01*
X1364766Y267837D01*
X1364663Y268182D01*
X1364456Y268450D01*
X1364094Y268642D01*
X1363681Y268680D01*
X1363268Y268604D01*
X1363009Y268412D01*
X1362803Y268144D01*
X1362751Y267875D01*
X1362803Y267607D01*
X1363009Y267262D01*
X1361666Y267377D01*
Y268412D01*
G01X1356766Y260794D02*
X1353666D01*
Y261560D01*
X1353821Y261867D01*
X1354028Y262097D01*
X1354338Y262289D01*
X1354699Y262442D01*
X1355216Y262480D01*
X1355733Y262442D01*
X1356094Y262289D01*
X1356404Y262097D01*
X1356611Y261867D01*
X1356766Y261560D01*
Y260794D01*
G01Y264737D02*
X1356714Y265005D01*
X1356559Y265312D01*
X1356301Y265504D01*
X1355939Y265580D01*
X1355578Y265504D01*
X1355268Y265274D01*
X1355113Y264929D01*
Y264545D01*
X1355009Y264315D01*
X1354751Y264124D01*
X1354389Y264047D01*
X1354028Y264162D01*
X1353769Y264430D01*
X1353666Y264737D01*
X1353769Y265044D01*
X1354028Y265312D01*
X1354389Y265427D01*
X1354751Y265350D01*
X1355009Y265159D01*
X1355113Y264929D01*
Y264545D01*
X1355268Y264200D01*
X1355578Y263970D01*
X1355939Y263894D01*
X1356301Y263970D01*
X1356559Y264162D01*
X1356714Y264469D01*
X1356766Y264737D01*
G01Y268297D02*
X1353666D01*
X1355888Y266879D01*
Y268795D01*
G01X1356194Y273458D02*
Y280548D01*
G01D02*
X1359994D01*
G01D02*
Y273458D01*
G01X1356194Y272858D02*
Y280048D01*
G01D02*
X1359994D01*
G01D02*
Y272858D01*
G01X1356194Y272458D02*
Y279548D01*
G01D02*
X1359994D01*
G01D02*
Y272408D01*
G01D02*
X1356244D01*
G01X1351994Y280548D02*
Y273458D01*
G01Y280048D02*
Y272858D01*
G01Y279548D02*
Y272408D01*
G01X1360813Y294392D02*
X1355813D01*
Y295912D01*
X1356063Y296419D01*
X1356646Y296799D01*
X1357313Y296926D01*
X1357980Y296799D01*
X1358480Y296482D01*
X1358730Y295912D01*
Y294392D01*
G01X1355813Y298859D02*
X1360813Y299746D01*
X1355813Y300759D01*
X1360813Y301772D01*
X1355813Y302659D01*
G01X1360813Y304592D02*
X1355813D01*
Y306176D01*
X1356063Y306682D01*
X1356396Y306999D01*
X1357063Y307126D01*
X1357730Y306999D01*
X1358146Y306619D01*
X1358396Y306176D01*
Y304592D01*
G01Y306176D02*
X1360813Y307126D01*
G01X1358313Y311339D02*
Y312606D01*
X1359813D01*
X1360313Y312226D01*
X1360646Y311782D01*
X1360813Y311149D01*
X1360646Y310516D01*
X1360313Y310072D01*
X1359813Y309692D01*
X1359230Y309439D01*
X1358563Y309312D01*
X1357980D01*
X1357480Y309439D01*
X1356896Y309692D01*
X1356396Y310072D01*
X1356063Y310452D01*
X1355813Y310959D01*
Y311402D01*
X1355980Y311909D01*
X1356313Y312289D01*
G01X1360813Y314666D02*
X1355813D01*
Y315932D01*
X1356063Y316439D01*
X1356396Y316819D01*
X1356896Y317136D01*
X1357480Y317389D01*
X1358313Y317452D01*
X1359146Y317389D01*
X1359730Y317136D01*
X1360230Y316819D01*
X1360563Y316439D01*
X1360813Y315932D01*
Y314666D01*
G01X1362480Y319259D02*
Y323059D01*
G01X1360813Y324992D02*
X1355813D01*
Y326512D01*
X1356063Y327019D01*
X1356646Y327399D01*
X1357313Y327526D01*
X1357980Y327399D01*
X1358480Y327082D01*
X1358730Y326512D01*
Y324992D01*
G01X1355813Y329776D02*
X1360813Y331359D01*
X1355813Y332942D01*
G01X1360813Y335066D02*
X1355813D01*
Y336332D01*
X1356063Y336839D01*
X1356396Y337219D01*
X1356896Y337536D01*
X1357480Y337789D01*
X1358313Y337852D01*
X1359146Y337789D01*
X1359730Y337536D01*
X1360230Y337219D01*
X1360563Y336839D01*
X1360813Y336332D01*
Y335066D01*
G01Y340166D02*
X1355813D01*
Y341432D01*
X1356063Y341939D01*
X1356396Y342319D01*
X1356896Y342636D01*
X1357480Y342889D01*
X1358313Y342952D01*
X1359146Y342889D01*
X1359730Y342636D01*
X1360230Y342319D01*
X1360563Y341939D01*
X1360813Y341432D01*
Y340166D01*
G01X1355813Y345899D02*
Y347419D01*
G01Y346659D02*
X1360813D01*
G01Y345899D02*
Y347419D01*
G01Y351759D02*
X1360730Y351252D01*
X1360396Y350809D01*
X1359896Y350429D01*
X1359313Y350176D01*
X1358646Y350049D01*
X1357980D01*
X1357313Y350176D01*
X1356730Y350429D01*
X1356230Y350809D01*
X1355896Y351252D01*
X1355813Y351759D01*
X1355896Y352266D01*
X1356230Y352709D01*
X1356730Y353089D01*
X1357313Y353342D01*
X1357980Y353469D01*
X1358646D01*
X1359313Y353342D01*
X1359896Y353089D01*
X1360396Y352709D01*
X1360730Y352266D01*
X1360813Y351759D01*
G01X1362480Y354959D02*
Y358759D01*
G01X1360813Y360692D02*
X1355813D01*
Y362212D01*
X1356063Y362719D01*
X1356646Y363099D01*
X1357313Y363226D01*
X1357980Y363099D01*
X1358480Y362782D01*
X1358730Y362212D01*
Y360692D01*
G01X1360813Y367059D02*
X1355813D01*
X1356813Y366299D01*
G01X1360813D02*
Y367819D01*
G01X1368413Y294392D02*
X1363413D01*
Y295912D01*
X1363663Y296419D01*
X1364246Y296799D01*
X1364913Y296926D01*
X1365580Y296799D01*
X1366080Y296482D01*
X1366330Y295912D01*
Y294392D01*
G01X1363413Y298859D02*
X1368413Y299746D01*
X1363413Y300759D01*
X1368413Y301772D01*
X1363413Y302659D01*
G01X1368413Y304592D02*
X1363413D01*
Y306176D01*
X1363663Y306682D01*
X1363996Y306999D01*
X1364663Y307126D01*
X1365330Y306999D01*
X1365746Y306619D01*
X1365996Y306176D01*
Y304592D01*
G01Y306176D02*
X1368413Y307126D01*
G01X1365913Y311339D02*
Y312606D01*
X1367413D01*
X1367913Y312226D01*
X1368246Y311782D01*
X1368413Y311149D01*
X1368246Y310516D01*
X1367913Y310072D01*
X1367413Y309692D01*
X1366830Y309439D01*
X1366163Y309312D01*
X1365580D01*
X1365080Y309439D01*
X1364496Y309692D01*
X1363996Y310072D01*
X1363663Y310452D01*
X1363413Y310959D01*
Y311402D01*
X1363580Y311909D01*
X1363913Y312289D01*
G01X1368413Y314666D02*
X1363413D01*
Y315932D01*
X1363663Y316439D01*
X1363996Y316819D01*
X1364496Y317136D01*
X1365080Y317389D01*
X1365913Y317452D01*
X1366746Y317389D01*
X1367330Y317136D01*
X1367830Y316819D01*
X1368163Y316439D01*
X1368413Y315932D01*
Y314666D01*
G01X1370080Y319259D02*
Y323059D01*
G01X1368413Y324992D02*
X1363413D01*
Y326512D01*
X1363663Y327019D01*
X1364246Y327399D01*
X1364913Y327526D01*
X1365580Y327399D01*
X1366080Y327082D01*
X1366330Y326512D01*
Y324992D01*
G01X1363413Y329776D02*
X1368413Y331359D01*
X1363413Y332942D01*
G01X1368413Y335066D02*
X1363413D01*
Y336332D01*
X1363663Y336839D01*
X1363996Y337219D01*
X1364496Y337536D01*
X1365080Y337789D01*
X1365913Y337852D01*
X1366746Y337789D01*
X1367330Y337536D01*
X1367830Y337219D01*
X1368163Y336839D01*
X1368413Y336332D01*
Y335066D01*
G01Y340166D02*
X1363413D01*
Y341432D01*
X1363663Y341939D01*
X1363996Y342319D01*
X1364496Y342636D01*
X1365080Y342889D01*
X1365913Y342952D01*
X1366746Y342889D01*
X1367330Y342636D01*
X1367830Y342319D01*
X1368163Y341939D01*
X1368413Y341432D01*
Y340166D01*
G01Y346659D02*
X1363413D01*
X1364413Y345899D01*
G01X1368413D02*
Y347419D01*
G01Y351759D02*
X1363413D01*
X1364413Y350999D01*
G01X1368413D02*
Y352519D01*
G01X1370080Y354959D02*
Y358759D01*
G01X1367746Y360629D02*
X1368163Y361136D01*
X1368413Y361706D01*
Y362212D01*
X1368163Y362719D01*
X1367746Y363099D01*
X1367163Y363289D01*
X1366580Y363162D01*
X1366080Y362846D01*
X1365746Y362276D01*
X1365580Y361516D01*
X1365246Y361072D01*
X1364663Y360882D01*
X1364080Y361009D01*
X1363663Y361326D01*
X1363413Y361769D01*
Y362212D01*
X1363580Y362656D01*
X1363996Y363036D01*
G01X1367413Y365666D02*
X1367996Y366046D01*
X1368330Y366552D01*
X1368413Y367122D01*
X1368330Y367629D01*
X1367913Y368136D01*
X1367413Y368452D01*
X1366913Y368516D01*
X1366330Y368389D01*
X1365913Y367946D01*
X1365746Y367502D01*
Y366932D01*
G01Y367502D02*
X1365496Y367882D01*
X1365080Y368199D01*
X1364580Y368326D01*
X1364080Y368199D01*
X1363663Y367882D01*
X1363413Y367312D01*
X1363496Y366742D01*
X1363830Y366172D01*
G01X1370080Y370259D02*
Y374059D01*
G01X1368413Y375992D02*
X1363413D01*
Y377512D01*
X1363663Y378019D01*
X1364246Y378399D01*
X1364913Y378526D01*
X1365580Y378399D01*
X1366080Y378082D01*
X1366330Y377512D01*
Y375992D01*
G01X1368413Y382359D02*
X1363413D01*
X1364413Y381599D01*
G01X1368413D02*
Y383119D01*
G01X1355229Y596003D02*
Y599103D01*
G01X1356839D02*
Y596003D01*
G01Y597553D02*
X1355229D01*
G01X1358291Y596468D02*
X1358521Y596210D01*
X1358789Y596055D01*
X1359134Y596003D01*
X1359479Y596106D01*
X1359747Y596313D01*
X1359939Y596675D01*
X1359977Y597088D01*
X1359901Y597501D01*
X1359709Y597760D01*
X1359441Y597966D01*
X1359172Y598018D01*
X1358904Y597966D01*
X1358559Y597760D01*
X1358674Y599103D01*
X1359709D01*
G01X1362694Y596003D02*
Y599103D01*
X1361276Y596881D01*
X1363192D01*
G01X1360376Y612993D02*
Y619193D01*
G01D02*
X1363576D01*
G01D02*
Y612993D01*
G01D02*
X1360376D01*
G01X1359897Y622596D02*
X1359164D01*
G01D02*
Y624787D01*
G01X1351861Y637181D02*
Y630981D01*
G01X1352997D02*
Y637181D01*
G01D02*
X1356197D01*
G01D02*
Y630981D01*
G01D02*
X1352997D01*
G01X1352017Y665566D02*
Y639976D01*
G01X1359164Y643618D02*
Y646218D01*
G01D02*
X1359957D01*
G01X1354097Y692745D02*
Y649437D01*
G01D02*
X1359438D01*
G01X1352372Y679268D02*
Y673068D01*
G01D02*
X1349172D01*
G01D02*
Y679268D01*
G01D02*
X1352372D01*
G01X1354638Y700883D02*
Y703983D01*
X1355558D01*
X1355865Y703828D01*
X1356095Y703466D01*
X1356172Y703053D01*
X1356095Y702640D01*
X1355903Y702330D01*
X1355558Y702175D01*
X1354638D01*
G01X1357738Y703983D02*
Y700883D01*
X1359272D01*
G01X1361528D02*
X1361605Y701555D01*
X1361720Y702123D01*
X1361873Y702640D01*
X1362065Y703208D01*
X1362372Y703983D01*
X1360838D01*
G01X1364705D02*
X1364398Y703880D01*
X1364168Y703621D01*
X1364015Y703311D01*
X1363900Y702898D01*
X1363862Y702433D01*
X1363900Y701968D01*
X1364015Y701555D01*
X1364168Y701245D01*
X1364398Y700986D01*
X1364705Y700883D01*
X1365012Y700986D01*
X1365242Y701245D01*
X1365395Y701555D01*
X1365510Y701968D01*
X1365548Y702433D01*
X1365510Y702898D01*
X1365395Y703311D01*
X1365242Y703621D01*
X1365012Y703880D01*
X1364705Y703983D01*
G01X1359438Y692745D02*
X1354097D01*
G01X1361513Y1260515D02*
X1366854D01*
G01X1361773Y1307183D02*
X1360980D01*
G01X1361773Y1309783D02*
Y1307183D01*
G01X1366854Y1303823D02*
X1361513D01*
G01X1357361Y1340408D02*
X1360561D01*
G01X1357361Y1334208D02*
Y1340408D01*
G01X1360561Y1334208D02*
X1357361D01*
G01X1360561Y1340408D02*
Y1334208D01*
G01X1349894Y1341112D02*
Y1337912D01*
G01X1356519Y1334208D02*
X1353319D01*
G01X1356519Y1340408D02*
Y1334208D01*
G01X1353319Y1340408D02*
X1356519D01*
G01X1353319Y1334208D02*
Y1340408D01*
G01X1361773Y1330805D02*
Y1328614D01*
G01X1361040Y1330805D02*
X1361773D01*
G01X1358990Y1393819D02*
X1433712D01*
G01X1361706Y1396568D02*
X1358606D01*
Y1397488D01*
X1358761Y1397795D01*
X1359123Y1398025D01*
X1359536Y1398102D01*
X1359949Y1398025D01*
X1360259Y1397833D01*
X1360414Y1397488D01*
Y1396568D01*
G01X1358606Y1399668D02*
X1361706D01*
Y1401202D01*
G01Y1403535D02*
X1358606D01*
X1359226Y1403075D01*
G01X1361706D02*
Y1403995D01*
G01X1359123Y1405907D02*
X1358813Y1406137D01*
X1358658Y1406405D01*
X1358606Y1406712D01*
X1358709Y1407095D01*
X1358968Y1407363D01*
X1359278Y1407440D01*
X1359588Y1407402D01*
X1359846Y1407248D01*
X1360363Y1406482D01*
X1360724Y1406137D01*
X1361241Y1405907D01*
X1361706Y1405830D01*
Y1407440D01*
G01X1356884Y1389777D02*
Y1413793D01*
G01X1350773Y1389777D02*
X1356884D01*
G01Y1413793D02*
X1350773D01*
G01X1358356Y1441599D02*
X1350856Y1443932D01*
X1358356Y1446265D01*
G01X1355731Y1445425D02*
Y1442439D01*
G01X1358356Y1451432D02*
X1350856D01*
X1352356Y1450312D01*
G01X1358356D02*
Y1452552D01*
G01X1377313Y1437636D02*
X1362313D01*
G01D02*
Y1457636D01*
G01D02*
Y1437636D01*
G01Y1457636D02*
X1369441D01*
G01X1352722Y1653285D02*
X1352050Y1653362D01*
X1351482Y1653477D01*
X1350965Y1653630D01*
X1350397Y1653822D01*
X1349622Y1654129D01*
Y1652595D01*
G01X1362659Y1656012D02*
X1362607Y1656280D01*
X1362452Y1656587D01*
X1362194Y1656779D01*
X1361832Y1656855D01*
X1361471Y1656779D01*
X1361161Y1656549D01*
X1361006Y1656204D01*
Y1655820D01*
X1360902Y1655590D01*
X1360644Y1655399D01*
X1360282Y1655322D01*
X1359921Y1655437D01*
X1359662Y1655705D01*
X1359559Y1656012D01*
X1359662Y1656319D01*
X1359921Y1656587D01*
X1360282Y1656702D01*
X1360644Y1656625D01*
X1360902Y1656434D01*
X1361006Y1656204D01*
Y1655820D01*
X1361161Y1655475D01*
X1361471Y1655245D01*
X1361832Y1655169D01*
X1362194Y1655245D01*
X1362452Y1655437D01*
X1362607Y1655744D01*
X1362659Y1656012D01*
G01X1363800Y1646023D02*
X1357300D01*
G01X1358000Y1657834D02*
X1362800D01*
G01X1366350Y59811D02*
Y66011D01*
G01X1369550D02*
Y59811D01*
G01D02*
X1366350D01*
G01X1375703Y50691D02*
X1372603D01*
Y51457D01*
X1372758Y51764D01*
X1372965Y51994D01*
X1373275Y52186D01*
X1373636Y52339D01*
X1374153Y52377D01*
X1374670Y52339D01*
X1375031Y52186D01*
X1375341Y51994D01*
X1375548Y51764D01*
X1375703Y51457D01*
Y50691D01*
G01Y55094D02*
X1372603D01*
X1374825Y53676D01*
Y55592D01*
G01X1374411Y57006D02*
X1374050Y57274D01*
X1373843Y57504D01*
X1373740Y57811D01*
X1373843Y58079D01*
X1374050Y58271D01*
X1374360Y58424D01*
X1374721Y58462D01*
X1375031Y58424D01*
X1375341Y58271D01*
X1375600Y58041D01*
X1375703Y57772D01*
X1375600Y57466D01*
X1375290Y57197D01*
X1374825Y57044D01*
X1374308Y57006D01*
X1373636Y57082D01*
X1373275Y57197D01*
X1372913Y57389D01*
X1372655Y57657D01*
X1372603Y57926D01*
X1372706Y58194D01*
X1372965Y58386D01*
G01X1371850Y59174D02*
Y66264D01*
G01X1375650D02*
Y59124D01*
G01D02*
X1371900D01*
G01X1371850Y59574D02*
Y66764D01*
G01X1375650D02*
Y59574D01*
G01X1371850Y60174D02*
Y67264D01*
G01X1375650D02*
Y60174D01*
G01X1366398Y67766D02*
X1363898D01*
Y68406D01*
X1364023Y68619D01*
X1364315Y68779D01*
X1364648Y68832D01*
X1364981Y68779D01*
X1365231Y68646D01*
X1365356Y68406D01*
Y67766D01*
G01X1366023Y69912D02*
X1366231Y70072D01*
X1366356Y70259D01*
X1366398Y70499D01*
X1366315Y70739D01*
X1366148Y70926D01*
X1365856Y71059D01*
X1365523Y71086D01*
X1365190Y71032D01*
X1364981Y70899D01*
X1364815Y70712D01*
X1364773Y70526D01*
X1364815Y70339D01*
X1364981Y70099D01*
X1363898Y70179D01*
Y70899D01*
G01Y72032D02*
X1366398Y72699D01*
X1363898Y73366D01*
G01X1367231Y74099D02*
Y75699D01*
G01X1366398Y76432D02*
X1363898Y77099D01*
X1366398Y77766D01*
G01X1365523Y77526D02*
Y76672D01*
G01X1363898Y78712D02*
X1365690D01*
X1366065Y78819D01*
X1366315Y79032D01*
X1366398Y79299D01*
X1366315Y79566D01*
X1366065Y79779D01*
X1365690Y79886D01*
X1363898D01*
G01X1366398Y80939D02*
X1363898Y82059D01*
G01Y80939D02*
X1366398Y82059D01*
G01X1366350Y66011D02*
X1369550D01*
G01X1380245Y71878D02*
X1367245D01*
G01D02*
Y86678D01*
G01X1371850Y66264D02*
X1375650D01*
G01X1371850Y66764D02*
X1375650D01*
G01X1371850Y67264D02*
X1375650D01*
G01X1367245Y86678D02*
X1380245D01*
G01X1366584Y102109D02*
X1372784D01*
G01D02*
Y98909D01*
G01D02*
X1366584D01*
G01D02*
Y102109D01*
G01X1373044Y104585D02*
X1375266D01*
X1375731Y104738D01*
X1376041Y105045D01*
X1376144Y105428D01*
X1376041Y105811D01*
X1375731Y106118D01*
X1375266Y106271D01*
X1373044D01*
G01X1376144Y108528D02*
X1376092Y108796D01*
X1375937Y109103D01*
X1375679Y109295D01*
X1375317Y109371D01*
X1374956Y109295D01*
X1374646Y109065D01*
X1374491Y108720D01*
Y108336D01*
X1374387Y108106D01*
X1374129Y107915D01*
X1373767Y107838D01*
X1373406Y107953D01*
X1373147Y108221D01*
X1373044Y108528D01*
X1373147Y108835D01*
X1373406Y109103D01*
X1373767Y109218D01*
X1374129Y109141D01*
X1374387Y108950D01*
X1374491Y108720D01*
Y108336D01*
X1374646Y107991D01*
X1374956Y107761D01*
X1375317Y107685D01*
X1375679Y107761D01*
X1375937Y107953D01*
X1376092Y108260D01*
X1376144Y108528D01*
G01X1374852Y110900D02*
X1374491Y111168D01*
X1374284Y111398D01*
X1374181Y111705D01*
X1374284Y111973D01*
X1374491Y112165D01*
X1374801Y112318D01*
X1375162Y112356D01*
X1375472Y112318D01*
X1375782Y112165D01*
X1376041Y111935D01*
X1376144Y111666D01*
X1376041Y111360D01*
X1375731Y111091D01*
X1375266Y110938D01*
X1374749Y110900D01*
X1374077Y110976D01*
X1373716Y111091D01*
X1373354Y111283D01*
X1373096Y111551D01*
X1373044Y111820D01*
X1373147Y112088D01*
X1373406Y112280D01*
G01X1370869Y109882D02*
Y103282D01*
G01Y119482D02*
Y112882D01*
G01D02*
X1368369Y111382D01*
G01D02*
X1370869Y109882D01*
G01X1372095Y186325D02*
X1372287Y186015D01*
X1372517Y185808D01*
X1372785Y185705D01*
X1373092Y185808D01*
X1373322Y186015D01*
X1373552Y186325D01*
X1373629Y186738D01*
Y188805D01*
G01X1375234Y188288D02*
X1375464Y188598D01*
X1375732Y188753D01*
X1376039Y188805D01*
X1376422Y188702D01*
X1376690Y188443D01*
X1376767Y188133D01*
X1376729Y187823D01*
X1376575Y187565D01*
X1375809Y187048D01*
X1375464Y186687D01*
X1375234Y186170D01*
X1375157Y185705D01*
X1376767D01*
G01X1379062D02*
Y188805D01*
X1378602Y188185D01*
G01Y185705D02*
X1379522D01*
G01X1381434Y188288D02*
X1381664Y188598D01*
X1381932Y188753D01*
X1382239Y188805D01*
X1382622Y188702D01*
X1382890Y188443D01*
X1382967Y188133D01*
X1382929Y187823D01*
X1382775Y187565D01*
X1382009Y187048D01*
X1381664Y186687D01*
X1381434Y186170D01*
X1381357Y185705D01*
X1382967D01*
G01X1382815Y234994D02*
X1376615D01*
G01D02*
Y238194D01*
G01D02*
X1382815D01*
G01Y239994D02*
X1376615D01*
G01D02*
Y243194D01*
G01D02*
X1382815D01*
G01Y244994D02*
X1376615D01*
G01D02*
Y248194D01*
G01D02*
X1382815D01*
G01Y249994D02*
X1376615D01*
G01D02*
Y253194D01*
G01D02*
X1382815D01*
G01X1364194Y273458D02*
Y280548D01*
G01D02*
X1367994D01*
G01D02*
Y273458D01*
G01X1364194Y272858D02*
Y280048D01*
G01D02*
X1367994D01*
G01D02*
Y272858D01*
G01X1364194Y272458D02*
Y279548D01*
G01D02*
X1367994D01*
G01D02*
Y272408D01*
G01D02*
X1364244D01*
G01X1376013Y294392D02*
X1371013D01*
Y295912D01*
X1371263Y296419D01*
X1371846Y296799D01*
X1372513Y296926D01*
X1373180Y296799D01*
X1373680Y296482D01*
X1373930Y295912D01*
Y294392D01*
G01X1371013Y298859D02*
X1376013Y299746D01*
X1371013Y300759D01*
X1376013Y301772D01*
X1371013Y302659D01*
G01X1376013Y304592D02*
X1371013D01*
Y306176D01*
X1371263Y306682D01*
X1371596Y306999D01*
X1372263Y307126D01*
X1372930Y306999D01*
X1373346Y306619D01*
X1373596Y306176D01*
Y304592D01*
G01Y306176D02*
X1376013Y307126D01*
G01X1373513Y311339D02*
Y312606D01*
X1375013D01*
X1375513Y312226D01*
X1375846Y311782D01*
X1376013Y311149D01*
X1375846Y310516D01*
X1375513Y310072D01*
X1375013Y309692D01*
X1374430Y309439D01*
X1373763Y309312D01*
X1373180D01*
X1372680Y309439D01*
X1372096Y309692D01*
X1371596Y310072D01*
X1371263Y310452D01*
X1371013Y310959D01*
Y311402D01*
X1371180Y311909D01*
X1371513Y312289D01*
G01X1376013Y314666D02*
X1371013D01*
Y315932D01*
X1371263Y316439D01*
X1371596Y316819D01*
X1372096Y317136D01*
X1372680Y317389D01*
X1373513Y317452D01*
X1374346Y317389D01*
X1374930Y317136D01*
X1375430Y316819D01*
X1375763Y316439D01*
X1376013Y315932D01*
Y314666D01*
G01X1377680Y319259D02*
Y323059D01*
G01X1376013Y324992D02*
X1371013D01*
Y326512D01*
X1371263Y327019D01*
X1371846Y327399D01*
X1372513Y327526D01*
X1373180Y327399D01*
X1373680Y327082D01*
X1373930Y326512D01*
Y324992D01*
G01X1371013Y329776D02*
X1376013Y331359D01*
X1371013Y332942D01*
G01X1376013Y335066D02*
X1371013D01*
Y336332D01*
X1371263Y336839D01*
X1371596Y337219D01*
X1372096Y337536D01*
X1372680Y337789D01*
X1373513Y337852D01*
X1374346Y337789D01*
X1374930Y337536D01*
X1375430Y337219D01*
X1375763Y336839D01*
X1376013Y336332D01*
Y335066D01*
G01Y340166D02*
X1371013D01*
Y341432D01*
X1371263Y341939D01*
X1371596Y342319D01*
X1372096Y342636D01*
X1372680Y342889D01*
X1373513Y342952D01*
X1374346Y342889D01*
X1374930Y342636D01*
X1375430Y342319D01*
X1375763Y341939D01*
X1376013Y341432D01*
Y340166D01*
G01Y346659D02*
X1371013D01*
X1372013Y345899D01*
G01X1376013D02*
Y347419D01*
G01Y351759D02*
X1375930Y352202D01*
X1375680Y352709D01*
X1375263Y353026D01*
X1374680Y353152D01*
X1374096Y353026D01*
X1373596Y352646D01*
X1373346Y352076D01*
Y351442D01*
X1373180Y351062D01*
X1372763Y350746D01*
X1372180Y350619D01*
X1371596Y350809D01*
X1371180Y351252D01*
X1371013Y351759D01*
X1371180Y352266D01*
X1371596Y352709D01*
X1372180Y352899D01*
X1372763Y352772D01*
X1373180Y352456D01*
X1373346Y352076D01*
Y351442D01*
X1373596Y350872D01*
X1374096Y350492D01*
X1374680Y350366D01*
X1375263Y350492D01*
X1375680Y350809D01*
X1375930Y351316D01*
X1376013Y351759D01*
G01X1377680Y354959D02*
Y358759D01*
G01X1375346Y360629D02*
X1375763Y361136D01*
X1376013Y361706D01*
Y362212D01*
X1375763Y362719D01*
X1375346Y363099D01*
X1374763Y363289D01*
X1374180Y363162D01*
X1373680Y362846D01*
X1373346Y362276D01*
X1373180Y361516D01*
X1372846Y361072D01*
X1372263Y360882D01*
X1371680Y361009D01*
X1371263Y361326D01*
X1371013Y361769D01*
Y362212D01*
X1371180Y362656D01*
X1371596Y363036D01*
G01X1375263Y365666D02*
X1375680Y366046D01*
X1375930Y366489D01*
X1376013Y367059D01*
X1375846Y367629D01*
X1375513Y368072D01*
X1374930Y368389D01*
X1374263Y368452D01*
X1373596Y368326D01*
X1373180Y368009D01*
X1372846Y367566D01*
X1372763Y367122D01*
X1372846Y366679D01*
X1373180Y366109D01*
X1371013Y366299D01*
Y368009D01*
G01X1377680Y370259D02*
Y374059D01*
G01X1376013Y375992D02*
X1371013D01*
Y377512D01*
X1371263Y378019D01*
X1371846Y378399D01*
X1372513Y378526D01*
X1373180Y378399D01*
X1373680Y378082D01*
X1373930Y377512D01*
Y375992D01*
G01X1376013Y382359D02*
X1371013D01*
X1372013Y381599D01*
G01X1376013D02*
Y383119D01*
G01X1365335Y397056D02*
Y402056D01*
X1367741D01*
G01X1366855Y399639D02*
X1365335D01*
G01X1370371Y397056D02*
Y402056D01*
X1371891D01*
X1372398Y401806D01*
X1372778Y401223D01*
X1372905Y400556D01*
X1372778Y399889D01*
X1372461Y399389D01*
X1371891Y399139D01*
X1370371D01*
G01X1377118Y399556D02*
X1378385D01*
Y398056D01*
X1378005Y397556D01*
X1377561Y397223D01*
X1376928Y397056D01*
X1376295Y397223D01*
X1375851Y397556D01*
X1375471Y398056D01*
X1375218Y398639D01*
X1375091Y399306D01*
Y399889D01*
X1375218Y400389D01*
X1375471Y400973D01*
X1375851Y401473D01*
X1376231Y401806D01*
X1376738Y402056D01*
X1377181D01*
X1377688Y401889D01*
X1378068Y401556D01*
G01X1380255Y397056D02*
X1381838Y402056D01*
X1383421Y397056D01*
G01X1382851Y398806D02*
X1380825D01*
G01X1390645Y397056D02*
Y402056D01*
X1391911D01*
X1392418Y401806D01*
X1392798Y401473D01*
X1393115Y400973D01*
X1393368Y400389D01*
X1393431Y399556D01*
X1393368Y398723D01*
X1393115Y398139D01*
X1392798Y397639D01*
X1392418Y397306D01*
X1391911Y397056D01*
X1390645D01*
G01X1398405D02*
X1395871D01*
Y402056D01*
X1398405D01*
G01X1397391Y399639D02*
X1395871D01*
G01X1402745Y399723D02*
X1402998Y399973D01*
X1403188Y400389D01*
X1403315Y400973D01*
X1403188Y401473D01*
X1402935Y401806D01*
X1402491Y402056D01*
X1400781D01*
Y397056D01*
X1402871D01*
X1403315Y397389D01*
X1403568Y397889D01*
X1403695Y398473D01*
X1403568Y399056D01*
X1403188Y399556D01*
X1402745Y399723D01*
X1400781D01*
G01X1405945Y402056D02*
Y398473D01*
X1406198Y397723D01*
X1406705Y397223D01*
X1407338Y397056D01*
X1407971Y397223D01*
X1408478Y397723D01*
X1408731Y398473D01*
Y402056D01*
G01X1412818Y399556D02*
X1414085D01*
Y398056D01*
X1413705Y397556D01*
X1413261Y397223D01*
X1412628Y397056D01*
X1411995Y397223D01*
X1411551Y397556D01*
X1411171Y398056D01*
X1410918Y398639D01*
X1410791Y399306D01*
Y399889D01*
X1410918Y400389D01*
X1411171Y400973D01*
X1411551Y401473D01*
X1411931Y401806D01*
X1412438Y402056D01*
X1412881D01*
X1413388Y401889D01*
X1413768Y401556D01*
G01X1421371Y402056D02*
Y397056D01*
X1423905D01*
G01X1429005D02*
X1426471D01*
Y402056D01*
X1429005D01*
G01X1427991Y399639D02*
X1426471D01*
G01X1431445Y397056D02*
Y402056D01*
X1432711D01*
X1433218Y401806D01*
X1433598Y401473D01*
X1433915Y400973D01*
X1434168Y400389D01*
X1434231Y399556D01*
X1434168Y398723D01*
X1433915Y398139D01*
X1433598Y397639D01*
X1433218Y397306D01*
X1432711Y397056D01*
X1431445D01*
G01X1436038Y395389D02*
X1439838D01*
G01X1444431Y401639D02*
X1444051Y401889D01*
X1443608Y402056D01*
X1443101D01*
X1442531Y401806D01*
X1442088Y401389D01*
X1441771Y400889D01*
X1441518Y400056D01*
X1441455Y399306D01*
X1441581Y398556D01*
X1441771Y398056D01*
X1442151Y397556D01*
X1442595Y397223D01*
X1443038Y397056D01*
X1443481D01*
X1443925Y397223D01*
X1444305Y397473D01*
X1444621Y397806D01*
G01X1448138Y402056D02*
Y397056D01*
G01X1446681Y402056D02*
X1449595D01*
G01X1451971Y397056D02*
Y402056D01*
X1453555D01*
X1454061Y401806D01*
X1454378Y401473D01*
X1454505Y400806D01*
X1454378Y400139D01*
X1453998Y399723D01*
X1453555Y399473D01*
X1451971D01*
G01X1453555D02*
X1454505Y397056D01*
G01X1457071Y402056D02*
Y397056D01*
X1459605D01*
G01X1365771Y405156D02*
Y410156D01*
X1367291D01*
X1367798Y409906D01*
X1368178Y409323D01*
X1368305Y408656D01*
X1368178Y407989D01*
X1367861Y407489D01*
X1367291Y407239D01*
X1365771D01*
G01X1370238Y410156D02*
X1371125Y405156D01*
X1372138Y410156D01*
X1373151Y405156D01*
X1374038Y410156D01*
G01X1375845Y405156D02*
Y410156D01*
X1377111D01*
X1377618Y409906D01*
X1377998Y409573D01*
X1378315Y409073D01*
X1378568Y408489D01*
X1378631Y407656D01*
X1378568Y406823D01*
X1378315Y406239D01*
X1377998Y405739D01*
X1377618Y405406D01*
X1377111Y405156D01*
X1375845D01*
G01X1388831Y409739D02*
X1388451Y409989D01*
X1388008Y410156D01*
X1387501D01*
X1386931Y409906D01*
X1386488Y409489D01*
X1386171Y408989D01*
X1385918Y408156D01*
X1385855Y407406D01*
X1385981Y406656D01*
X1386171Y406156D01*
X1386551Y405656D01*
X1386995Y405323D01*
X1387438Y405156D01*
X1387881D01*
X1388325Y405323D01*
X1388705Y405573D01*
X1389021Y405906D01*
G01X1391271Y410156D02*
Y405156D01*
X1393805D01*
G01X1396371D02*
Y410156D01*
X1397955D01*
X1398461Y409906D01*
X1398778Y409573D01*
X1398905Y408906D01*
X1398778Y408239D01*
X1398398Y407823D01*
X1397955Y407573D01*
X1396371D01*
G01X1397955D02*
X1398905Y405156D01*
G01X1363820Y403600D02*
X1364320D01*
G01X1363820Y394600D02*
Y403600D01*
G01X1364320D02*
X1611820D01*
G01X1363820D02*
Y412600D01*
G01X1611820Y403600D02*
X1363820D01*
G01X1611820Y394600D02*
X1363820D01*
G01D02*
X1364320D01*
G01X1367931Y418839D02*
X1367551Y419089D01*
X1367108Y419256D01*
X1366601D01*
X1366031Y419006D01*
X1365588Y418589D01*
X1365271Y418089D01*
X1365018Y417256D01*
X1364955Y416506D01*
X1365081Y415756D01*
X1365271Y415256D01*
X1365651Y414756D01*
X1366095Y414423D01*
X1366538Y414256D01*
X1366981D01*
X1367425Y414423D01*
X1367805Y414673D01*
X1368121Y415006D01*
G01X1370371Y414256D02*
Y419256D01*
X1371891D01*
X1372398Y419006D01*
X1372778Y418423D01*
X1372905Y417756D01*
X1372778Y417089D01*
X1372461Y416589D01*
X1371891Y416339D01*
X1370371D01*
G01X1375345Y419256D02*
Y415673D01*
X1375598Y414923D01*
X1376105Y414423D01*
X1376738Y414256D01*
X1377371Y414423D01*
X1377878Y414923D01*
X1378131Y415673D01*
Y419256D01*
G01X1381838Y414256D02*
Y419256D01*
X1381078Y418256D01*
G01Y414256D02*
X1382598D01*
G01X1390771D02*
Y419256D01*
X1392291D01*
X1392798Y419006D01*
X1393178Y418423D01*
X1393305Y417756D01*
X1393178Y417089D01*
X1392861Y416589D01*
X1392291Y416339D01*
X1390771D01*
G01X1395871Y414256D02*
Y419256D01*
X1397455D01*
X1397961Y419006D01*
X1398278Y418673D01*
X1398405Y418006D01*
X1398278Y417339D01*
X1397898Y416923D01*
X1397455Y416673D01*
X1395871D01*
G01X1397455D02*
X1398405Y414256D01*
G01X1400908Y414923D02*
X1401415Y414506D01*
X1401985Y414256D01*
X1402491D01*
X1402998Y414506D01*
X1403378Y414923D01*
X1403568Y415506D01*
X1403441Y416089D01*
X1403125Y416589D01*
X1402555Y416923D01*
X1401795Y417089D01*
X1401351Y417423D01*
X1401161Y418006D01*
X1401288Y418589D01*
X1401605Y419006D01*
X1402048Y419256D01*
X1402491D01*
X1402935Y419089D01*
X1403315Y418673D01*
G01X1405881Y414256D02*
Y419256D01*
X1408795Y414256D01*
Y419256D01*
G01X1412438D02*
Y414256D01*
G01X1410981Y419256D02*
X1413895D01*
G01X1424031Y418839D02*
X1423651Y419089D01*
X1423208Y419256D01*
X1422701D01*
X1422131Y419006D01*
X1421688Y418589D01*
X1421371Y418089D01*
X1421118Y417256D01*
X1421055Y416506D01*
X1421181Y415756D01*
X1421371Y415256D01*
X1421751Y414756D01*
X1422195Y414423D01*
X1422638Y414256D01*
X1423081D01*
X1423525Y414423D01*
X1423905Y414673D01*
X1424221Y415006D01*
G01X1427738Y419256D02*
Y414256D01*
G01X1426281Y419256D02*
X1429195D01*
G01X1431571Y414256D02*
Y419256D01*
X1433155D01*
X1433661Y419006D01*
X1433978Y418673D01*
X1434105Y418006D01*
X1433978Y417339D01*
X1433598Y416923D01*
X1433155Y416673D01*
X1431571D01*
G01X1433155D02*
X1434105Y414256D01*
G01X1436671Y419256D02*
Y414256D01*
X1439205D01*
G01X1363820Y412600D02*
Y421600D01*
G01X1611820Y412600D02*
X1363820D01*
G01D02*
X1364320D01*
G01D02*
X1611820D01*
G01X1367045Y436123D02*
X1367298Y436373D01*
X1367488Y436789D01*
X1367615Y437373D01*
X1367488Y437873D01*
X1367235Y438206D01*
X1366791Y438456D01*
X1365081D01*
Y433456D01*
X1367171D01*
X1367615Y433789D01*
X1367868Y434289D01*
X1367995Y434873D01*
X1367868Y435456D01*
X1367488Y435956D01*
X1367045Y436123D01*
X1365081D01*
G01X1370878Y438456D02*
X1372398D01*
G01X1371638D02*
Y433456D01*
G01X1370878D02*
X1372398D01*
G01X1376738D02*
X1376231Y433539D01*
X1375788Y433873D01*
X1375408Y434373D01*
X1375155Y434956D01*
X1375028Y435623D01*
Y436289D01*
X1375155Y436956D01*
X1375408Y437539D01*
X1375788Y438039D01*
X1376231Y438373D01*
X1376738Y438456D01*
X1377245Y438373D01*
X1377688Y438039D01*
X1378068Y437539D01*
X1378321Y436956D01*
X1378448Y436289D01*
Y435623D01*
X1378321Y434956D01*
X1378068Y434373D01*
X1377688Y433873D01*
X1377245Y433539D01*
X1376738Y433456D01*
G01X1380508Y434123D02*
X1381015Y433706D01*
X1381585Y433456D01*
X1382091D01*
X1382598Y433706D01*
X1382978Y434123D01*
X1383168Y434706D01*
X1383041Y435289D01*
X1382725Y435789D01*
X1382155Y436123D01*
X1381395Y436289D01*
X1380951Y436623D01*
X1380761Y437206D01*
X1380888Y437789D01*
X1381205Y438206D01*
X1381648Y438456D01*
X1382091D01*
X1382535Y438289D01*
X1382915Y437873D01*
G01X1385038Y431789D02*
X1388838D01*
G01X1390645Y433456D02*
Y438456D01*
X1391911D01*
X1392418Y438206D01*
X1392798Y437873D01*
X1393115Y437373D01*
X1393368Y436789D01*
X1393431Y435956D01*
X1393368Y435123D01*
X1393115Y434539D01*
X1392798Y434039D01*
X1392418Y433706D01*
X1391911Y433456D01*
X1390645D01*
G01X1398405D02*
X1395871D01*
Y438456D01*
X1398405D01*
G01X1397391Y436039D02*
X1395871D01*
G01X1402745Y436123D02*
X1402998Y436373D01*
X1403188Y436789D01*
X1403315Y437373D01*
X1403188Y437873D01*
X1402935Y438206D01*
X1402491Y438456D01*
X1400781D01*
Y433456D01*
X1402871D01*
X1403315Y433789D01*
X1403568Y434289D01*
X1403695Y434873D01*
X1403568Y435456D01*
X1403188Y435956D01*
X1402745Y436123D01*
X1400781D01*
G01X1405945Y438456D02*
Y434873D01*
X1406198Y434123D01*
X1406705Y433623D01*
X1407338Y433456D01*
X1407971Y433623D01*
X1408478Y434123D01*
X1408731Y434873D01*
Y438456D01*
G01X1412818Y435956D02*
X1414085D01*
Y434456D01*
X1413705Y433956D01*
X1413261Y433623D01*
X1412628Y433456D01*
X1411995Y433623D01*
X1411551Y433956D01*
X1411171Y434456D01*
X1410918Y435039D01*
X1410791Y435706D01*
Y436289D01*
X1410918Y436789D01*
X1411171Y437373D01*
X1411551Y437873D01*
X1411931Y438206D01*
X1412438Y438456D01*
X1412881D01*
X1413388Y438289D01*
X1413768Y437956D01*
G01X1420991Y433456D02*
Y438456D01*
X1422638Y434289D01*
X1424285Y438456D01*
Y433456D01*
G01X1427738D02*
X1427231Y433539D01*
X1426788Y433873D01*
X1426408Y434373D01*
X1426155Y434956D01*
X1426028Y435623D01*
Y436289D01*
X1426155Y436956D01*
X1426408Y437539D01*
X1426788Y438039D01*
X1427231Y438373D01*
X1427738Y438456D01*
X1428245Y438373D01*
X1428688Y438039D01*
X1429068Y437539D01*
X1429321Y436956D01*
X1429448Y436289D01*
Y435623D01*
X1429321Y434956D01*
X1429068Y434373D01*
X1428688Y433873D01*
X1428245Y433539D01*
X1427738Y433456D01*
G01X1431445D02*
Y438456D01*
X1432711D01*
X1433218Y438206D01*
X1433598Y437873D01*
X1433915Y437373D01*
X1434168Y436789D01*
X1434231Y435956D01*
X1434168Y435123D01*
X1433915Y434539D01*
X1433598Y434039D01*
X1433218Y433706D01*
X1432711Y433456D01*
X1431445D01*
G01X1439205D02*
X1436671D01*
Y438456D01*
X1439205D01*
G01X1438191Y436039D02*
X1436671D01*
G01X1367931Y427939D02*
X1367551Y428189D01*
X1367108Y428356D01*
X1366601D01*
X1366031Y428106D01*
X1365588Y427689D01*
X1365271Y427189D01*
X1365018Y426356D01*
X1364955Y425606D01*
X1365081Y424856D01*
X1365271Y424356D01*
X1365651Y423856D01*
X1366095Y423523D01*
X1366538Y423356D01*
X1366981D01*
X1367425Y423523D01*
X1367805Y423773D01*
X1368121Y424106D01*
G01X1370371Y423356D02*
Y428356D01*
X1371891D01*
X1372398Y428106D01*
X1372778Y427523D01*
X1372905Y426856D01*
X1372778Y426189D01*
X1372461Y425689D01*
X1371891Y425439D01*
X1370371D01*
G01X1375345Y428356D02*
Y424773D01*
X1375598Y424023D01*
X1376105Y423523D01*
X1376738Y423356D01*
X1377371Y423523D01*
X1377878Y424023D01*
X1378131Y424773D01*
Y428356D01*
G01X1381838D02*
X1381331Y428189D01*
X1380951Y427773D01*
X1380698Y427273D01*
X1380508Y426606D01*
X1380445Y425856D01*
X1380508Y425106D01*
X1380698Y424439D01*
X1380951Y423939D01*
X1381331Y423523D01*
X1381838Y423356D01*
X1382345Y423523D01*
X1382725Y423939D01*
X1382978Y424439D01*
X1383168Y425106D01*
X1383231Y425856D01*
X1383168Y426606D01*
X1382978Y427273D01*
X1382725Y427773D01*
X1382345Y428189D01*
X1381838Y428356D01*
G01X1390771Y423356D02*
Y428356D01*
X1392291D01*
X1392798Y428106D01*
X1393178Y427523D01*
X1393305Y426856D01*
X1393178Y426189D01*
X1392861Y425689D01*
X1392291Y425439D01*
X1390771D01*
G01X1395871Y423356D02*
Y428356D01*
X1397455D01*
X1397961Y428106D01*
X1398278Y427773D01*
X1398405Y427106D01*
X1398278Y426439D01*
X1397898Y426023D01*
X1397455Y425773D01*
X1395871D01*
G01X1397455D02*
X1398405Y423356D01*
G01X1400908Y424023D02*
X1401415Y423606D01*
X1401985Y423356D01*
X1402491D01*
X1402998Y423606D01*
X1403378Y424023D01*
X1403568Y424606D01*
X1403441Y425189D01*
X1403125Y425689D01*
X1402555Y426023D01*
X1401795Y426189D01*
X1401351Y426523D01*
X1401161Y427106D01*
X1401288Y427689D01*
X1401605Y428106D01*
X1402048Y428356D01*
X1402491D01*
X1402935Y428189D01*
X1403315Y427773D01*
G01X1405881Y423356D02*
Y428356D01*
X1408795Y423356D01*
Y428356D01*
G01X1412438D02*
Y423356D01*
G01X1410981Y428356D02*
X1413895D01*
G01X1424031Y427939D02*
X1423651Y428189D01*
X1423208Y428356D01*
X1422701D01*
X1422131Y428106D01*
X1421688Y427689D01*
X1421371Y427189D01*
X1421118Y426356D01*
X1421055Y425606D01*
X1421181Y424856D01*
X1421371Y424356D01*
X1421751Y423856D01*
X1422195Y423523D01*
X1422638Y423356D01*
X1423081D01*
X1423525Y423523D01*
X1423905Y423773D01*
X1424221Y424106D01*
G01X1427738Y428356D02*
Y423356D01*
G01X1426281Y428356D02*
X1429195D01*
G01X1431571Y423356D02*
Y428356D01*
X1433155D01*
X1433661Y428106D01*
X1433978Y427773D01*
X1434105Y427106D01*
X1433978Y426439D01*
X1433598Y426023D01*
X1433155Y425773D01*
X1431571D01*
G01X1433155D02*
X1434105Y423356D01*
G01X1436671Y428356D02*
Y423356D01*
X1439205D01*
G01X1363820Y430600D02*
Y439600D01*
G01X1611820Y430600D02*
X1363820D01*
G01D02*
X1364320D01*
G01X1363820Y421600D02*
Y430600D01*
G01X1364320D02*
X1611820D01*
G01X1363820Y421600D02*
X1364320D01*
G01D02*
X1611820D01*
G01D02*
X1363820D01*
G01X1365335Y441556D02*
Y446556D01*
X1367741D01*
G01X1366855Y444139D02*
X1365335D01*
G01X1370371Y441556D02*
Y446556D01*
X1371891D01*
X1372398Y446306D01*
X1372778Y445723D01*
X1372905Y445056D01*
X1372778Y444389D01*
X1372461Y443889D01*
X1371891Y443639D01*
X1370371D01*
G01X1377118Y444056D02*
X1378385D01*
Y442556D01*
X1378005Y442056D01*
X1377561Y441723D01*
X1376928Y441556D01*
X1376295Y441723D01*
X1375851Y442056D01*
X1375471Y442556D01*
X1375218Y443139D01*
X1375091Y443806D01*
Y444389D01*
X1375218Y444889D01*
X1375471Y445473D01*
X1375851Y445973D01*
X1376231Y446306D01*
X1376738Y446556D01*
X1377181D01*
X1377688Y446389D01*
X1378068Y446056D01*
G01X1380255Y441556D02*
X1381838Y446556D01*
X1383421Y441556D01*
G01X1382851Y443306D02*
X1380825D01*
G01X1390645Y441556D02*
Y446556D01*
X1391911D01*
X1392418Y446306D01*
X1392798Y445973D01*
X1393115Y445473D01*
X1393368Y444889D01*
X1393431Y444056D01*
X1393368Y443223D01*
X1393115Y442639D01*
X1392798Y442139D01*
X1392418Y441806D01*
X1391911Y441556D01*
X1390645D01*
G01X1398405D02*
X1395871D01*
Y446556D01*
X1398405D01*
G01X1397391Y444139D02*
X1395871D01*
G01X1402745Y444223D02*
X1402998Y444473D01*
X1403188Y444889D01*
X1403315Y445473D01*
X1403188Y445973D01*
X1402935Y446306D01*
X1402491Y446556D01*
X1400781D01*
Y441556D01*
X1402871D01*
X1403315Y441889D01*
X1403568Y442389D01*
X1403695Y442973D01*
X1403568Y443556D01*
X1403188Y444056D01*
X1402745Y444223D01*
X1400781D01*
G01X1405945Y446556D02*
Y442973D01*
X1406198Y442223D01*
X1406705Y441723D01*
X1407338Y441556D01*
X1407971Y441723D01*
X1408478Y442223D01*
X1408731Y442973D01*
Y446556D01*
G01X1412818Y444056D02*
X1414085D01*
Y442556D01*
X1413705Y442056D01*
X1413261Y441723D01*
X1412628Y441556D01*
X1411995Y441723D01*
X1411551Y442056D01*
X1411171Y442556D01*
X1410918Y443139D01*
X1410791Y443806D01*
Y444389D01*
X1410918Y444889D01*
X1411171Y445473D01*
X1411551Y445973D01*
X1411931Y446306D01*
X1412438Y446556D01*
X1412881D01*
X1413388Y446389D01*
X1413768Y446056D01*
G01X1421308Y442223D02*
X1421815Y441806D01*
X1422385Y441556D01*
X1422891D01*
X1423398Y441806D01*
X1423778Y442223D01*
X1423968Y442806D01*
X1423841Y443389D01*
X1423525Y443889D01*
X1422955Y444223D01*
X1422195Y444389D01*
X1421751Y444723D01*
X1421561Y445306D01*
X1421688Y445889D01*
X1422005Y446306D01*
X1422448Y446556D01*
X1422891D01*
X1423335Y446389D01*
X1423715Y445973D01*
G01X1425838Y446556D02*
X1426725Y441556D01*
X1427738Y446556D01*
X1428751Y441556D01*
X1429638Y446556D01*
G01X1436608Y442223D02*
X1437115Y441806D01*
X1437685Y441556D01*
X1438191D01*
X1438698Y441806D01*
X1439078Y442223D01*
X1439268Y442806D01*
X1439141Y443389D01*
X1438825Y443889D01*
X1438255Y444223D01*
X1437495Y444389D01*
X1437051Y444723D01*
X1436861Y445306D01*
X1436988Y445889D01*
X1437305Y446306D01*
X1437748Y446556D01*
X1438191D01*
X1438635Y446389D01*
X1439015Y445973D01*
G01X1441771Y441556D02*
Y446556D01*
X1443291D01*
X1443798Y446306D01*
X1444178Y445723D01*
X1444305Y445056D01*
X1444178Y444389D01*
X1443861Y443889D01*
X1443291Y443639D01*
X1441771D01*
G01X1446555Y441556D02*
X1448138Y446556D01*
X1449721Y441556D01*
G01X1449151Y443306D02*
X1447125D01*
G01X1451971Y441556D02*
Y446556D01*
X1453555D01*
X1454061Y446306D01*
X1454378Y445973D01*
X1454505Y445306D01*
X1454378Y444639D01*
X1453998Y444223D01*
X1453555Y443973D01*
X1451971D01*
G01X1453555D02*
X1454505Y441556D01*
G01X1459605D02*
X1457071D01*
Y446556D01*
X1459605D01*
G01X1458591Y444139D02*
X1457071D01*
G01X1363820Y448600D02*
X1364320D01*
G01X1363820Y439600D02*
Y448600D01*
G01X1364320D02*
X1611820D01*
G01X1363820D02*
Y457600D01*
G01X1611820Y448600D02*
X1363820D01*
G01X1611820Y439600D02*
X1363820D01*
G01D02*
X1364320D01*
G01D02*
X1611820D01*
G01X1367045Y462923D02*
X1367298Y463173D01*
X1367488Y463589D01*
X1367615Y464173D01*
X1367488Y464673D01*
X1367235Y465006D01*
X1366791Y465256D01*
X1365081D01*
Y460256D01*
X1367171D01*
X1367615Y460589D01*
X1367868Y461089D01*
X1367995Y461673D01*
X1367868Y462256D01*
X1367488Y462756D01*
X1367045Y462923D01*
X1365081D01*
G01X1369991Y460256D02*
Y465256D01*
X1371638Y461089D01*
X1373285Y465256D01*
Y460256D01*
G01X1378131Y464839D02*
X1377751Y465089D01*
X1377308Y465256D01*
X1376801D01*
X1376231Y465006D01*
X1375788Y464589D01*
X1375471Y464089D01*
X1375218Y463256D01*
X1375155Y462506D01*
X1375281Y461756D01*
X1375471Y461256D01*
X1375851Y460756D01*
X1376295Y460423D01*
X1376738Y460256D01*
X1377181D01*
X1377625Y460423D01*
X1378005Y460673D01*
X1378321Y461006D01*
G01X1379938Y458589D02*
X1383738D01*
G01X1385671Y461256D02*
X1385988Y460756D01*
X1386368Y460423D01*
X1386811Y460256D01*
X1387318Y460423D01*
X1387698Y460756D01*
X1388078Y461256D01*
X1388205Y461923D01*
Y465256D01*
G01X1392038D02*
Y460256D01*
G01X1390581Y465256D02*
X1393495D01*
G01X1395555Y460256D02*
X1397138Y465256D01*
X1398721Y460256D01*
G01X1398151Y462006D02*
X1396125D01*
G01X1402618Y462756D02*
X1403885D01*
Y461256D01*
X1403505Y460756D01*
X1403061Y460423D01*
X1402428Y460256D01*
X1401795Y460423D01*
X1401351Y460756D01*
X1400971Y461256D01*
X1400718Y461839D01*
X1400591Y462506D01*
Y463089D01*
X1400718Y463589D01*
X1400971Y464173D01*
X1401351Y464673D01*
X1401731Y465006D01*
X1402238Y465256D01*
X1402681D01*
X1403188Y465089D01*
X1403568Y464756D01*
G01X1405438Y458589D02*
X1409238D01*
G01X1411108Y460923D02*
X1411615Y460506D01*
X1412185Y460256D01*
X1412691D01*
X1413198Y460506D01*
X1413578Y460923D01*
X1413768Y461506D01*
X1413641Y462089D01*
X1413325Y462589D01*
X1412755Y462923D01*
X1411995Y463089D01*
X1411551Y463423D01*
X1411361Y464006D01*
X1411488Y464589D01*
X1411805Y465006D01*
X1412248Y465256D01*
X1412691D01*
X1413135Y465089D01*
X1413515Y464673D01*
G01X1418805Y460256D02*
X1416271D01*
Y465256D01*
X1418805D01*
G01X1417791Y462839D02*
X1416271D01*
G01X1421371Y465256D02*
Y460256D01*
X1423905D01*
G01X1367045Y453323D02*
X1367298Y453573D01*
X1367488Y453989D01*
X1367615Y454573D01*
X1367488Y455073D01*
X1367235Y455406D01*
X1366791Y455656D01*
X1365081D01*
Y450656D01*
X1367171D01*
X1367615Y450989D01*
X1367868Y451489D01*
X1367995Y452073D01*
X1367868Y452656D01*
X1367488Y453156D01*
X1367045Y453323D01*
X1365081D01*
G01X1370878Y455656D02*
X1372398D01*
G01X1371638D02*
Y450656D01*
G01X1370878D02*
X1372398D01*
G01X1376738D02*
X1376231Y450739D01*
X1375788Y451073D01*
X1375408Y451573D01*
X1375155Y452156D01*
X1375028Y452823D01*
Y453489D01*
X1375155Y454156D01*
X1375408Y454739D01*
X1375788Y455239D01*
X1376231Y455573D01*
X1376738Y455656D01*
X1377245Y455573D01*
X1377688Y455239D01*
X1378068Y454739D01*
X1378321Y454156D01*
X1378448Y453489D01*
Y452823D01*
X1378321Y452156D01*
X1378068Y451573D01*
X1377688Y451073D01*
X1377245Y450739D01*
X1376738Y450656D01*
G01X1380508Y451323D02*
X1381015Y450906D01*
X1381585Y450656D01*
X1382091D01*
X1382598Y450906D01*
X1382978Y451323D01*
X1383168Y451906D01*
X1383041Y452489D01*
X1382725Y452989D01*
X1382155Y453323D01*
X1381395Y453489D01*
X1380951Y453823D01*
X1380761Y454406D01*
X1380888Y454989D01*
X1381205Y455406D01*
X1381648Y455656D01*
X1382091D01*
X1382535Y455489D01*
X1382915Y455073D01*
G01X1390645Y455656D02*
Y452073D01*
X1390898Y451323D01*
X1391405Y450823D01*
X1392038Y450656D01*
X1392671Y450823D01*
X1393178Y451323D01*
X1393431Y452073D01*
Y455656D01*
G01X1395808Y451323D02*
X1396315Y450906D01*
X1396885Y450656D01*
X1397391D01*
X1397898Y450906D01*
X1398278Y451323D01*
X1398468Y451906D01*
X1398341Y452489D01*
X1398025Y452989D01*
X1397455Y453323D01*
X1396695Y453489D01*
X1396251Y453823D01*
X1396061Y454406D01*
X1396188Y454989D01*
X1396505Y455406D01*
X1396948Y455656D01*
X1397391D01*
X1397835Y455489D01*
X1398215Y455073D01*
G01X1402745Y453323D02*
X1402998Y453573D01*
X1403188Y453989D01*
X1403315Y454573D01*
X1403188Y455073D01*
X1402935Y455406D01*
X1402491Y455656D01*
X1400781D01*
Y450656D01*
X1402871D01*
X1403315Y450989D01*
X1403568Y451489D01*
X1403695Y452073D01*
X1403568Y452656D01*
X1403188Y453156D01*
X1402745Y453323D01*
X1400781D01*
G01X1411171Y450656D02*
Y455656D01*
X1412755D01*
X1413261Y455406D01*
X1413578Y455073D01*
X1413705Y454406D01*
X1413578Y453739D01*
X1413198Y453323D01*
X1412755Y453073D01*
X1411171D01*
G01X1412755D02*
X1413705Y450656D01*
G01X1418931Y455239D02*
X1418551Y455489D01*
X1418108Y455656D01*
X1417601D01*
X1417031Y455406D01*
X1416588Y454989D01*
X1416271Y454489D01*
X1416018Y453656D01*
X1415955Y452906D01*
X1416081Y452156D01*
X1416271Y451656D01*
X1416651Y451156D01*
X1417095Y450823D01*
X1417538Y450656D01*
X1417981D01*
X1418425Y450823D01*
X1418805Y451073D01*
X1419121Y451406D01*
G01X1421055Y455656D02*
X1422638Y450656D01*
X1424221Y455656D01*
G01X1427738Y450656D02*
Y452906D01*
X1426471Y455656D01*
G01X1429005D02*
X1427738Y452906D01*
G01X1363820Y457600D02*
Y466600D01*
G01X1611820Y457600D02*
X1363820D01*
G01D02*
X1364320D01*
G01D02*
X1611820D01*
G01X1365778Y483456D02*
X1367298D01*
G01X1366538D02*
Y478456D01*
G01X1365778D02*
X1367298D01*
G01X1370245Y479456D02*
X1370625Y478873D01*
X1371131Y478539D01*
X1371701Y478456D01*
X1372208Y478539D01*
X1372715Y478956D01*
X1373031Y479456D01*
X1373095Y479956D01*
X1372968Y480539D01*
X1372525Y480956D01*
X1372081Y481123D01*
X1371511D01*
G01X1372081D02*
X1372461Y481373D01*
X1372778Y481789D01*
X1372905Y482289D01*
X1372778Y482789D01*
X1372461Y483206D01*
X1371891Y483456D01*
X1371321Y483373D01*
X1370751Y483039D01*
G01X1378131D02*
X1377751Y483289D01*
X1377308Y483456D01*
X1376801D01*
X1376231Y483206D01*
X1375788Y482789D01*
X1375471Y482289D01*
X1375218Y481456D01*
X1375155Y480706D01*
X1375281Y479956D01*
X1375471Y479456D01*
X1375851Y478956D01*
X1376295Y478623D01*
X1376738Y478456D01*
X1377181D01*
X1377625Y478623D01*
X1378005Y478873D01*
X1378321Y479206D01*
G01X1379938Y476789D02*
X1383738D01*
G01X1385608Y479123D02*
X1386115Y478706D01*
X1386685Y478456D01*
X1387191D01*
X1387698Y478706D01*
X1388078Y479123D01*
X1388268Y479706D01*
X1388141Y480289D01*
X1387825Y480789D01*
X1387255Y481123D01*
X1386495Y481289D01*
X1386051Y481623D01*
X1385861Y482206D01*
X1385988Y482789D01*
X1386305Y483206D01*
X1386748Y483456D01*
X1387191D01*
X1387635Y483289D01*
X1388015Y482873D01*
G01X1390771Y478456D02*
Y483456D01*
X1392291D01*
X1392798Y483206D01*
X1393178Y482623D01*
X1393305Y481956D01*
X1393178Y481289D01*
X1392861Y480789D01*
X1392291Y480539D01*
X1390771D01*
G01X1395745Y478456D02*
Y483456D01*
X1397011D01*
X1397518Y483206D01*
X1397898Y482873D01*
X1398215Y482373D01*
X1398468Y481789D01*
X1398531Y480956D01*
X1398468Y480123D01*
X1398215Y479539D01*
X1397898Y479039D01*
X1397518Y478706D01*
X1397011Y478456D01*
X1395745D01*
G01X1400338Y476789D02*
X1404138D01*
G01X1408731Y483039D02*
X1408351Y483289D01*
X1407908Y483456D01*
X1407401D01*
X1406831Y483206D01*
X1406388Y482789D01*
X1406071Y482289D01*
X1405818Y481456D01*
X1405755Y480706D01*
X1405881Y479956D01*
X1406071Y479456D01*
X1406451Y478956D01*
X1406895Y478623D01*
X1407338Y478456D01*
X1407781D01*
X1408225Y478623D01*
X1408605Y478873D01*
X1408921Y479206D01*
G01X1412438Y483456D02*
Y478456D01*
G01X1410981Y483456D02*
X1413895D01*
G01X1416271D02*
Y478456D01*
X1418805D01*
G01X1365335Y469356D02*
Y474356D01*
X1367741D01*
G01X1366855Y471939D02*
X1365335D01*
G01X1371638Y469356D02*
X1371131Y469439D01*
X1370688Y469773D01*
X1370308Y470273D01*
X1370055Y470856D01*
X1369928Y471523D01*
Y472189D01*
X1370055Y472856D01*
X1370308Y473439D01*
X1370688Y473939D01*
X1371131Y474273D01*
X1371638Y474356D01*
X1372145Y474273D01*
X1372588Y473939D01*
X1372968Y473439D01*
X1373221Y472856D01*
X1373348Y472189D01*
Y471523D01*
X1373221Y470856D01*
X1372968Y470273D01*
X1372588Y469773D01*
X1372145Y469439D01*
X1371638Y469356D01*
G01X1375471D02*
Y474356D01*
X1377055D01*
X1377561Y474106D01*
X1377878Y473773D01*
X1378005Y473106D01*
X1377878Y472439D01*
X1377498Y472023D01*
X1377055Y471773D01*
X1375471D01*
G01X1377055D02*
X1378005Y469356D01*
G01X1383231Y473939D02*
X1382851Y474189D01*
X1382408Y474356D01*
X1381901D01*
X1381331Y474106D01*
X1380888Y473689D01*
X1380571Y473189D01*
X1380318Y472356D01*
X1380255Y471606D01*
X1380381Y470856D01*
X1380571Y470356D01*
X1380951Y469856D01*
X1381395Y469523D01*
X1381838Y469356D01*
X1382281D01*
X1382725Y469523D01*
X1383105Y469773D01*
X1383421Y470106D01*
G01X1388205Y469356D02*
X1385671D01*
Y474356D01*
X1388205D01*
G01X1387191Y471939D02*
X1385671D01*
G01X1390138Y467689D02*
X1393938D01*
G01X1395871Y469356D02*
Y474356D01*
X1397391D01*
X1397898Y474106D01*
X1398278Y473523D01*
X1398405Y472856D01*
X1398278Y472189D01*
X1397961Y471689D01*
X1397391Y471439D01*
X1395871D01*
G01X1400338Y474356D02*
X1401225Y469356D01*
X1402238Y474356D01*
X1403251Y469356D01*
X1404138Y474356D01*
G01X1406071Y469356D02*
Y474356D01*
X1407655D01*
X1408161Y474106D01*
X1408478Y473773D01*
X1408605Y473106D01*
X1408478Y472439D01*
X1408098Y472023D01*
X1407655Y471773D01*
X1406071D01*
G01X1407655D02*
X1408605Y469356D01*
G01X1410538Y467689D02*
X1414338D01*
G01X1417538Y469356D02*
X1417031Y469439D01*
X1416588Y469773D01*
X1416208Y470273D01*
X1415955Y470856D01*
X1415828Y471523D01*
Y472189D01*
X1415955Y472856D01*
X1416208Y473439D01*
X1416588Y473939D01*
X1417031Y474273D01*
X1417538Y474356D01*
X1418045Y474273D01*
X1418488Y473939D01*
X1418868Y473439D01*
X1419121Y472856D01*
X1419248Y472189D01*
Y471523D01*
X1419121Y470856D01*
X1418868Y470273D01*
X1418488Y469773D01*
X1418045Y469439D01*
X1417538Y469356D01*
G01X1421181D02*
Y474356D01*
X1424095Y469356D01*
Y474356D01*
G01X1363820Y475600D02*
Y484600D01*
G01X1611820Y475600D02*
X1363820D01*
G01D02*
X1364320D01*
G01X1363820Y466600D02*
Y475600D01*
G01X1364320D02*
X1611820D01*
G01X1363820Y466600D02*
X1364320D01*
G01D02*
X1611820D01*
G01D02*
X1363820D01*
G01X1366335Y486556D02*
Y491556D01*
X1368741D01*
G01X1367855Y489139D02*
X1366335D01*
G01X1371245Y491556D02*
Y487973D01*
X1371498Y487223D01*
X1372005Y486723D01*
X1372638Y486556D01*
X1373271Y486723D01*
X1373778Y487223D01*
X1374031Y487973D01*
Y491556D01*
G01X1376281Y486556D02*
Y491556D01*
X1379195Y486556D01*
Y491556D01*
G01X1384231Y491139D02*
X1383851Y491389D01*
X1383408Y491556D01*
X1382901D01*
X1382331Y491306D01*
X1381888Y490889D01*
X1381571Y490389D01*
X1381318Y489556D01*
X1381255Y488806D01*
X1381381Y488056D01*
X1381571Y487556D01*
X1381951Y487056D01*
X1382395Y486723D01*
X1382838Y486556D01*
X1383281D01*
X1383725Y486723D01*
X1384105Y486973D01*
X1384421Y487306D01*
G01X1387938Y491556D02*
Y486556D01*
G01X1386481Y491556D02*
X1389395D01*
G01X1392278D02*
X1393798D01*
G01X1393038D02*
Y486556D01*
G01X1392278D02*
X1393798D01*
G01X1398138D02*
X1397631Y486639D01*
X1397188Y486973D01*
X1396808Y487473D01*
X1396555Y488056D01*
X1396428Y488723D01*
Y489389D01*
X1396555Y490056D01*
X1396808Y490639D01*
X1397188Y491139D01*
X1397631Y491473D01*
X1398138Y491556D01*
X1398645Y491473D01*
X1399088Y491139D01*
X1399468Y490639D01*
X1399721Y490056D01*
X1399848Y489389D01*
Y488723D01*
X1399721Y488056D01*
X1399468Y487473D01*
X1399088Y486973D01*
X1398645Y486639D01*
X1398138Y486556D01*
G01X1401781D02*
Y491556D01*
X1404695Y486556D01*
Y491556D01*
G01X1363820Y484600D02*
Y493600D01*
G01X1611820Y484600D02*
X1363820D01*
G01D02*
X1364320D01*
G01D02*
X1611820D01*
G01X1363820Y502600D02*
X1364320D01*
G01X1363820Y493600D02*
Y502600D01*
G01X1611820Y493600D02*
X1363820D01*
G01X1364320Y502600D02*
X1611820D01*
G01X1363820Y493600D02*
X1364320D01*
G01D02*
X1611820D01*
G01X1377432Y564880D02*
Y569880D01*
X1378952D01*
X1379459Y569630D01*
X1379839Y569047D01*
X1379966Y568380D01*
X1379839Y567713D01*
X1379522Y567213D01*
X1378952Y566963D01*
X1377432D01*
G01X1382216Y569880D02*
X1383799Y564880D01*
X1385382Y569880D01*
G01X1387506Y564880D02*
Y569880D01*
X1388772D01*
X1389279Y569630D01*
X1389659Y569297D01*
X1389976Y568797D01*
X1390229Y568213D01*
X1390292Y567380D01*
X1390229Y566547D01*
X1389976Y565963D01*
X1389659Y565463D01*
X1389279Y565130D01*
X1388772Y564880D01*
X1387506D01*
G01X1392606D02*
Y569880D01*
X1393872D01*
X1394379Y569630D01*
X1394759Y569297D01*
X1395076Y568797D01*
X1395329Y568213D01*
X1395392Y567380D01*
X1395329Y566547D01*
X1395076Y565963D01*
X1394759Y565463D01*
X1394379Y565130D01*
X1393872Y564880D01*
X1392606D01*
G01X1400492Y569463D02*
X1400112Y569713D01*
X1399669Y569880D01*
X1399162D01*
X1398592Y569630D01*
X1398149Y569213D01*
X1397832Y568713D01*
X1397579Y567880D01*
X1397516Y567130D01*
X1397642Y566380D01*
X1397832Y565880D01*
X1398212Y565380D01*
X1398656Y565047D01*
X1399099Y564880D01*
X1399542D01*
X1399986Y565047D01*
X1400366Y565297D01*
X1400682Y565630D01*
G01X1402932Y564880D02*
Y569880D01*
X1404516D01*
X1405022Y569630D01*
X1405339Y569297D01*
X1405466Y568630D01*
X1405339Y567963D01*
X1404959Y567547D01*
X1404516Y567297D01*
X1402932D01*
G01X1404516D02*
X1405466Y564880D01*
G01X1412816Y569880D02*
X1414399Y564880D01*
X1415982Y569880D01*
G01X1418232Y564880D02*
Y569880D01*
X1419816D01*
X1420322Y569630D01*
X1420639Y569297D01*
X1420766Y568630D01*
X1420639Y567963D01*
X1420259Y567547D01*
X1419816Y567297D01*
X1418232D01*
G01X1419816D02*
X1420766Y564880D01*
G01X1428432D02*
Y569880D01*
X1429952D01*
X1430459Y569630D01*
X1430839Y569047D01*
X1430966Y568380D01*
X1430839Y567713D01*
X1430522Y567213D01*
X1429952Y566963D01*
X1428432D01*
G01X1433152Y564880D02*
Y569880D01*
X1434799Y565713D01*
X1436446Y569880D01*
Y564880D01*
G01X1440406Y567547D02*
X1440659Y567797D01*
X1440849Y568213D01*
X1440976Y568797D01*
X1440849Y569297D01*
X1440596Y569630D01*
X1440152Y569880D01*
X1438442D01*
Y564880D01*
X1440532D01*
X1440976Y565213D01*
X1441229Y565713D01*
X1441356Y566297D01*
X1441229Y566880D01*
X1440849Y567380D01*
X1440406Y567547D01*
X1438442D01*
G01X1443606Y569880D02*
Y566297D01*
X1443859Y565547D01*
X1444366Y565047D01*
X1444999Y564880D01*
X1445632Y565047D01*
X1446139Y565547D01*
X1446392Y566297D01*
Y569880D01*
G01X1448769Y565547D02*
X1449276Y565130D01*
X1449846Y564880D01*
X1450352D01*
X1450859Y565130D01*
X1451239Y565547D01*
X1451429Y566130D01*
X1451302Y566713D01*
X1450986Y567213D01*
X1450416Y567547D01*
X1449656Y567713D01*
X1449212Y568047D01*
X1449022Y568630D01*
X1449149Y569213D01*
X1449466Y569630D01*
X1449909Y569880D01*
X1450352D01*
X1450796Y569713D01*
X1451176Y569297D01*
G01X1376223Y570579D02*
Y563073D01*
X1452523D01*
Y571062D01*
X1376223D01*
Y570579D01*
G01X1381213Y612183D02*
X1378013D01*
G01D02*
Y618383D01*
G01X1377243Y615489D02*
Y612289D01*
G01D02*
X1371043D01*
G01D02*
Y615489D01*
G01X1378013Y618383D02*
X1381213D01*
G01X1371043Y615489D02*
X1377243D01*
G01X1367618Y619193D02*
Y612993D01*
G01D02*
X1364418D01*
G01D02*
Y619193D01*
G01D02*
X1367618D01*
G01X1378850Y622596D02*
X1377842D01*
G01X1378057Y646218D02*
X1378850D01*
G01X1383625Y649437D02*
X1378284D01*
G01Y692745D02*
X1383625D01*
G01X1365100Y1167638D02*
X1391200D01*
G01X1366854Y1260515D02*
Y1303823D01*
G01X1370212Y1279989D02*
Y1323297D01*
G01X1375553Y1279989D02*
X1370212D01*
G01X1364639Y1322685D02*
X1367839D01*
G01X1364639Y1316485D02*
Y1322685D01*
G01X1367839Y1316485D02*
X1364639D01*
G01X1367839Y1322685D02*
Y1316485D01*
G01X1373069Y1328097D02*
Y1324897D01*
G01X1366869Y1328097D02*
X1373069D01*
G01X1366869Y1324897D02*
Y1328097D01*
G01X1373069Y1324897D02*
X1366869D01*
G01X1374669Y1326514D02*
Y1329114D01*
G01X1375462Y1326514D02*
X1374669D01*
G01X1370212Y1323297D02*
X1375553D01*
G01X1368412Y1341418D02*
X1371612D01*
G01X1368412Y1335218D02*
Y1341418D01*
G01X1371612Y1335218D02*
X1368412D01*
G01X1371612Y1341418D02*
Y1335218D01*
G01X1371635Y1328397D02*
X1368435D01*
G01X1371635Y1334597D02*
Y1328397D01*
G01X1368435Y1334597D02*
X1371635D01*
G01X1368435Y1328397D02*
Y1334597D01*
G01X1374669Y1335725D02*
Y1337423D01*
G01X1365306Y1357315D02*
X1371506D01*
G01X1365306Y1354115D02*
Y1357315D01*
G01X1371506Y1354115D02*
X1365306D01*
G01X1371506Y1357315D02*
Y1354115D01*
G01X1375506Y1354349D02*
X1372306D01*
G01X1375506Y1360549D02*
Y1354349D01*
G01X1372306D02*
Y1360549D01*
G01X1371612Y1345718D02*
X1368412D01*
G01X1371612Y1351918D02*
Y1350300D01*
G01X1368412Y1351918D02*
X1371612D01*
G01X1368412Y1345718D02*
Y1351918D01*
G01X1371612Y1348100D02*
Y1345718D01*
G01X1376276Y1357243D02*
Y1360443D01*
G01X1382476Y1357243D02*
X1376276D01*
G01X1374669Y1350136D02*
X1375677D01*
G01X1374669Y1348282D02*
Y1350136D01*
G01X1372306Y1360549D02*
X1375506D01*
G01X1376276Y1360443D02*
X1382476D01*
G01X1378883Y1368500D02*
Y1371600D01*
X1379803D01*
X1380110Y1371445D01*
X1380340Y1371083D01*
X1380417Y1370670D01*
X1380340Y1370257D01*
X1380148Y1369947D01*
X1379803Y1369792D01*
X1378883D01*
G01X1381907Y1371600D02*
Y1369378D01*
X1382060Y1368913D01*
X1382367Y1368603D01*
X1382750Y1368500D01*
X1383133Y1368603D01*
X1383440Y1368913D01*
X1383593Y1369378D01*
Y1371600D01*
G01X1385850Y1368500D02*
Y1371600D01*
X1385390Y1370980D01*
G01Y1368500D02*
X1386310D01*
G01X1388950D02*
Y1371600D01*
X1388490Y1370980D01*
G01Y1368500D02*
X1389410D01*
G01X1377313Y1424136D02*
Y1437636D01*
G01X1373356Y1441599D02*
X1365856Y1443932D01*
X1373356Y1446265D01*
G01X1370731Y1445425D02*
Y1442439D01*
G01X1365856Y1451432D02*
X1366106Y1450685D01*
X1366731Y1450125D01*
X1367481Y1449752D01*
X1368481Y1449472D01*
X1369606Y1449379D01*
X1370731Y1449472D01*
X1371731Y1449752D01*
X1372481Y1450125D01*
X1373106Y1450685D01*
X1373356Y1451432D01*
X1373106Y1452179D01*
X1372481Y1452739D01*
X1371731Y1453112D01*
X1370731Y1453392D01*
X1369606Y1453485D01*
X1368481Y1453392D01*
X1367481Y1453112D01*
X1366731Y1452739D01*
X1366106Y1452179D01*
X1365856Y1451432D01*
G01X1377313Y1437636D02*
Y1451156D01*
G01Y1457636D02*
X1375125D01*
G01X1377313D02*
Y1455740D01*
G01X1375900Y1646023D02*
X1369300D01*
G01X1367322Y1657834D02*
Y1736118D01*
G01X1378154Y1671947D02*
X1375054D01*
Y1672867D01*
X1375209Y1673174D01*
X1375571Y1673404D01*
X1375984Y1673481D01*
X1376397Y1673404D01*
X1376707Y1673212D01*
X1376862Y1672867D01*
Y1671947D01*
G01X1378154Y1675047D02*
X1375054D01*
Y1676006D01*
X1375209Y1676312D01*
X1375416Y1676504D01*
X1375829Y1676581D01*
X1376242Y1676504D01*
X1376501Y1676274D01*
X1376656Y1676006D01*
Y1675047D01*
G01Y1676006D02*
X1378154Y1676581D01*
G01Y1679681D02*
Y1678147D01*
X1375054D01*
Y1679681D01*
G01X1376552Y1679067D02*
Y1678147D01*
G01X1377741Y1681209D02*
X1377999Y1681516D01*
X1378154Y1681861D01*
Y1682167D01*
X1377999Y1682474D01*
X1377741Y1682704D01*
X1377379Y1682819D01*
X1377017Y1682742D01*
X1376707Y1682551D01*
X1376501Y1682206D01*
X1376397Y1681746D01*
X1376191Y1681477D01*
X1375829Y1681362D01*
X1375467Y1681439D01*
X1375209Y1681631D01*
X1375054Y1681899D01*
Y1682167D01*
X1375157Y1682436D01*
X1375416Y1682666D01*
G01X1377741Y1684309D02*
X1377999Y1684616D01*
X1378154Y1684961D01*
Y1685267D01*
X1377999Y1685574D01*
X1377741Y1685804D01*
X1377379Y1685919D01*
X1377017Y1685842D01*
X1376707Y1685651D01*
X1376501Y1685306D01*
X1376397Y1684846D01*
X1376191Y1684577D01*
X1375829Y1684462D01*
X1375467Y1684539D01*
X1375209Y1684731D01*
X1375054Y1684999D01*
Y1685267D01*
X1375157Y1685536D01*
X1375416Y1685766D01*
G01X1377121Y1687716D02*
Y1688712D01*
G01X1378154Y1690586D02*
X1375054D01*
Y1692042D01*
G01X1376552Y1691506D02*
Y1690586D01*
G01X1375054Y1693954D02*
Y1694874D01*
G01Y1694414D02*
X1378154D01*
G01Y1693954D02*
Y1694874D01*
G01X1375054Y1697514D02*
X1378154D01*
G01X1375054Y1696632D02*
Y1698396D01*
G01X1372159Y1671913D02*
X1369059D01*
X1372159Y1673677D01*
X1369059D01*
G01X1372159Y1676522D02*
X1369059D01*
X1371642Y1677519D01*
X1369059Y1678516D01*
X1372159D01*
G01X1369059Y1681476D02*
X1372159D01*
Y1683010D01*
G01Y1686125D02*
X1369059D01*
G01Y1687581D02*
X1370971Y1686125D01*
G01X1372159Y1687811D02*
X1370092Y1686776D01*
G01X1369059Y1695957D02*
Y1696877D01*
G01Y1696417D02*
X1372159D01*
G01Y1695957D02*
Y1696877D01*
G01Y1700336D02*
X1369059D01*
G01Y1701946D02*
X1372159D01*
G01X1370609D02*
Y1700336D01*
G01X1371539Y1690925D02*
X1371849Y1691117D01*
X1372056Y1691347D01*
X1372159Y1691615D01*
X1372056Y1691922D01*
X1371849Y1692152D01*
X1371539Y1692382D01*
X1371126Y1692459D01*
X1369059D01*
G01X1370609Y1706096D02*
Y1706863D01*
X1371539D01*
X1371849Y1706633D01*
X1372056Y1706364D01*
X1372159Y1705981D01*
X1372056Y1705598D01*
X1371849Y1705329D01*
X1371539Y1705099D01*
X1371177Y1704946D01*
X1370764Y1704869D01*
X1370402D01*
X1370092Y1704946D01*
X1369731Y1705099D01*
X1369421Y1705329D01*
X1369214Y1705559D01*
X1369059Y1705866D01*
Y1706134D01*
X1369162Y1706441D01*
X1369369Y1706671D01*
G01X1372159Y1709862D02*
X1369059D01*
Y1711318D01*
G01X1370557Y1710782D02*
Y1709862D01*
G01X1372159Y1716081D02*
Y1714547D01*
X1369059D01*
Y1716081D01*
G01X1370557Y1715467D02*
Y1714547D01*
G01X1369317Y1725606D02*
X1369162Y1725376D01*
X1369059Y1725108D01*
Y1724801D01*
X1369214Y1724456D01*
X1369472Y1724188D01*
X1369782Y1723996D01*
X1370299Y1723843D01*
X1370764Y1723805D01*
X1371229Y1723881D01*
X1371539Y1723996D01*
X1371849Y1724226D01*
X1372056Y1724495D01*
X1372159Y1724763D01*
Y1725031D01*
X1372056Y1725300D01*
X1371901Y1725530D01*
X1371694Y1725721D01*
G01X1370506Y1729795D02*
X1370351Y1729948D01*
X1370092Y1730063D01*
X1369731Y1730140D01*
X1369421Y1730063D01*
X1369214Y1729910D01*
X1369059Y1729641D01*
Y1728606D01*
X1372159D01*
Y1729871D01*
X1371952Y1730140D01*
X1371642Y1730293D01*
X1371281Y1730370D01*
X1370919Y1730293D01*
X1370609Y1730063D01*
X1370506Y1729795D01*
Y1728606D01*
G01X1372159Y1719196D02*
X1369059D01*
Y1719962D01*
X1369214Y1720269D01*
X1369421Y1720499D01*
X1369731Y1720691D01*
X1370092Y1720844D01*
X1370609Y1720882D01*
X1371126Y1720844D01*
X1371487Y1720691D01*
X1371797Y1720499D01*
X1372004Y1720269D01*
X1372159Y1719962D01*
Y1719196D01*
G01X1385048Y56872D02*
X1382548D01*
X1383048Y56552D01*
G01X1385048D02*
Y57192D01*
G01X1382965Y58565D02*
X1382715Y58725D01*
X1382590Y58912D01*
X1382548Y59125D01*
X1382631Y59392D01*
X1382840Y59579D01*
X1383090Y59632D01*
X1383340Y59605D01*
X1383548Y59499D01*
X1383965Y58965D01*
X1384256Y58725D01*
X1384673Y58565D01*
X1385048Y58512D01*
Y59632D01*
G01X1382548Y60605D02*
X1385048Y61272D01*
X1382548Y61939D01*
G01X1385881Y62672D02*
Y64272D01*
G01X1385048Y65005D02*
X1382548Y65672D01*
X1385048Y66339D01*
G01X1384173Y66099D02*
Y65245D01*
G01X1382548Y67339D02*
X1385048D01*
Y68405D01*
G01X1382548Y69539D02*
X1385048D01*
Y70605D01*
G01X1385881Y71472D02*
Y73072D01*
G01X1385048Y73939D02*
X1382548D01*
Y74579D01*
X1382673Y74792D01*
X1382965Y74952D01*
X1383298Y75005D01*
X1383631Y74952D01*
X1383881Y74819D01*
X1384006Y74579D01*
Y73939D01*
G01X1382548Y75872D02*
X1385048Y76245D01*
X1382548Y76672D01*
X1385048Y77099D01*
X1382548Y77472D01*
G01X1385048Y78339D02*
X1382548D01*
Y79005D01*
X1382673Y79219D01*
X1382840Y79352D01*
X1383173Y79405D01*
X1383506Y79352D01*
X1383715Y79192D01*
X1383840Y79005D01*
Y78339D01*
G01Y79005D02*
X1385048Y79405D01*
G01Y81072D02*
X1385006Y80859D01*
X1384840Y80672D01*
X1384590Y80512D01*
X1384298Y80405D01*
X1383965Y80352D01*
X1383631D01*
X1383298Y80405D01*
X1383006Y80512D01*
X1382756Y80672D01*
X1382590Y80859D01*
X1382548Y81072D01*
X1382590Y81285D01*
X1382756Y81472D01*
X1383006Y81632D01*
X1383298Y81739D01*
X1383631Y81792D01*
X1383965D01*
X1384298Y81739D01*
X1384590Y81632D01*
X1384840Y81472D01*
X1385006Y81285D01*
X1385048Y81072D01*
G01Y82685D02*
X1382548D01*
G01Y83699D02*
X1384090Y82685D01*
G01X1385048Y83859D02*
X1383381Y83139D01*
G01X1380245Y86678D02*
Y71878D01*
G01X1384335Y88852D02*
X1384283Y88545D01*
X1384077Y88277D01*
X1383767Y88047D01*
X1383405Y87894D01*
X1382992Y87817D01*
X1382578D01*
X1382165Y87894D01*
X1381803Y88047D01*
X1381493Y88277D01*
X1381287Y88545D01*
X1381235Y88852D01*
X1381287Y89159D01*
X1381493Y89427D01*
X1381803Y89657D01*
X1382165Y89810D01*
X1382578Y89887D01*
X1382992D01*
X1383405Y89810D01*
X1383767Y89657D01*
X1384077Y89427D01*
X1384283Y89159D01*
X1384335Y88852D01*
G01X1383508Y89159D02*
X1384335Y89619D01*
G01Y91952D02*
X1381235D01*
X1381855Y91492D01*
G01X1384335D02*
Y92412D01*
G01X1381752Y94324D02*
X1381442Y94554D01*
X1381287Y94822D01*
X1381235Y95129D01*
X1381338Y95512D01*
X1381597Y95780D01*
X1381907Y95857D01*
X1382217Y95819D01*
X1382475Y95665D01*
X1382992Y94899D01*
X1383353Y94554D01*
X1383870Y94324D01*
X1384335Y94247D01*
Y95857D01*
G01X1382815Y238194D02*
Y234994D01*
G01Y243194D02*
Y239994D01*
G01Y248194D02*
Y244994D01*
G01Y253194D02*
Y249994D01*
G01X1381213Y618383D02*
Y612183D01*
G01X1385107Y627014D02*
Y620814D01*
G01D02*
X1381907D01*
G01D02*
Y622500D01*
G01Y627014D02*
X1385107D01*
G01X1381907Y624600D02*
Y627014D01*
G01X1378850Y624450D02*
Y622596D01*
G01X1381907Y631314D02*
Y637514D01*
G01D02*
X1385107D01*
G01D02*
Y631314D01*
G01D02*
X1381907D01*
G01X1385084Y644335D02*
Y638135D01*
G01D02*
X1381884D01*
G01D02*
Y644335D01*
G01X1378850Y637007D02*
Y635309D01*
G01X1393076Y645893D02*
Y652093D01*
G01D02*
X1396276D01*
G01Y645893D02*
X1393076D01*
G01X1380450Y647835D02*
X1386650D01*
G01D02*
Y644635D01*
G01D02*
X1380450D01*
G01D02*
Y647835D01*
G01X1381884Y644335D02*
X1385084D01*
G01X1378850Y646218D02*
Y643618D01*
G01X1392597Y655496D02*
X1391864D01*
G01D02*
Y657687D01*
G01X1383625Y692745D02*
Y649437D01*
G01X1385697Y663881D02*
Y670081D01*
G01D02*
X1388897D01*
G01D02*
Y663881D01*
G01D02*
X1385697D01*
G01X1391864Y676518D02*
Y679118D01*
G01D02*
X1392657D01*
G01X1386479Y725643D02*
Y682335D01*
G01D02*
X1391820D01*
G01Y725643D02*
X1386479D01*
G01X1387566Y734645D02*
Y737745D01*
X1388486D01*
X1388793Y737590D01*
X1389023Y737228D01*
X1389100Y736815D01*
X1389023Y736402D01*
X1388831Y736092D01*
X1388486Y735937D01*
X1387566D01*
G01X1390666Y737745D02*
Y734645D01*
X1392200D01*
G01X1393805Y735937D02*
X1394073Y736298D01*
X1394303Y736505D01*
X1394610Y736608D01*
X1394878Y736505D01*
X1395070Y736298D01*
X1395223Y735988D01*
X1395261Y735627D01*
X1395223Y735317D01*
X1395070Y735007D01*
X1394840Y734748D01*
X1394571Y734645D01*
X1394265Y734748D01*
X1393996Y735058D01*
X1393843Y735523D01*
X1393805Y736040D01*
X1393881Y736712D01*
X1393996Y737073D01*
X1394188Y737435D01*
X1394456Y737693D01*
X1394725Y737745D01*
X1394993Y737642D01*
X1395185Y737383D01*
G01X1397633Y734645D02*
Y737745D01*
X1397173Y737125D01*
G01Y734645D02*
X1398093D01*
G01X1389047Y1003465D02*
Y1034961D01*
G01X1444559Y1003465D02*
X1389047D01*
G01X1390208Y1011463D02*
X1396408D01*
Y1008263D01*
X1390208D01*
Y1011463D01*
G01Y1015203D02*
X1396408D01*
Y1012003D01*
X1390208D01*
Y1015203D01*
G01Y1007722D02*
X1396408D01*
Y1004522D01*
X1390208D01*
Y1007722D01*
G01Y1018943D02*
X1396408D01*
Y1015743D01*
X1390208D01*
Y1018943D01*
G01Y1030163D02*
X1396408D01*
Y1026963D01*
X1390208D01*
Y1030163D01*
G01Y1026423D02*
X1396408D01*
Y1023223D01*
X1390208D01*
Y1026423D01*
G01Y1022683D02*
X1396408D01*
Y1019483D01*
X1390208D01*
Y1022683D01*
G01X1389047Y1034961D02*
X1444559D01*
G01X1396408Y1030703D02*
X1390208D01*
Y1033903D01*
X1396408D01*
Y1030703D01*
G01X1394355Y1326514D02*
X1393562D01*
G01X1389943Y1353539D02*
Y1359739D01*
G01X1393143Y1353539D02*
X1389943D01*
G01X1393143Y1359739D02*
Y1353539D01*
G01X1382476Y1360443D02*
Y1357243D01*
G01X1389101Y1359739D02*
Y1353539D01*
G01D02*
X1385901D01*
G01D02*
Y1359739D01*
G01X1389943D02*
X1393143D01*
G01X1385901D02*
X1389101D01*
G01X1379095Y1363797D02*
Y1366897D01*
X1380015D01*
X1380322Y1366742D01*
X1380552Y1366380D01*
X1380629Y1365967D01*
X1380552Y1365554D01*
X1380360Y1365244D01*
X1380015Y1365089D01*
X1379095D01*
G01X1382195Y1366897D02*
Y1363797D01*
X1383729D01*
G01X1385985D02*
X1386062Y1364469D01*
X1386177Y1365037D01*
X1386330Y1365554D01*
X1386522Y1366122D01*
X1386829Y1366897D01*
X1385295D01*
G01X1394274Y1633917D02*
X1394222Y1633610D01*
X1394016Y1633342D01*
X1393706Y1633112D01*
X1393344Y1632959D01*
X1392931Y1632882D01*
X1392517D01*
X1392104Y1632959D01*
X1391742Y1633112D01*
X1391432Y1633342D01*
X1391226Y1633610D01*
X1391174Y1633917D01*
X1391226Y1634224D01*
X1391432Y1634492D01*
X1391742Y1634722D01*
X1392104Y1634875D01*
X1392517Y1634952D01*
X1392931D01*
X1393344Y1634875D01*
X1393706Y1634722D01*
X1394016Y1634492D01*
X1394222Y1634224D01*
X1394274Y1633917D01*
G01X1393447Y1634224D02*
X1394274Y1634684D01*
G01Y1637017D02*
X1391174D01*
X1391794Y1636557D01*
G01X1394274D02*
Y1637477D01*
G01X1393654Y1639274D02*
X1394016Y1639504D01*
X1394222Y1639810D01*
X1394274Y1640155D01*
X1394222Y1640462D01*
X1393964Y1640769D01*
X1393654Y1640960D01*
X1393344Y1640999D01*
X1392982Y1640922D01*
X1392724Y1640654D01*
X1392621Y1640385D01*
Y1640040D01*
G01Y1640385D02*
X1392466Y1640615D01*
X1392207Y1640807D01*
X1391897Y1640884D01*
X1391587Y1640807D01*
X1391329Y1640615D01*
X1391174Y1640270D01*
X1391226Y1639925D01*
X1391432Y1639580D01*
G01X1394274Y1643677D02*
X1391174D01*
X1393396Y1642259D01*
Y1644175D01*
G01X1387393Y1668791D02*
Y1671991D01*
G01X1393593Y1668791D02*
X1387393D01*
G01X1393593Y1671991D02*
Y1668791D01*
G01X1386593Y1671991D02*
Y1668791D01*
G01X1380393D02*
Y1671991D01*
G01X1386593Y1668791D02*
X1380393D01*
G01X1384526Y1659098D02*
X1384718Y1658788D01*
X1384948Y1658581D01*
X1385216Y1658478D01*
X1385523Y1658581D01*
X1385753Y1658788D01*
X1385983Y1659098D01*
X1386060Y1659511D01*
Y1661578D01*
G01X1388393Y1658478D02*
Y1661578D01*
X1387933Y1660958D01*
G01Y1658478D02*
X1388853D01*
G01X1391493Y1661578D02*
X1391186Y1661475D01*
X1390956Y1661216D01*
X1390803Y1660906D01*
X1390688Y1660493D01*
X1390650Y1660028D01*
X1390688Y1659563D01*
X1390803Y1659150D01*
X1390956Y1658840D01*
X1391186Y1658581D01*
X1391493Y1658478D01*
X1391800Y1658581D01*
X1392030Y1658840D01*
X1392183Y1659150D01*
X1392298Y1659563D01*
X1392336Y1660028D01*
X1392298Y1660493D01*
X1392183Y1660906D01*
X1392030Y1661216D01*
X1391800Y1661475D01*
X1391493Y1661578D01*
G01X1394516Y1658478D02*
X1394593Y1659150D01*
X1394708Y1659718D01*
X1394861Y1660235D01*
X1395053Y1660803D01*
X1395360Y1661578D01*
X1393826D01*
G01X1379133Y1713840D02*
Y1658900D01*
G01X1387393Y1671991D02*
X1393593D01*
G01Y1675991D02*
Y1672791D01*
G01X1387393Y1675991D02*
X1393593D01*
G01X1387393Y1672791D02*
Y1675991D01*
G01X1393593Y1672791D02*
X1387393D01*
G01X1380393D02*
Y1675991D01*
G01X1386593Y1672791D02*
X1380393D01*
G01X1386593Y1675991D02*
Y1672791D01*
G01X1380393Y1675991D02*
X1386593D01*
G01X1380393Y1671991D02*
X1386593D01*
G01X1394792Y1682688D02*
X1394740Y1682381D01*
X1394534Y1682113D01*
X1394224Y1681883D01*
X1393862Y1681730D01*
X1393449Y1681653D01*
X1393035D01*
X1392622Y1681730D01*
X1392260Y1681883D01*
X1391950Y1682113D01*
X1391744Y1682381D01*
X1391692Y1682688D01*
X1391744Y1682995D01*
X1391950Y1683263D01*
X1392260Y1683493D01*
X1392622Y1683646D01*
X1393035Y1683723D01*
X1393449D01*
X1393862Y1683646D01*
X1394224Y1683493D01*
X1394534Y1683263D01*
X1394740Y1682995D01*
X1394792Y1682688D01*
G01X1393965Y1682995D02*
X1394792Y1683455D01*
G01Y1685788D02*
X1391692D01*
X1392312Y1685328D01*
G01X1394792D02*
Y1686248D01*
G01Y1689348D02*
X1391692D01*
X1393914Y1687930D01*
Y1689846D01*
G01X1393500Y1691260D02*
X1393139Y1691528D01*
X1392932Y1691758D01*
X1392829Y1692065D01*
X1392932Y1692333D01*
X1393139Y1692525D01*
X1393449Y1692678D01*
X1393810Y1692716D01*
X1394120Y1692678D01*
X1394430Y1692525D01*
X1394689Y1692295D01*
X1394792Y1692026D01*
X1394689Y1691720D01*
X1394379Y1691451D01*
X1393914Y1691298D01*
X1393397Y1691260D01*
X1392725Y1691336D01*
X1392364Y1691451D01*
X1392002Y1691643D01*
X1391744Y1691911D01*
X1391692Y1692180D01*
X1391795Y1692448D01*
X1392054Y1692640D01*
G01X1390690Y1681391D02*
X1382028D01*
G01X1390690Y1691885D02*
Y1681391D01*
G01X1382028Y1684738D02*
X1384228Y1686638D01*
G01X1382028Y1681391D02*
Y1684738D01*
G01X1389145Y1701638D02*
Y1698438D01*
G01X1382945D02*
Y1701638D01*
G01X1389145Y1698438D02*
X1382945D01*
G01X1393275Y1696838D02*
Y1693638D01*
G01X1387075Y1696838D02*
X1393275D01*
G01X1387075Y1693638D02*
Y1696838D01*
G01X1393275Y1693638D02*
X1387075D01*
G01X1382028Y1691885D02*
X1390690D01*
G01X1382028Y1688538D02*
Y1691885D01*
G01X1384228Y1686638D02*
X1382028Y1688538D01*
G01X1389145Y1713638D02*
Y1710438D01*
G01X1382945Y1713638D02*
X1389145D01*
G01X1382945Y1710438D02*
Y1713638D01*
G01X1389145Y1710438D02*
X1382945D01*
G01Y1701638D02*
X1389145D01*
G01Y1709638D02*
Y1706438D01*
G01X1382945Y1709638D02*
X1389145D01*
G01X1382945Y1706438D02*
Y1709638D01*
G01X1389145Y1706438D02*
X1382945D01*
G01Y1702438D02*
Y1705638D01*
G01X1389145Y1702438D02*
X1382945D01*
G01X1389145Y1705638D02*
Y1702438D01*
G01X1382945Y1705638D02*
X1389145D01*
G01X1393280Y1714129D02*
X1395502D01*
X1395967Y1714282D01*
X1396277Y1714589D01*
X1396380Y1714972D01*
X1396277Y1715355D01*
X1395967Y1715662D01*
X1395502Y1715815D01*
X1393280D01*
G01X1395760Y1717229D02*
X1396122Y1717459D01*
X1396328Y1717765D01*
X1396380Y1718110D01*
X1396328Y1718417D01*
X1396070Y1718724D01*
X1395760Y1718915D01*
X1395450Y1718954D01*
X1395088Y1718877D01*
X1394830Y1718609D01*
X1394727Y1718340D01*
Y1717995D01*
G01Y1718340D02*
X1394572Y1718570D01*
X1394313Y1718762D01*
X1394003Y1718839D01*
X1393693Y1718762D01*
X1393435Y1718570D01*
X1393280Y1718225D01*
X1393332Y1717880D01*
X1393538Y1717535D01*
G01X1396380Y1721172D02*
X1393280D01*
X1393900Y1720712D01*
G01X1396380D02*
Y1721632D01*
G01X1395088Y1723544D02*
X1394727Y1723812D01*
X1394520Y1724042D01*
X1394417Y1724349D01*
X1394520Y1724617D01*
X1394727Y1724809D01*
X1395037Y1724962D01*
X1395398Y1725000D01*
X1395708Y1724962D01*
X1396018Y1724809D01*
X1396277Y1724579D01*
X1396380Y1724310D01*
X1396277Y1724004D01*
X1395967Y1723735D01*
X1395502Y1723582D01*
X1394985Y1723544D01*
X1394313Y1723620D01*
X1393952Y1723735D01*
X1393590Y1723927D01*
X1393332Y1724195D01*
X1393280Y1724464D01*
X1393383Y1724732D01*
X1393642Y1724924D01*
G01X1391951Y1717540D02*
Y1714878D01*
G01X1383289D02*
Y1725478D01*
G01X1391951Y1714878D02*
X1383289D01*
G01X1391704Y1729918D02*
Y1726718D01*
G01X1385504Y1729918D02*
X1391704D01*
G01X1385504Y1726718D02*
Y1729918D01*
G01X1391704Y1726718D02*
X1385504D01*
G01X1379133Y1736118D02*
Y1719070D01*
G01X1389120Y1720178D02*
X1391951Y1717540D01*
G01Y1722816D02*
X1389120Y1720178D01*
G01X1391951Y1725478D02*
Y1722816D01*
G01X1383289Y1725478D02*
X1391951D01*
G01X1380704Y1731518D02*
Y1734718D01*
G01X1386904Y1731518D02*
X1380704D01*
G01X1386904Y1734718D02*
Y1731518D01*
G01X1380704Y1734718D02*
X1386904D01*
G01X1395481Y67488D02*
Y70588D01*
X1396401D01*
X1396708Y70433D01*
X1396938Y70071D01*
X1397015Y69658D01*
X1396938Y69245D01*
X1396746Y68935D01*
X1396401Y68780D01*
X1395481D01*
G01X1399348Y70588D02*
X1399041Y70485D01*
X1398811Y70226D01*
X1398658Y69916D01*
X1398543Y69503D01*
X1398505Y69038D01*
X1398543Y68573D01*
X1398658Y68160D01*
X1398811Y67850D01*
X1399041Y67591D01*
X1399348Y67488D01*
X1399655Y67591D01*
X1399885Y67850D01*
X1400038Y68160D01*
X1400153Y68573D01*
X1400191Y69038D01*
X1400153Y69503D01*
X1400038Y69916D01*
X1399885Y70226D01*
X1399655Y70485D01*
X1399348Y70588D01*
G01X1401298Y66455D02*
X1403598D01*
G01X1404705Y70588D02*
Y68366D01*
X1404858Y67901D01*
X1405165Y67591D01*
X1405548Y67488D01*
X1405931Y67591D01*
X1406238Y67901D01*
X1406391Y68366D01*
Y70588D01*
G01X1407690Y67488D02*
X1408648Y70588D01*
X1409606Y67488D01*
G01X1409261Y68573D02*
X1408035D01*
G01X1410981Y67488D02*
Y70588D01*
X1411940D01*
X1412246Y70433D01*
X1412438Y70226D01*
X1412515Y69813D01*
X1412438Y69400D01*
X1412208Y69141D01*
X1411940Y68986D01*
X1410981D01*
G01X1411940D02*
X1412515Y67488D01*
G01X1414848Y70588D02*
Y67488D01*
G01X1413966Y70588D02*
X1415730D01*
G01X1417948D02*
X1417641Y70485D01*
X1417411Y70226D01*
X1417258Y69916D01*
X1417143Y69503D01*
X1417105Y69038D01*
X1417143Y68573D01*
X1417258Y68160D01*
X1417411Y67850D01*
X1417641Y67591D01*
X1417948Y67488D01*
X1418255Y67591D01*
X1418485Y67850D01*
X1418638Y68160D01*
X1418753Y68573D01*
X1418791Y69038D01*
X1418753Y69503D01*
X1418638Y69916D01*
X1418485Y70226D01*
X1418255Y70485D01*
X1417948Y70588D01*
G01X1409066Y120841D02*
X1408759Y120893D01*
X1408491Y121099D01*
X1408261Y121409D01*
X1408108Y121771D01*
X1408031Y122184D01*
Y122598D01*
X1408108Y123011D01*
X1408261Y123373D01*
X1408491Y123683D01*
X1408759Y123889D01*
X1409066Y123941D01*
X1409373Y123889D01*
X1409641Y123683D01*
X1409871Y123373D01*
X1410024Y123011D01*
X1410101Y122598D01*
Y122184D01*
X1410024Y121771D01*
X1409871Y121409D01*
X1409641Y121099D01*
X1409373Y120893D01*
X1409066Y120841D01*
G01X1409373Y121668D02*
X1409833Y120841D01*
G01X1411438Y122133D02*
X1411706Y122494D01*
X1411936Y122701D01*
X1412243Y122804D01*
X1412511Y122701D01*
X1412703Y122494D01*
X1412856Y122184D01*
X1412894Y121823D01*
X1412856Y121513D01*
X1412703Y121203D01*
X1412473Y120944D01*
X1412204Y120841D01*
X1411898Y120944D01*
X1411629Y121254D01*
X1411476Y121719D01*
X1411438Y122236D01*
X1411514Y122908D01*
X1411629Y123269D01*
X1411821Y123631D01*
X1412089Y123889D01*
X1412358Y123941D01*
X1412626Y123838D01*
X1412818Y123579D01*
G01X1415266Y120841D02*
Y123941D01*
X1414806Y123321D01*
G01Y120841D02*
X1415726D01*
G01X1420626Y106474D02*
X1405826D01*
G01D02*
Y119474D01*
G01D02*
X1420626D01*
G01X1396516Y159410D02*
Y179016D01*
G01X1403698Y255448D02*
Y258548D01*
X1404618D01*
X1404925Y258393D01*
X1405155Y258031D01*
X1405232Y257618D01*
X1405155Y257205D01*
X1404963Y256895D01*
X1404618Y256740D01*
X1403698D01*
G01X1407565Y255448D02*
Y258548D01*
X1407105Y257928D01*
G01Y255448D02*
X1408025D01*
G01X1409937Y258031D02*
X1410167Y258341D01*
X1410435Y258496D01*
X1410742Y258548D01*
X1411125Y258445D01*
X1411393Y258186D01*
X1411470Y257876D01*
X1411432Y257566D01*
X1411278Y257308D01*
X1410512Y256791D01*
X1410167Y256430D01*
X1409937Y255913D01*
X1409860Y255448D01*
X1411470D01*
G01X1412807Y258548D02*
X1413765Y255448D01*
X1414723Y258548D01*
G01X1415715Y254415D02*
X1418015D01*
G01X1419007Y255448D02*
X1419965Y258548D01*
X1420923Y255448D01*
G01X1420578Y256533D02*
X1419352D01*
G01X1422222Y258548D02*
Y256326D01*
X1422375Y255861D01*
X1422682Y255551D01*
X1423065Y255448D01*
X1423448Y255551D01*
X1423755Y255861D01*
X1423908Y256326D01*
Y258548D01*
G01X1425360Y255448D02*
X1426970Y258548D01*
G01X1425360D02*
X1426970Y255448D01*
G01X1403668Y249561D02*
Y252661D01*
X1404434D01*
X1404741Y252506D01*
X1404971Y252299D01*
X1405163Y251989D01*
X1405316Y251628D01*
X1405354Y251111D01*
X1405316Y250594D01*
X1405163Y250233D01*
X1404971Y249923D01*
X1404741Y249716D01*
X1404434Y249561D01*
X1403668D01*
G01X1407611D02*
X1407879Y249613D01*
X1408186Y249768D01*
X1408378Y250026D01*
X1408454Y250388D01*
X1408378Y250749D01*
X1408148Y251059D01*
X1407803Y251214D01*
X1407419D01*
X1407189Y251318D01*
X1406998Y251576D01*
X1406921Y251938D01*
X1407036Y252299D01*
X1407304Y252558D01*
X1407611Y252661D01*
X1407918Y252558D01*
X1408186Y252299D01*
X1408301Y251938D01*
X1408224Y251576D01*
X1408033Y251318D01*
X1407803Y251214D01*
X1407419D01*
X1407074Y251059D01*
X1406844Y250749D01*
X1406768Y250388D01*
X1406844Y250026D01*
X1407036Y249768D01*
X1407343Y249613D01*
X1407611Y249561D01*
G01X1410711Y252661D02*
X1410404Y252558D01*
X1410174Y252299D01*
X1410021Y251989D01*
X1409906Y251576D01*
X1409868Y251111D01*
X1409906Y250646D01*
X1410021Y250233D01*
X1410174Y249923D01*
X1410404Y249664D01*
X1410711Y249561D01*
X1411018Y249664D01*
X1411248Y249923D01*
X1411401Y250233D01*
X1411516Y250646D01*
X1411554Y251111D01*
X1411516Y251576D01*
X1411401Y251989D01*
X1411248Y252299D01*
X1411018Y252558D01*
X1410711Y252661D01*
G01X1413811D02*
X1413504Y252558D01*
X1413274Y252299D01*
X1413121Y251989D01*
X1413006Y251576D01*
X1412968Y251111D01*
X1413006Y250646D01*
X1413121Y250233D01*
X1413274Y249923D01*
X1413504Y249664D01*
X1413811Y249561D01*
X1414118Y249664D01*
X1414348Y249923D01*
X1414501Y250233D01*
X1414616Y250646D01*
X1414654Y251111D01*
X1414616Y251576D01*
X1414501Y251989D01*
X1414348Y252299D01*
X1414118Y252558D01*
X1413811Y252661D01*
G01X1416911D02*
X1416604Y252558D01*
X1416374Y252299D01*
X1416221Y251989D01*
X1416106Y251576D01*
X1416068Y251111D01*
X1416106Y250646D01*
X1416221Y250233D01*
X1416374Y249923D01*
X1416604Y249664D01*
X1416911Y249561D01*
X1417218Y249664D01*
X1417448Y249923D01*
X1417601Y250233D01*
X1417716Y250646D01*
X1417754Y251111D01*
X1417716Y251576D01*
X1417601Y251989D01*
X1417448Y252299D01*
X1417218Y252558D01*
X1416911Y252661D01*
G01X1404628Y263344D02*
X1404781Y263499D01*
X1404896Y263758D01*
X1404973Y264119D01*
X1404896Y264429D01*
X1404743Y264636D01*
X1404474Y264791D01*
X1403439D01*
Y261691D01*
X1404704D01*
X1404973Y261898D01*
X1405126Y262208D01*
X1405203Y262569D01*
X1405126Y262931D01*
X1404896Y263241D01*
X1404628Y263344D01*
X1403439D01*
G01X1407421Y261691D02*
Y264791D01*
G01X1409869Y263758D02*
Y262311D01*
X1410023Y261949D01*
X1410253Y261743D01*
X1410521Y261691D01*
X1410789Y261743D01*
X1411019Y261949D01*
X1411173Y262311D01*
G01Y261691D02*
Y263758D01*
G01X1413046Y263086D02*
X1414273D01*
X1414158Y263448D01*
X1413966Y263654D01*
X1413698Y263758D01*
X1413429Y263706D01*
X1413199Y263551D01*
X1413046Y263189D01*
X1412969Y262879D01*
Y262569D01*
X1413046Y262259D01*
X1413238Y261949D01*
X1413468Y261743D01*
X1413736Y261691D01*
X1414004Y261794D01*
X1414273Y262104D01*
G01X1419054Y264791D02*
Y261691D01*
X1420588D01*
G01X1422921Y263758D02*
Y261691D01*
G01Y264584D02*
X1422844Y264636D01*
Y264739D01*
X1422921Y264791D01*
X1422998Y264739D01*
Y264636D01*
X1422921Y264584D01*
G01X1425484Y260916D02*
X1425753Y260709D01*
X1426059Y260658D01*
X1426328Y260709D01*
X1426558Y260968D01*
X1426711Y261329D01*
Y263758D01*
G01Y263344D02*
X1426558Y263551D01*
X1426328Y263706D01*
X1426059Y263758D01*
X1425753Y263654D01*
X1425561Y263448D01*
X1425408Y263086D01*
X1425331Y262724D01*
X1425369Y262414D01*
X1425523Y262053D01*
X1425753Y261794D01*
X1426059Y261691D01*
X1426289Y261743D01*
X1426558Y261949D01*
X1426711Y262156D01*
G01X1428469Y261691D02*
Y264791D01*
G01Y263293D02*
X1428661Y263551D01*
X1428853Y263706D01*
X1429159Y263758D01*
X1429389Y263706D01*
X1429658Y263499D01*
X1429773Y263189D01*
Y261691D01*
G01X1432221Y264791D02*
Y261691D01*
G01X1431684Y263758D02*
X1432758D01*
G01X1437654Y264791D02*
Y261691D01*
X1439188D01*
G01X1442288D02*
X1440754D01*
Y264791D01*
X1442288D01*
G01X1441674Y263293D02*
X1440754D01*
G01X1443778Y261691D02*
Y264791D01*
X1444544D01*
X1444851Y264636D01*
X1445081Y264429D01*
X1445273Y264119D01*
X1445426Y263758D01*
X1445464Y263241D01*
X1445426Y262724D01*
X1445273Y262363D01*
X1445081Y262053D01*
X1444851Y261846D01*
X1444544Y261691D01*
X1443778D01*
G01X1433997Y601230D02*
G02I-13386J0D01*
G01X1401357Y644365D02*
Y641165D01*
G01D02*
X1395157D01*
G01D02*
Y644365D01*
G01X1400176Y636293D02*
Y639393D01*
X1401096D01*
X1401403Y639238D01*
X1401633Y638876D01*
X1401710Y638463D01*
X1401633Y638050D01*
X1401441Y637740D01*
X1401096Y637585D01*
X1400176D01*
G01X1403200Y639393D02*
Y637171D01*
X1403353Y636706D01*
X1403660Y636396D01*
X1404043Y636293D01*
X1404426Y636396D01*
X1404733Y636706D01*
X1404886Y637171D01*
Y639393D01*
G01X1407603Y636293D02*
Y639393D01*
X1406185Y637171D01*
X1408101D01*
G01X1410243Y636293D02*
X1410511Y636345D01*
X1410818Y636500D01*
X1411010Y636758D01*
X1411086Y637120D01*
X1411010Y637481D01*
X1410780Y637791D01*
X1410435Y637946D01*
X1410051D01*
X1409821Y638050D01*
X1409630Y638308D01*
X1409553Y638670D01*
X1409668Y639031D01*
X1409936Y639290D01*
X1410243Y639393D01*
X1410550Y639290D01*
X1410818Y639031D01*
X1410933Y638670D01*
X1410856Y638308D01*
X1410665Y638050D01*
X1410435Y637946D01*
X1410051D01*
X1409706Y637791D01*
X1409476Y637481D01*
X1409400Y637120D01*
X1409476Y636758D01*
X1409668Y636500D01*
X1409975Y636345D01*
X1410243Y636293D01*
G01X1396276Y652093D02*
Y645893D01*
G01X1395157Y644365D02*
X1401357D01*
G01X1403743Y648389D02*
X1409943D01*
G01Y645189D02*
X1403743D01*
G01D02*
Y648389D01*
G01X1400318Y652093D02*
Y645893D01*
G01D02*
X1397118D01*
G01D02*
Y652093D01*
G01D02*
X1400318D01*
G01X1405943Y1004822D02*
Y1011022D01*
X1409143D01*
Y1004822D01*
X1405943D01*
G01X1402203D02*
Y1011022D01*
X1405403D01*
Y1004822D01*
X1402203D01*
G01X1398463D02*
Y1011022D01*
X1401663D01*
Y1004822D01*
X1398463D01*
G01X1399640Y1016344D02*
X1405840D01*
Y1013144D01*
X1399640D01*
Y1016344D01*
G01Y1020478D02*
X1405840D01*
Y1017278D01*
X1399640D01*
Y1020478D01*
G01Y1024612D02*
X1405840D01*
Y1021412D01*
X1399640D01*
Y1024612D01*
G01X1405408Y1033603D02*
Y1027403D01*
X1402208D01*
Y1033603D01*
X1405408D01*
G01X1409148D02*
Y1027403D01*
X1405948D01*
Y1033603D01*
X1409148D01*
G01X1401668D02*
Y1027403D01*
X1398468D01*
Y1033603D01*
X1401668D01*
G01X1399700Y1177705D02*
X1559100D01*
G01X1396900Y1167638D02*
X1403900D01*
G01X1399740Y1279989D02*
Y1323297D01*
G01X1394399Y1279989D02*
X1399740D01*
G01X1402090Y1290865D02*
X1405290D01*
G01X1402090Y1284665D02*
Y1290865D01*
G01X1405290Y1284665D02*
X1402090D01*
G01X1405290Y1290865D02*
Y1284665D01*
G01X1406090Y1287365D02*
X1412290D01*
G01X1406090Y1284165D02*
Y1287365D01*
G01X1412290Y1284165D02*
X1406090D01*
G01Y1291365D02*
X1412290D01*
G01X1406090Y1288165D02*
Y1291365D01*
G01X1412290Y1288165D02*
X1406090D01*
G01X1401764Y1296579D02*
Y1322169D01*
G01X1405759Y1296579D02*
X1401764D01*
G01Y1322169D02*
X1405759D01*
G01X1394355Y1329114D02*
Y1326514D01*
G01X1399740Y1323297D02*
X1394399D01*
G01X1397221Y1342016D02*
X1400421D01*
G01X1397221Y1335816D02*
Y1342016D01*
G01X1400421Y1335816D02*
X1397221D01*
G01X1400421Y1342016D02*
Y1335816D01*
G01X1394355Y1350136D02*
Y1347945D01*
G01X1393622Y1350136D02*
X1394355D01*
G01X1403132Y1540451D02*
X1396600D01*
G01X1403132Y1575491D02*
Y1540451D01*
G01X1407932Y1551320D02*
Y1557520D01*
X1411132D01*
Y1551320D01*
X1407932D01*
G01X1414084Y1547520D02*
X1407884D01*
Y1550720D01*
X1414084D01*
Y1547520D01*
G01Y1543620D02*
X1407884D01*
Y1546820D01*
X1414084D01*
Y1543620D01*
G01X1396300Y1575491D02*
X1403132D01*
G01X1403533Y1620567D02*
Y1623767D01*
G01X1409733Y1620567D02*
X1403533D01*
G01Y1623767D02*
X1409733D01*
G01X1402733D02*
Y1620567D01*
G01X1396533Y1623767D02*
X1402733D01*
G01X1396533Y1620567D02*
Y1623767D01*
G01X1402733Y1620567D02*
X1396533D01*
G01Y1624567D02*
Y1627767D01*
G01X1402733Y1624567D02*
X1396533D01*
G01X1402733Y1627767D02*
Y1624567D01*
G01X1403533D02*
Y1627767D01*
G01X1409733Y1624567D02*
X1403533D01*
G01X1396533Y1627767D02*
X1402733D01*
G01X1400383Y1628567D02*
Y1631767D01*
G01X1406583Y1628567D02*
X1400383D01*
G01X1406583Y1631767D02*
Y1628567D01*
G01X1400383Y1631767D02*
X1406583D01*
G01X1403533Y1627767D02*
X1409733D01*
G01X1406830Y1633120D02*
X1398168D01*
G01X1406830Y1643614D02*
Y1633120D01*
G01X1398168Y1640267D02*
Y1643614D01*
G01X1400368Y1638367D02*
X1398168Y1640267D01*
G01Y1636467D02*
X1400368Y1638367D01*
G01X1398168Y1633120D02*
Y1636467D01*
G01X1407655Y1629686D02*
X1409877D01*
X1410342Y1629839D01*
X1410652Y1630146D01*
X1410755Y1630529D01*
X1410652Y1630912D01*
X1410342Y1631219D01*
X1409877Y1631372D01*
X1407655D01*
G01X1408172Y1632901D02*
X1407862Y1633131D01*
X1407707Y1633399D01*
X1407655Y1633706D01*
X1407758Y1634089D01*
X1408017Y1634357D01*
X1408327Y1634434D01*
X1408637Y1634396D01*
X1408895Y1634242D01*
X1409412Y1633476D01*
X1409773Y1633131D01*
X1410290Y1632901D01*
X1410755Y1632824D01*
Y1634434D01*
G01X1407655Y1636729D02*
X1407758Y1636422D01*
X1408017Y1636192D01*
X1408327Y1636039D01*
X1408740Y1635924D01*
X1409205Y1635886D01*
X1409670Y1635924D01*
X1410083Y1636039D01*
X1410393Y1636192D01*
X1410652Y1636422D01*
X1410755Y1636729D01*
X1410652Y1637036D01*
X1410393Y1637266D01*
X1410083Y1637419D01*
X1409670Y1637534D01*
X1409205Y1637572D01*
X1408740Y1637534D01*
X1408327Y1637419D01*
X1408017Y1637266D01*
X1407758Y1637036D01*
X1407655Y1636729D01*
G01X1410755Y1640289D02*
X1407655D01*
X1409877Y1638871D01*
Y1640787D01*
G01X1403215Y1648567D02*
X1409415D01*
G01X1403215Y1645367D02*
Y1648567D01*
G01X1409415Y1645367D02*
X1403215D01*
G01X1398168Y1643614D02*
X1406830D01*
G01X1398754Y1661848D02*
X1399064Y1662040D01*
X1399271Y1662270D01*
X1399374Y1662538D01*
X1399271Y1662845D01*
X1399064Y1663075D01*
X1398754Y1663305D01*
X1398341Y1663382D01*
X1396274D01*
G01X1399374Y1665715D02*
X1396274D01*
X1396894Y1665255D01*
G01X1399374D02*
Y1666175D01*
G01X1396791Y1668087D02*
X1396481Y1668317D01*
X1396326Y1668585D01*
X1396274Y1668892D01*
X1396377Y1669275D01*
X1396636Y1669543D01*
X1396946Y1669620D01*
X1397256Y1669582D01*
X1397514Y1669428D01*
X1398031Y1668662D01*
X1398392Y1668317D01*
X1398909Y1668087D01*
X1399374Y1668010D01*
Y1669620D01*
G01X1396791Y1671187D02*
X1396481Y1671417D01*
X1396326Y1671685D01*
X1396274Y1671992D01*
X1396377Y1672375D01*
X1396636Y1672643D01*
X1396946Y1672720D01*
X1397256Y1672682D01*
X1397514Y1672528D01*
X1398031Y1671762D01*
X1398392Y1671417D01*
X1398909Y1671187D01*
X1399374Y1671110D01*
Y1672720D01*
G01X1402559Y1736118D02*
Y1656969D01*
G01D02*
X1430315D01*
G01X1420844Y75305D02*
X1421154Y75497D01*
X1421361Y75727D01*
X1421464Y75995D01*
X1421361Y76302D01*
X1421154Y76532D01*
X1420844Y76762D01*
X1420431Y76839D01*
X1418364D01*
G01X1421464Y79172D02*
X1418364D01*
X1418984Y78712D01*
G01X1421464D02*
Y79632D01*
G01X1420844Y81429D02*
X1421206Y81659D01*
X1421412Y81965D01*
X1421464Y82310D01*
X1421412Y82617D01*
X1421154Y82924D01*
X1420844Y83115D01*
X1420534Y83154D01*
X1420172Y83077D01*
X1419914Y82809D01*
X1419811Y82540D01*
Y82195D01*
G01Y82540D02*
X1419656Y82770D01*
X1419397Y82962D01*
X1419087Y83039D01*
X1418777Y82962D01*
X1418519Y82770D01*
X1418364Y82425D01*
X1418416Y82080D01*
X1418622Y81735D01*
G01X1423301Y94125D02*
Y75621D01*
G01D02*
X1462671D01*
G01Y94125D02*
X1423301D01*
G01X1420626Y119474D02*
Y106474D01*
G01X1413500Y147000D02*
Y126000D01*
G01X1423639Y242550D02*
X1416549D01*
Y246350D01*
X1423689D01*
Y242600D01*
G01X1423239Y242550D02*
X1416049D01*
Y246350D01*
X1423239D01*
G01X1422639Y242550D02*
X1415549D01*
Y246350D01*
X1422639D01*
G01X1416278Y570956D02*
Y586310D01*
X1416330Y586362D01*
X1474499D01*
Y592081D01*
X1541069D01*
Y586575D01*
X1541098D01*
X1538098Y589575D01*
G01X1420611Y587844D02*
Y614616D01*
G01X1412913Y615777D02*
Y618877D01*
X1413833D01*
X1414140Y618722D01*
X1414370Y618360D01*
X1414447Y617947D01*
X1414370Y617534D01*
X1414178Y617224D01*
X1413833Y617069D01*
X1412913D01*
G01X1417623Y618619D02*
X1417393Y618774D01*
X1417125Y618877D01*
X1416818D01*
X1416473Y618722D01*
X1416205Y618464D01*
X1416013Y618154D01*
X1415860Y617637D01*
X1415822Y617172D01*
X1415898Y616707D01*
X1416013Y616397D01*
X1416243Y616087D01*
X1416512Y615880D01*
X1416780Y615777D01*
X1417048D01*
X1417317Y615880D01*
X1417547Y616035D01*
X1417738Y616242D01*
G01X1420340Y615777D02*
Y618877D01*
X1418922Y616655D01*
X1420838D01*
G01X1422328Y616139D02*
X1422597Y615880D01*
X1422903Y615777D01*
X1423210Y615880D01*
X1423478Y616190D01*
X1423670Y616655D01*
X1423747Y617120D01*
Y617689D01*
X1423670Y618154D01*
X1423478Y618567D01*
X1423248Y618774D01*
X1422980Y618877D01*
X1422673Y618774D01*
X1422443Y618567D01*
X1422290Y618257D01*
X1422213Y617844D01*
X1422290Y617482D01*
X1422482Y617120D01*
X1422712Y616914D01*
X1422980Y616862D01*
X1423287Y616965D01*
X1423517Y617224D01*
X1423747Y617689D01*
G01X1425352Y618360D02*
X1425582Y618670D01*
X1425850Y618825D01*
X1426157Y618877D01*
X1426540Y618774D01*
X1426808Y618515D01*
X1426885Y618205D01*
X1426847Y617895D01*
X1426693Y617637D01*
X1425927Y617120D01*
X1425582Y616759D01*
X1425352Y616242D01*
X1425275Y615777D01*
X1426885D01*
G01X1413913Y651283D02*
Y645083D01*
G01D02*
X1410713D01*
G01D02*
Y651283D01*
G01D02*
X1413913D01*
G01X1417807Y659914D02*
Y653714D01*
G01D02*
X1414607D01*
G01D02*
Y655200D01*
G01X1409943Y648389D02*
Y645189D01*
G01X1411550Y657350D02*
Y655496D01*
G01D02*
X1410542D01*
G01X1414607Y659914D02*
X1417807D01*
G01X1414607Y657600D02*
Y659914D01*
G01Y664214D02*
Y670414D01*
G01D02*
X1417807D01*
G01D02*
Y664214D01*
G01D02*
X1414607D01*
G01X1417784Y677235D02*
Y671035D01*
G01D02*
X1414584D01*
G01D02*
Y677235D01*
G01X1411550Y669907D02*
Y668209D01*
G01X1413150Y680735D02*
X1419350D01*
G01D02*
Y677535D01*
G01D02*
X1413150D01*
G01D02*
Y680735D01*
G01X1414584Y677235D02*
X1417784D01*
G01X1410757Y679118D02*
X1411550D01*
G01D02*
Y676518D01*
G01X1416007Y725643D02*
Y682335D01*
G01D02*
X1410666D01*
G01X1418407Y696131D02*
Y702331D01*
G01X1421607D02*
Y696131D01*
G01D02*
X1418407D01*
G01Y702331D02*
X1421607D01*
G01X1419079Y758223D02*
Y714915D01*
G01D02*
X1424420D01*
G01X1410666Y725643D02*
X1416007D01*
G01X1424420Y758223D02*
X1419079D01*
G01X1419476Y764075D02*
Y767175D01*
X1420396D01*
X1420703Y767020D01*
X1420933Y766658D01*
X1421010Y766245D01*
X1420933Y765832D01*
X1420741Y765522D01*
X1420396Y765367D01*
X1419476D01*
G01X1422576Y767175D02*
Y764075D01*
X1424110D01*
G01X1425600Y764540D02*
X1425830Y764282D01*
X1426098Y764127D01*
X1426443Y764075D01*
X1426788Y764178D01*
X1427056Y764385D01*
X1427248Y764747D01*
X1427286Y765160D01*
X1427210Y765573D01*
X1427018Y765832D01*
X1426750Y766038D01*
X1426481Y766090D01*
X1426213Y766038D01*
X1425868Y765832D01*
X1425983Y767175D01*
X1427018D01*
G01X1429543Y764075D02*
Y767175D01*
X1429083Y766555D01*
G01Y764075D02*
X1430003D01*
G01X1413424Y1004822D02*
Y1011022D01*
X1416624D01*
Y1004822D01*
X1413424D01*
G01X1409683D02*
Y1011022D01*
X1412883D01*
Y1004822D01*
X1409683D01*
G01X1417164D02*
Y1011022D01*
X1420364D01*
Y1004822D01*
X1417164D01*
G01X1418341Y1016344D02*
X1424541D01*
Y1013144D01*
X1418341D01*
Y1016344D01*
G01X1409487D02*
X1415687D01*
Y1013144D01*
X1409487D01*
Y1016344D01*
G01X1420904Y1004822D02*
Y1011022D01*
X1424104D01*
Y1004822D01*
X1420904D01*
G01X1418341Y1024612D02*
X1424541D01*
Y1021412D01*
X1418341D01*
Y1024612D01*
G01X1424108Y1033603D02*
Y1027403D01*
X1420908D01*
Y1033603D01*
X1424108D01*
G01X1409483Y1020478D02*
X1415683D01*
Y1017278D01*
X1409483D01*
Y1020478D01*
G01X1418341D02*
X1424541D01*
Y1017278D01*
X1418341D01*
Y1020478D01*
G01X1416628Y1033603D02*
Y1027403D01*
X1413428D01*
Y1033603D01*
X1416628D01*
G01X1412888D02*
Y1027403D01*
X1409688D01*
Y1033603D01*
X1412888D01*
G01X1420368D02*
Y1027403D01*
X1417168D01*
Y1033603D01*
X1420368D01*
G01X1409483Y1024612D02*
X1415683D01*
Y1021412D01*
X1409483D01*
Y1024612D01*
G01X1408600Y1167638D02*
X1558535D01*
G01X1416111Y1257266D02*
Y1263466D01*
X1417500D01*
G01X1419311Y1261800D02*
Y1258900D01*
G01X1417800Y1257266D02*
X1416111D01*
G01X1421500Y1263466D02*
X1422811D01*
Y1257266D01*
X1421300D01*
G01X1419611Y1258900D02*
Y1261800D01*
G01X1421600Y1256024D02*
X1431400D01*
G01X1415671Y1279414D02*
Y1276314D01*
G01X1414789Y1279414D02*
X1416553D01*
G01X1418004Y1276314D02*
Y1279414D01*
X1418924D01*
X1419231Y1279259D01*
X1419461Y1278897D01*
X1419538Y1278484D01*
X1419461Y1278071D01*
X1419269Y1277761D01*
X1418924Y1277606D01*
X1418004D01*
G01X1421028Y1276934D02*
X1421258Y1276572D01*
X1421564Y1276366D01*
X1421909Y1276314D01*
X1422216Y1276366D01*
X1422523Y1276624D01*
X1422714Y1276934D01*
X1422753Y1277244D01*
X1422676Y1277606D01*
X1422408Y1277864D01*
X1422139Y1277967D01*
X1421794D01*
G01X1422139D02*
X1422369Y1278122D01*
X1422561Y1278381D01*
X1422638Y1278691D01*
X1422561Y1279001D01*
X1422369Y1279259D01*
X1422024Y1279414D01*
X1421679Y1279362D01*
X1421334Y1279156D01*
G01X1412290Y1287365D02*
Y1284165D01*
G01Y1291365D02*
Y1288165D01*
G01X1427354Y1296579D02*
X1423359D01*
G01Y1322169D02*
X1427354D01*
G01X1415398Y1359449D02*
Y1362549D01*
G01X1417008D02*
Y1359449D01*
G01Y1360999D02*
X1415398D01*
G01X1419763Y1359449D02*
Y1362549D01*
X1418345Y1360327D01*
X1420261D01*
G01X1422863Y1359449D02*
Y1362549D01*
X1421445Y1360327D01*
X1423361D01*
G01X1411134Y1550620D02*
X1417134D01*
Y1547620D01*
X1411134D01*
Y1550620D01*
G01X1413834Y1551320D02*
Y1557520D01*
X1417034D01*
Y1551320D01*
X1413834D01*
G01X1417234Y1543620D02*
X1411034D01*
Y1546820D01*
X1417234D01*
Y1543620D01*
G01X1423122Y1569503D02*
Y1572911D01*
G01X1440838Y1569503D02*
X1423122D01*
G01X1422963Y1591758D02*
Y1588658D01*
X1424497D01*
G01X1426102Y1591241D02*
X1426332Y1591551D01*
X1426600Y1591706D01*
X1426907Y1591758D01*
X1427290Y1591655D01*
X1427558Y1591396D01*
X1427635Y1591086D01*
X1427597Y1590776D01*
X1427443Y1590518D01*
X1426677Y1590001D01*
X1426332Y1589640D01*
X1426102Y1589123D01*
X1426025Y1588658D01*
X1427635D01*
G01X1429087Y1589278D02*
X1429317Y1588916D01*
X1429623Y1588710D01*
X1429968Y1588658D01*
X1430275Y1588710D01*
X1430582Y1588968D01*
X1430773Y1589278D01*
X1430812Y1589588D01*
X1430735Y1589950D01*
X1430467Y1590208D01*
X1430198Y1590311D01*
X1429853D01*
G01X1430198D02*
X1430428Y1590466D01*
X1430620Y1590725D01*
X1430697Y1591035D01*
X1430620Y1591345D01*
X1430428Y1591603D01*
X1430083Y1591758D01*
X1429738Y1591706D01*
X1429393Y1591500D01*
G01X1423122Y1587219D02*
X1440838D01*
G01X1423122Y1583811D02*
Y1587219D01*
G01X1417222Y1608667D02*
X1414022D01*
G01X1417222Y1614867D02*
Y1608667D01*
G01X1414022D02*
Y1614867D01*
G01X1412222Y1608667D02*
X1409022D01*
G01X1412222Y1614867D02*
Y1608667D01*
G01X1409022D02*
Y1614867D01*
G01X1421222D02*
Y1608667D01*
G01X1418022D02*
Y1614867D01*
G01X1421222Y1608667D02*
X1418022D01*
G01X1414023Y1603759D02*
X1417223D01*
G01X1414023Y1597559D02*
Y1603759D01*
G01X1417223Y1597559D02*
X1414023D01*
G01X1417223Y1603759D02*
Y1597559D01*
G01X1422197Y1611504D02*
X1428397D01*
G01X1422197Y1608304D02*
Y1611504D01*
G01X1428397Y1608304D02*
X1422197D01*
G01X1409733Y1623767D02*
Y1620567D01*
G01Y1627767D02*
Y1624567D01*
G01X1414022Y1614867D02*
X1417222D01*
G01X1409022D02*
X1412222D01*
G01X1418022D02*
X1421222D01*
G01X1422197Y1617904D02*
Y1621104D01*
G01X1428397Y1617904D02*
X1422197D01*
G01Y1621104D02*
X1428397D01*
G01X1422197Y1612366D02*
Y1615566D01*
G01X1428397Y1612366D02*
X1422197D01*
G01Y1615566D02*
X1428397D01*
G01X1422197Y1624966D02*
X1428397D01*
G01X1422197Y1621766D02*
Y1624966D01*
G01X1428397Y1621766D02*
X1422197D01*
G01X1411850Y1634879D02*
Y1623855D01*
G01X1420512D02*
X1411850D01*
G01X1420512Y1634879D02*
Y1623855D01*
G01X1415222Y1636242D02*
X1412022D01*
G01X1415222Y1642442D02*
Y1636242D01*
G01X1412022D02*
Y1642442D01*
G01X1423415Y1644567D02*
Y1641367D01*
G01X1417215D02*
Y1644567D01*
G01X1423415Y1641367D02*
X1417215D01*
G01X1411850Y1634879D02*
X1420512D01*
G01X1412022Y1642442D02*
X1415222D01*
G01X1409415Y1648567D02*
Y1645367D01*
G01X1417215Y1644567D02*
X1423415D01*
G01Y1648567D02*
Y1645367D01*
G01X1417215Y1648567D02*
X1423415D01*
G01X1417215Y1645367D02*
Y1648567D01*
G01X1423415Y1645367D02*
X1417215D01*
G01X1437281Y-28151D02*
Y-11871D01*
X1446881D01*
Y-28151D01*
X1437281D01*
G01Y-8151D02*
Y8129D01*
X1446881D01*
Y-8151D01*
X1437281D01*
G01Y11849D02*
Y28129D01*
X1446881D01*
Y11849D01*
X1437281D01*
G01X1439862Y53792D02*
X1436662D01*
G01D02*
Y59992D01*
G01D02*
X1439862D01*
G01X1432662Y53792D02*
Y59992D01*
G01D02*
X1435862D01*
G01D02*
Y53792D01*
G01D02*
X1432662D01*
G01X1452536Y77589D02*
X1425269D01*
G01D02*
Y92156D01*
G01D02*
X1435112D01*
G01D02*
Y94125D01*
G01X1436113Y114500D02*
Y108300D01*
G01D02*
X1432913D01*
G01D02*
Y114500D01*
G01D02*
X1436113D01*
G01X1437449Y108343D02*
Y114543D01*
G01D02*
X1440649D01*
G01Y108343D02*
X1437449D01*
G01X1440649Y115343D02*
X1437449D01*
G01D02*
Y121543D01*
G01X1436782Y116064D02*
X1430582D01*
G01D02*
Y119264D01*
G01D02*
X1436782D01*
G01D02*
Y116064D01*
G01X1427569Y108213D02*
Y114413D01*
G01D02*
X1430769D01*
G01D02*
Y108213D01*
G01D02*
X1427569D01*
G01X1437449Y121543D02*
X1440649D01*
G01X1437230Y153200D02*
Y138484D01*
G01D02*
X1457308D01*
G01Y153200D02*
X1437230D01*
G01X1441369Y167117D02*
X1438169D01*
G01D02*
Y173317D01*
G01D02*
X1441369D01*
G01Y175117D02*
X1438169D01*
G01D02*
Y181317D01*
G01D02*
X1441369D01*
G01X1430519Y246050D02*
X1436719D01*
Y242850D01*
X1430519D01*
Y246050D01*
G01X1431825Y394600D02*
X1431287D01*
G01X1440576Y630225D02*
X1437476D01*
Y631145D01*
X1437631Y631452D01*
X1437993Y631682D01*
X1438406Y631759D01*
X1438819Y631682D01*
X1439129Y631490D01*
X1439284Y631145D01*
Y630225D01*
G01X1437476Y633325D02*
X1440576D01*
Y634859D01*
G01X1440111Y636349D02*
X1440369Y636579D01*
X1440524Y636847D01*
X1440576Y637192D01*
X1440473Y637537D01*
X1440266Y637805D01*
X1439904Y637997D01*
X1439491Y638035D01*
X1439078Y637959D01*
X1438819Y637767D01*
X1438613Y637499D01*
X1438561Y637230D01*
X1438613Y636962D01*
X1438819Y636617D01*
X1437476Y636732D01*
Y637767D01*
G01X1439956Y639449D02*
X1440318Y639679D01*
X1440524Y639985D01*
X1440576Y640330D01*
X1440524Y640637D01*
X1440266Y640944D01*
X1439956Y641135D01*
X1439646Y641174D01*
X1439284Y641097D01*
X1439026Y640829D01*
X1438923Y640560D01*
Y640215D01*
G01Y640560D02*
X1438768Y640790D01*
X1438509Y640982D01*
X1438199Y641059D01*
X1437889Y640982D01*
X1437631Y640790D01*
X1437476Y640445D01*
X1437528Y640100D01*
X1437734Y639755D01*
G01X1438521Y672619D02*
Y675719D01*
X1439441D01*
X1439748Y675564D01*
X1439978Y675202D01*
X1440055Y674789D01*
X1439978Y674376D01*
X1439786Y674066D01*
X1439441Y673911D01*
X1438521D01*
G01X1441545Y675719D02*
Y673497D01*
X1441698Y673032D01*
X1442005Y672722D01*
X1442388Y672619D01*
X1442771Y672722D01*
X1443078Y673032D01*
X1443231Y673497D01*
Y675719D01*
G01X1444760Y673911D02*
X1445028Y674272D01*
X1445258Y674479D01*
X1445565Y674582D01*
X1445833Y674479D01*
X1446025Y674272D01*
X1446178Y673962D01*
X1446216Y673601D01*
X1446178Y673291D01*
X1446025Y672981D01*
X1445795Y672722D01*
X1445526Y672619D01*
X1445220Y672722D01*
X1444951Y673032D01*
X1444798Y673497D01*
X1444760Y674014D01*
X1444836Y674686D01*
X1444951Y675047D01*
X1445143Y675409D01*
X1445411Y675667D01*
X1445680Y675719D01*
X1445948Y675616D01*
X1446140Y675357D01*
G01X1429157Y677365D02*
X1435357D01*
G01D02*
Y674165D01*
G01D02*
X1429157D01*
G01D02*
Y677365D01*
G01X1425676Y678473D02*
Y684673D01*
G01D02*
X1428876D01*
G01D02*
Y678473D01*
G01D02*
X1425676D01*
G01X1436343Y680969D02*
X1442543D01*
G01Y677769D02*
X1436343D01*
G01D02*
Y680969D01*
G01X1432918Y684673D02*
Y678473D01*
G01D02*
X1429718D01*
G01D02*
Y684673D01*
G01D02*
X1432918D01*
G01X1425197Y688076D02*
X1424464D01*
G01D02*
Y690267D01*
G01Y709098D02*
Y711698D01*
G01D02*
X1425257D01*
G01X1443398Y1012003D02*
X1437198D01*
Y1015203D01*
X1443398D01*
Y1012003D01*
G01X1428577Y1016344D02*
X1434777D01*
Y1013144D01*
X1428577D01*
Y1016344D01*
G01X1443398Y1008263D02*
X1437198D01*
Y1011463D01*
X1443398D01*
Y1008263D01*
G01Y1004522D02*
X1437198D01*
Y1007722D01*
X1443398D01*
Y1004522D01*
G01X1432124Y1004822D02*
Y1011022D01*
X1435324D01*
Y1004822D01*
X1432124D01*
G01X1428384D02*
Y1011022D01*
X1431584D01*
Y1004822D01*
X1428384D01*
G01X1424644D02*
Y1011022D01*
X1427844D01*
Y1004822D01*
X1424644D01*
G01X1428577Y1024612D02*
X1434777D01*
Y1021412D01*
X1428577D01*
Y1024612D01*
G01X1431589Y1033603D02*
Y1027403D01*
X1428389D01*
Y1033603D01*
X1431589D01*
G01X1435329D02*
Y1027403D01*
X1432129D01*
Y1033603D01*
X1435329D01*
G01X1427849D02*
Y1027403D01*
X1424649D01*
Y1033603D01*
X1427849D01*
G01X1443398Y1015743D02*
X1437198D01*
Y1018943D01*
X1443398D01*
Y1015743D01*
G01X1428577Y1020478D02*
X1434777D01*
Y1017278D01*
X1428577D01*
Y1020478D01*
G01X1443398Y1026963D02*
X1437198D01*
Y1030163D01*
X1443398D01*
Y1026963D01*
G01Y1019483D02*
X1437198D01*
Y1022683D01*
X1443398D01*
Y1019483D01*
G01Y1023223D02*
X1437198D01*
Y1026423D01*
X1443398D01*
Y1023223D01*
G01Y1030703D02*
X1437198D01*
Y1033903D01*
X1443398D01*
Y1030703D01*
G01X1437000Y1256024D02*
X1600661D01*
G01X1436932Y1279860D02*
X1438500D01*
G01X1436932Y1273660D02*
Y1279860D01*
G01X1438500Y1273660D02*
X1436932D01*
G01X1432292Y1296757D02*
X1429192D01*
Y1297677D01*
X1429347Y1297984D01*
X1429709Y1298214D01*
X1430122Y1298291D01*
X1430535Y1298214D01*
X1430845Y1298022D01*
X1431000Y1297677D01*
Y1296757D01*
G01X1429192Y1299857D02*
X1432292D01*
Y1301391D01*
G01X1431930Y1303072D02*
X1432189Y1303341D01*
X1432292Y1303647D01*
X1432189Y1303954D01*
X1431879Y1304222D01*
X1431414Y1304414D01*
X1430949Y1304491D01*
X1430380D01*
X1429915Y1304414D01*
X1429502Y1304222D01*
X1429295Y1303992D01*
X1429192Y1303724D01*
X1429295Y1303417D01*
X1429502Y1303187D01*
X1429812Y1303034D01*
X1430225Y1302957D01*
X1430587Y1303034D01*
X1430949Y1303226D01*
X1431155Y1303456D01*
X1431207Y1303724D01*
X1431104Y1304031D01*
X1430845Y1304261D01*
X1430380Y1304491D01*
G01X1427354Y1322169D02*
Y1296579D01*
G01X1434556Y1603435D02*
Y1594773D01*
G01X1424062D02*
Y1603435D01*
G01X1427409Y1594773D02*
X1424062D01*
G01X1429309Y1596973D02*
X1427409Y1594773D01*
G01X1431209D02*
X1429309Y1596973D01*
G01X1434556Y1594773D02*
X1431209D01*
G01Y1608366D02*
Y1611566D01*
G01X1437409Y1608366D02*
X1431209D01*
G01X1437409Y1611566D02*
Y1608366D01*
G01X1428397Y1611504D02*
Y1608304D01*
G01X1424062Y1603435D02*
X1434556D01*
G01X1437409Y1615504D02*
Y1612304D01*
G01X1431209Y1615504D02*
X1437409D01*
G01X1431209Y1612304D02*
Y1615504D01*
G01X1437409Y1612304D02*
X1431209D01*
G01X1437597Y1625104D02*
Y1621904D01*
G01X1431397Y1625104D02*
X1437597D01*
G01X1431397Y1621904D02*
Y1625104D01*
G01X1437597Y1621904D02*
X1431397D01*
G01X1428397Y1621104D02*
Y1617904D01*
G01X1431209Y1611566D02*
X1437409D01*
G01X1428397Y1615566D02*
Y1612366D01*
G01X1431397Y1617966D02*
Y1621166D01*
G01X1437597Y1617966D02*
X1431397D01*
G01X1437597Y1621166D02*
Y1617966D01*
G01X1431397Y1621166D02*
X1437597D01*
G01X1428397Y1624966D02*
Y1621766D01*
G01X1437194Y1632122D02*
X1437142Y1631815D01*
X1436936Y1631547D01*
X1436626Y1631317D01*
X1436264Y1631164D01*
X1435851Y1631087D01*
X1435437D01*
X1435024Y1631164D01*
X1434662Y1631317D01*
X1434352Y1631547D01*
X1434146Y1631815D01*
X1434094Y1632122D01*
X1434146Y1632429D01*
X1434352Y1632697D01*
X1434662Y1632927D01*
X1435024Y1633080D01*
X1435437Y1633157D01*
X1435851D01*
X1436264Y1633080D01*
X1436626Y1632927D01*
X1436936Y1632697D01*
X1437142Y1632429D01*
X1437194Y1632122D01*
G01X1436367Y1632429D02*
X1437194Y1632889D01*
G01X1436832Y1634570D02*
X1437091Y1634839D01*
X1437194Y1635145D01*
X1437091Y1635452D01*
X1436781Y1635720D01*
X1436316Y1635912D01*
X1435851Y1635989D01*
X1435282D01*
X1434817Y1635912D01*
X1434404Y1635720D01*
X1434197Y1635490D01*
X1434094Y1635222D01*
X1434197Y1634915D01*
X1434404Y1634685D01*
X1434714Y1634532D01*
X1435127Y1634455D01*
X1435489Y1634532D01*
X1435851Y1634724D01*
X1436057Y1634954D01*
X1436109Y1635222D01*
X1436006Y1635529D01*
X1435747Y1635759D01*
X1435282Y1635989D01*
G01X1434094Y1638322D02*
X1434197Y1638015D01*
X1434456Y1637785D01*
X1434766Y1637632D01*
X1435179Y1637517D01*
X1435644Y1637479D01*
X1436109Y1637517D01*
X1436522Y1637632D01*
X1436832Y1637785D01*
X1437091Y1638015D01*
X1437194Y1638322D01*
X1437091Y1638629D01*
X1436832Y1638859D01*
X1436522Y1639012D01*
X1436109Y1639127D01*
X1435644Y1639165D01*
X1435179Y1639127D01*
X1434766Y1639012D01*
X1434456Y1638859D01*
X1434197Y1638629D01*
X1434094Y1638322D01*
G01Y1641422D02*
X1434197Y1641115D01*
X1434456Y1640885D01*
X1434766Y1640732D01*
X1435179Y1640617D01*
X1435644Y1640579D01*
X1436109Y1640617D01*
X1436522Y1640732D01*
X1436832Y1640885D01*
X1437091Y1641115D01*
X1437194Y1641422D01*
X1437091Y1641729D01*
X1436832Y1641959D01*
X1436522Y1642112D01*
X1436109Y1642227D01*
X1435644Y1642265D01*
X1435179Y1642227D01*
X1434766Y1642112D01*
X1434456Y1641959D01*
X1434197Y1641729D01*
X1434094Y1641422D01*
G01Y1644522D02*
X1434197Y1644215D01*
X1434456Y1643985D01*
X1434766Y1643832D01*
X1435179Y1643717D01*
X1435644Y1643679D01*
X1436109Y1643717D01*
X1436522Y1643832D01*
X1436832Y1643985D01*
X1437091Y1644215D01*
X1437194Y1644522D01*
X1437091Y1644829D01*
X1436832Y1645059D01*
X1436522Y1645212D01*
X1436109Y1645327D01*
X1435644Y1645365D01*
X1435179Y1645327D01*
X1434766Y1645212D01*
X1434456Y1645059D01*
X1434197Y1644829D01*
X1434094Y1644522D01*
G01X1433403Y1631482D02*
X1424741D01*
G01X1433403Y1641976D02*
Y1631482D01*
G01X1424741Y1638629D02*
Y1641976D01*
G01X1426941Y1636729D02*
X1424741Y1638629D01*
G01Y1634829D02*
X1426941Y1636729D01*
G01X1424741Y1631482D02*
Y1634829D01*
G01X1438236Y1644927D02*
Y1637196D01*
G01D02*
X1457922D01*
G01X1433486Y1648687D02*
Y1645487D01*
G01X1427286Y1648687D02*
X1433486D01*
G01X1427286Y1645487D02*
Y1648687D01*
G01X1433486Y1645487D02*
X1427286D01*
G01X1424741Y1641976D02*
X1433403D01*
G01X1434658Y1650557D02*
X1436880D01*
X1437345Y1650710D01*
X1437655Y1651017D01*
X1437758Y1651400D01*
X1437655Y1651783D01*
X1437345Y1652090D01*
X1436880Y1652243D01*
X1434658D01*
G01X1435175Y1653772D02*
X1434865Y1654002D01*
X1434710Y1654270D01*
X1434658Y1654577D01*
X1434761Y1654960D01*
X1435020Y1655228D01*
X1435330Y1655305D01*
X1435640Y1655267D01*
X1435898Y1655113D01*
X1436415Y1654347D01*
X1436776Y1654002D01*
X1437293Y1653772D01*
X1437758Y1653695D01*
Y1655305D01*
G01Y1657523D02*
X1437086Y1657600D01*
X1436518Y1657715D01*
X1436001Y1657868D01*
X1435433Y1658060D01*
X1434658Y1658367D01*
Y1656833D01*
G01Y1660700D02*
X1434761Y1660393D01*
X1435020Y1660163D01*
X1435330Y1660010D01*
X1435743Y1659895D01*
X1436208Y1659857D01*
X1436673Y1659895D01*
X1437086Y1660010D01*
X1437396Y1660163D01*
X1437655Y1660393D01*
X1437758Y1660700D01*
X1437655Y1661007D01*
X1437396Y1661237D01*
X1437086Y1661390D01*
X1436673Y1661505D01*
X1436208Y1661543D01*
X1435743Y1661505D01*
X1435330Y1661390D01*
X1435020Y1661237D01*
X1434761Y1661007D01*
X1434658Y1660700D01*
G01X1444079Y1650770D02*
X1438236Y1644927D01*
G01Y1664344D02*
Y1656613D01*
G01D02*
X1444079Y1650770D01*
G01X1457922Y1664344D02*
X1438236D01*
G01X1430315Y1656969D02*
Y1705500D01*
G01Y1723500D02*
Y1736118D01*
G01X1438606Y1733036D02*
Y1736136D01*
G01X1440216D02*
Y1733036D01*
G01Y1734586D02*
X1438606D01*
G01X1442511Y1733036D02*
Y1736136D01*
X1442051Y1735516D01*
G01Y1733036D02*
X1442971D01*
G01X1444883Y1735619D02*
X1445113Y1735929D01*
X1445381Y1736084D01*
X1445688Y1736136D01*
X1446071Y1736033D01*
X1446339Y1735774D01*
X1446416Y1735464D01*
X1446378Y1735154D01*
X1446224Y1734896D01*
X1445458Y1734379D01*
X1445113Y1734018D01*
X1444883Y1733501D01*
X1444806Y1733036D01*
X1446416D01*
G01X1448711D02*
X1448979Y1733088D01*
X1449286Y1733243D01*
X1449478Y1733501D01*
X1449554Y1733863D01*
X1449478Y1734224D01*
X1449248Y1734534D01*
X1448903Y1734689D01*
X1448519D01*
X1448289Y1734793D01*
X1448098Y1735051D01*
X1448021Y1735413D01*
X1448136Y1735774D01*
X1448404Y1736033D01*
X1448711Y1736136D01*
X1449018Y1736033D01*
X1449286Y1735774D01*
X1449401Y1735413D01*
X1449324Y1735051D01*
X1449133Y1734793D01*
X1448903Y1734689D01*
X1448519D01*
X1448174Y1734534D01*
X1447944Y1734224D01*
X1447868Y1733863D01*
X1447944Y1733501D01*
X1448136Y1733243D01*
X1448443Y1733088D01*
X1448711Y1733036D01*
G01X1439862Y59992D02*
Y53792D01*
G01X1450096Y60173D02*
X1447494Y62775D01*
G01X1443272D02*
Y50571D01*
G01D02*
X1456920D01*
G01X1452698Y62775D02*
X1450096Y60173D01*
G01X1443303Y67440D02*
Y65218D01*
X1443456Y64753D01*
X1443763Y64443D01*
X1444146Y64340D01*
X1444529Y64443D01*
X1444836Y64753D01*
X1444989Y65218D01*
Y67440D01*
G01X1447246Y64340D02*
Y67440D01*
X1446786Y66820D01*
G01Y64340D02*
X1447706D01*
G01X1450346Y67440D02*
X1450039Y67337D01*
X1449809Y67078D01*
X1449656Y66768D01*
X1449541Y66355D01*
X1449503Y65890D01*
X1449541Y65425D01*
X1449656Y65012D01*
X1449809Y64702D01*
X1450039Y64443D01*
X1450346Y64340D01*
X1450653Y64443D01*
X1450883Y64702D01*
X1451036Y65012D01*
X1451151Y65425D01*
X1451189Y65890D01*
X1451151Y66355D01*
X1451036Y66768D01*
X1450883Y67078D01*
X1450653Y67337D01*
X1450346Y67440D01*
G01X1453906Y64340D02*
Y67440D01*
X1452488Y65218D01*
X1454404D01*
G01X1447494Y62775D02*
X1443272D01*
G01X1456920D02*
X1452698D01*
G01X1450860Y94125D02*
Y92156D01*
G01D02*
X1460703D01*
G01X1448469Y112961D02*
Y106761D01*
G01D02*
X1445269D01*
G01D02*
Y112961D01*
G01D02*
X1448469D01*
G01X1446949Y115543D02*
Y121743D01*
G01X1450149D02*
Y115543D01*
G01D02*
X1446949D01*
G01X1441449Y108343D02*
Y114543D01*
G01D02*
X1444649D01*
G01D02*
Y108343D01*
G01D02*
X1441449D01*
G01X1440649Y114543D02*
Y108343D01*
G01X1444649Y121543D02*
Y115343D01*
G01D02*
X1441449D01*
G01D02*
Y121543D01*
G01X1440649D02*
Y115343D01*
G01X1452949Y108343D02*
Y114543D01*
G01D02*
X1456149D01*
G01Y108343D02*
X1452949D01*
G01X1456149Y115343D02*
X1452949D01*
G01D02*
Y121543D01*
G01X1446949Y121743D02*
X1450149D01*
G01X1441449Y121543D02*
X1444649D01*
G01X1452949D02*
X1456149D01*
G01X1453269Y145842D02*
X1457308Y149881D01*
G01Y141803D02*
X1453269Y145842D01*
G01X1446369Y173317D02*
Y167117D01*
G01D02*
X1443169D01*
G01D02*
Y173317D01*
G01D02*
X1446369D01*
G01X1441369D02*
Y167117D01*
G01X1451369Y173317D02*
Y167117D01*
G01D02*
X1448169D01*
G01D02*
Y173317D01*
G01D02*
X1451369D01*
G01X1441369Y181317D02*
Y175117D01*
G01X1451369Y181317D02*
Y175117D01*
G01D02*
X1448169D01*
G01D02*
Y181317D01*
G01X1456369Y167117D02*
X1453169D01*
G01D02*
Y173317D01*
G01D02*
X1456369D01*
G01X1448169Y181317D02*
X1451369D01*
G01X1443519Y246050D02*
X1449719D01*
Y242850D01*
X1443519D01*
Y246050D01*
G01X1441394Y303843D02*
Y297843D01*
X1447394D01*
G01X1442634Y309443D02*
X1443381Y308818D01*
X1444221Y308443D01*
X1444967D01*
X1445714Y308818D01*
X1446274Y309443D01*
X1446554Y310318D01*
X1446367Y311193D01*
X1445901Y311943D01*
X1445061Y312443D01*
X1443941Y312693D01*
X1443287Y313193D01*
X1443007Y314068D01*
X1443194Y314943D01*
X1443661Y315568D01*
X1444314Y315943D01*
X1444967D01*
X1445621Y315693D01*
X1446181Y315068D01*
G01X1450414Y308193D02*
X1453774Y315943D01*
G01X1457447Y308443D02*
Y315943D01*
X1461741Y308443D01*
Y315943D01*
G01X1447394Y317528D02*
X1441394D01*
Y311528D01*
G01X1443341Y600966D02*
Y594766D01*
G01D02*
X1440141D01*
G01D02*
Y600966D01*
G01D02*
X1443341D01*
G01X1442246Y641566D02*
Y617550D01*
G01D02*
X1448357D01*
G01Y641566D02*
X1442246D01*
G01X1446513Y683863D02*
Y677663D01*
G01D02*
X1443313D01*
G01D02*
Y683863D01*
G01D02*
X1446513D01*
G01X1450407Y692494D02*
Y686294D01*
G01D02*
X1447207D01*
G01D02*
Y687800D01*
G01X1442543Y680969D02*
Y677769D01*
G01X1447207Y692494D02*
X1450407D01*
G01X1447207Y690400D02*
Y692494D01*
G01Y696794D02*
Y702994D01*
G01X1450407D02*
Y696794D01*
G01D02*
X1447207D01*
G01X1444150Y702487D02*
Y700789D01*
G01Y689930D02*
Y688076D01*
G01D02*
X1443142D01*
G01X1451165Y715807D02*
Y722007D01*
G01X1454365Y715807D02*
X1451165D01*
G01X1447207Y702994D02*
X1450407D01*
G01X1445750Y713315D02*
X1451950D01*
G01D02*
Y710115D01*
G01D02*
X1445750D01*
G01D02*
Y713315D01*
G01X1450384Y709815D02*
Y703615D01*
G01D02*
X1447184D01*
G01D02*
Y709815D01*
G01D02*
X1450384D01*
G01X1443357Y711698D02*
X1444150D01*
G01D02*
Y709098D01*
G01X1448607Y758223D02*
Y714915D01*
G01D02*
X1443266D01*
G01X1451165Y722007D02*
X1454365D01*
G01X1451997Y734492D02*
X1457338D01*
G01X1451997Y777800D02*
Y734492D01*
G01X1443266Y758223D02*
X1448607D01*
G01X1450562Y766918D02*
X1447462D01*
Y767838D01*
X1447617Y768145D01*
X1447979Y768375D01*
X1448392Y768452D01*
X1448805Y768375D01*
X1449115Y768183D01*
X1449270Y767838D01*
Y766918D01*
G01X1447462Y770018D02*
X1450562D01*
Y771552D01*
G01X1450097Y773042D02*
X1450355Y773272D01*
X1450510Y773540D01*
X1450562Y773885D01*
X1450459Y774230D01*
X1450252Y774498D01*
X1449890Y774690D01*
X1449477Y774728D01*
X1449064Y774652D01*
X1448805Y774460D01*
X1448599Y774192D01*
X1448547Y773923D01*
X1448599Y773655D01*
X1448805Y773310D01*
X1447462Y773425D01*
Y774460D01*
G01X1447979Y776257D02*
X1447669Y776487D01*
X1447514Y776755D01*
X1447462Y777062D01*
X1447565Y777445D01*
X1447824Y777713D01*
X1448134Y777790D01*
X1448444Y777752D01*
X1448702Y777598D01*
X1449219Y776832D01*
X1449580Y776487D01*
X1450097Y776257D01*
X1450562Y776180D01*
Y777790D01*
G01X1457338Y777800D02*
X1451997D01*
G01X1444559Y1034961D02*
Y1003465D01*
G01X1450934Y1270392D02*
X1447734D01*
G01X1450934Y1276592D02*
Y1270392D01*
G01X1447734Y1276592D02*
X1450934D01*
G01X1447734Y1270392D02*
Y1276592D01*
G01X1454934Y1270392D02*
X1451734D01*
G01Y1276592D02*
X1454934D01*
G01X1451734Y1270392D02*
Y1276592D01*
G01X1440132Y1278300D02*
Y1275400D01*
G01X1444132Y1273660D02*
X1442800D01*
G01X1444132Y1279860D02*
Y1273660D01*
G01X1442600Y1279860D02*
X1444132D01*
G01X1440932Y1275400D02*
Y1278300D01*
G01X1600661Y1393819D02*
X1449848D01*
G01X1439305D02*
X1445264D01*
G01X1449480Y1540451D02*
Y1557400D01*
G01X1454900Y1540451D02*
X1449480D01*
G01Y1561800D02*
Y1575491D01*
G01X1440838Y1572911D02*
Y1569503D01*
G01X1449480Y1575491D02*
X1455800D01*
G01X1443812Y1592840D02*
X1443760Y1592533D01*
X1443554Y1592265D01*
X1443244Y1592035D01*
X1442882Y1591882D01*
X1442469Y1591805D01*
X1442055D01*
X1441642Y1591882D01*
X1441280Y1592035D01*
X1440970Y1592265D01*
X1440764Y1592533D01*
X1440712Y1592840D01*
X1440764Y1593147D01*
X1440970Y1593415D01*
X1441280Y1593645D01*
X1441642Y1593798D01*
X1442055Y1593875D01*
X1442469D01*
X1442882Y1593798D01*
X1443244Y1593645D01*
X1443554Y1593415D01*
X1443760Y1593147D01*
X1443812Y1592840D01*
G01X1442985Y1593147D02*
X1443812Y1593607D01*
G01X1443450Y1595288D02*
X1443709Y1595557D01*
X1443812Y1595863D01*
X1443709Y1596170D01*
X1443399Y1596438D01*
X1442934Y1596630D01*
X1442469Y1596707D01*
X1441900D01*
X1441435Y1596630D01*
X1441022Y1596438D01*
X1440815Y1596208D01*
X1440712Y1595940D01*
X1440815Y1595633D01*
X1441022Y1595403D01*
X1441332Y1595250D01*
X1441745Y1595173D01*
X1442107Y1595250D01*
X1442469Y1595442D01*
X1442675Y1595672D01*
X1442727Y1595940D01*
X1442624Y1596247D01*
X1442365Y1596477D01*
X1441900Y1596707D01*
G01X1440712Y1599040D02*
X1440815Y1598733D01*
X1441074Y1598503D01*
X1441384Y1598350D01*
X1441797Y1598235D01*
X1442262Y1598197D01*
X1442727Y1598235D01*
X1443140Y1598350D01*
X1443450Y1598503D01*
X1443709Y1598733D01*
X1443812Y1599040D01*
X1443709Y1599347D01*
X1443450Y1599577D01*
X1443140Y1599730D01*
X1442727Y1599845D01*
X1442262Y1599883D01*
X1441797Y1599845D01*
X1441384Y1599730D01*
X1441074Y1599577D01*
X1440815Y1599347D01*
X1440712Y1599040D01*
G01Y1602140D02*
X1440815Y1601833D01*
X1441074Y1601603D01*
X1441384Y1601450D01*
X1441797Y1601335D01*
X1442262Y1601297D01*
X1442727Y1601335D01*
X1443140Y1601450D01*
X1443450Y1601603D01*
X1443709Y1601833D01*
X1443812Y1602140D01*
X1443709Y1602447D01*
X1443450Y1602677D01*
X1443140Y1602830D01*
X1442727Y1602945D01*
X1442262Y1602983D01*
X1441797Y1602945D01*
X1441384Y1602830D01*
X1441074Y1602677D01*
X1440815Y1602447D01*
X1440712Y1602140D01*
G01X1441229Y1604512D02*
X1440919Y1604742D01*
X1440764Y1605010D01*
X1440712Y1605317D01*
X1440815Y1605700D01*
X1441074Y1605968D01*
X1441384Y1606045D01*
X1441694Y1606007D01*
X1441952Y1605853D01*
X1442469Y1605087D01*
X1442830Y1604742D01*
X1443347Y1604512D01*
X1443812Y1604435D01*
Y1606045D01*
G01X1440838Y1587219D02*
Y1583811D01*
G01X1452100Y1631600D02*
Y1625400D01*
G01D02*
X1448900D01*
G01D02*
Y1631600D01*
G01X1443900Y1625400D02*
Y1631600D01*
G01X1447100D02*
Y1625400D01*
G01D02*
X1443900D01*
G01X1438900D02*
Y1631600D01*
G01X1442100D02*
Y1625400D01*
G01D02*
X1438900D01*
G01X1442100Y1622100D02*
Y1615900D01*
G01X1438900Y1622100D02*
X1442100D01*
G01X1438900Y1615900D02*
Y1622100D01*
G01X1442100Y1615900D02*
X1438900D01*
G01X1443900Y1622100D02*
X1447100D01*
G01X1443900Y1615900D02*
Y1622100D01*
G01X1447100D02*
Y1615900D01*
G01D02*
X1443900D01*
G01X1448900D02*
Y1622100D01*
X1452100D01*
Y1615900D01*
X1448900D01*
G01Y1631600D02*
X1452100D01*
G01X1443900D02*
X1447100D01*
G01X1438900D02*
X1442100D01*
G01X1444179Y1666203D02*
X1440979D01*
G01D02*
Y1672403D01*
G01X1444179D02*
Y1666203D01*
G01X1445979D02*
Y1672403D01*
G01X1449179Y1666203D02*
X1445979D01*
G01X1449179Y1672403D02*
Y1666203D01*
G01X1454179D02*
X1450979D01*
G01D02*
Y1672403D01*
G01X1440979D02*
X1444179D01*
G01X1447470Y1679622D02*
Y1685822D01*
G01X1450670Y1679622D02*
X1447470D01*
G01X1450670Y1685822D02*
Y1679622D01*
G01X1447470Y1685822D02*
X1450670D01*
G01X1445979Y1672403D02*
X1449179D01*
G01X1450979D02*
X1454179D01*
G01X1446679Y1679578D02*
X1443479D01*
G01X1446679Y1685778D02*
Y1679578D01*
G01X1443479D02*
Y1685778D01*
G01D02*
X1446679D01*
G01X1461172Y-24986D02*
X1461482Y-24794D01*
X1461689Y-24564D01*
X1461792Y-24296D01*
X1461689Y-23989D01*
X1461482Y-23759D01*
X1461172Y-23529D01*
X1460759Y-23452D01*
X1458692D01*
G01X1460500Y-21847D02*
X1460139Y-21579D01*
X1459932Y-21349D01*
X1459829Y-21042D01*
X1459932Y-20774D01*
X1460139Y-20582D01*
X1460449Y-20429D01*
X1460810Y-20391D01*
X1461120Y-20429D01*
X1461430Y-20582D01*
X1461689Y-20812D01*
X1461792Y-21081D01*
X1461689Y-21387D01*
X1461379Y-21656D01*
X1460914Y-21809D01*
X1460397Y-21847D01*
X1459725Y-21771D01*
X1459364Y-21656D01*
X1459002Y-21464D01*
X1458744Y-21196D01*
X1458692Y-20927D01*
X1458795Y-20659D01*
X1459054Y-20467D01*
G01X1461327Y-18862D02*
X1461585Y-18632D01*
X1461740Y-18364D01*
X1461792Y-18019D01*
X1461689Y-17674D01*
X1461482Y-17406D01*
X1461120Y-17214D01*
X1460707Y-17176D01*
X1460294Y-17252D01*
X1460035Y-17444D01*
X1459829Y-17712D01*
X1459777Y-17981D01*
X1459829Y-18249D01*
X1460035Y-18594D01*
X1458692Y-18479D01*
Y-17444D01*
G01X1461400Y-7732D02*
X1461710Y-7540D01*
X1461917Y-7310D01*
X1462020Y-7042D01*
X1461917Y-6735D01*
X1461710Y-6505D01*
X1461400Y-6275D01*
X1460987Y-6198D01*
X1458920D01*
G01X1462020Y-3865D02*
X1461968Y-3597D01*
X1461813Y-3290D01*
X1461555Y-3098D01*
X1461193Y-3022D01*
X1460832Y-3098D01*
X1460522Y-3328D01*
X1460367Y-3673D01*
Y-4057D01*
X1460263Y-4287D01*
X1460005Y-4478D01*
X1459643Y-4555D01*
X1459282Y-4440D01*
X1459023Y-4172D01*
X1458920Y-3865D01*
X1459023Y-3558D01*
X1459282Y-3290D01*
X1459643Y-3175D01*
X1460005Y-3252D01*
X1460263Y-3443D01*
X1460367Y-3673D01*
Y-4057D01*
X1460522Y-4402D01*
X1460832Y-4632D01*
X1461193Y-4708D01*
X1461555Y-4632D01*
X1461813Y-4440D01*
X1461968Y-4133D01*
X1462020Y-3865D01*
G01X1458920Y-765D02*
X1459023Y-1072D01*
X1459282Y-1302D01*
X1459592Y-1455D01*
X1460005Y-1570D01*
X1460470Y-1608D01*
X1460935Y-1570D01*
X1461348Y-1455D01*
X1461658Y-1302D01*
X1461917Y-1072D01*
X1462020Y-765D01*
X1461917Y-458D01*
X1461658Y-228D01*
X1461348Y-75D01*
X1460935Y40D01*
X1460470Y78D01*
X1460005Y40D01*
X1459592Y-75D01*
X1459282Y-228D01*
X1459023Y-458D01*
X1458920Y-765D01*
G01X1460728Y1607D02*
X1460367Y1875D01*
X1460160Y2105D01*
X1460057Y2412D01*
X1460160Y2680D01*
X1460367Y2872D01*
X1460677Y3025D01*
X1461038Y3063D01*
X1461348Y3025D01*
X1461658Y2872D01*
X1461917Y2642D01*
X1462020Y2373D01*
X1461917Y2067D01*
X1461607Y1798D01*
X1461142Y1645D01*
X1460625Y1607D01*
X1459953Y1683D01*
X1459592Y1798D01*
X1459230Y1990D01*
X1458972Y2258D01*
X1458920Y2527D01*
X1459023Y2795D01*
X1459282Y2987D01*
G01X1462020Y5358D02*
X1461348Y5435D01*
X1460780Y5550D01*
X1460263Y5703D01*
X1459695Y5895D01*
X1458920Y6202D01*
Y4668D01*
G01X1460601Y16149D02*
X1460911Y16341D01*
X1461118Y16571D01*
X1461221Y16839D01*
X1461118Y17146D01*
X1460911Y17376D01*
X1460601Y17606D01*
X1460188Y17683D01*
X1458121D01*
G01X1459929Y19288D02*
X1459568Y19556D01*
X1459361Y19786D01*
X1459258Y20093D01*
X1459361Y20361D01*
X1459568Y20553D01*
X1459878Y20706D01*
X1460239Y20744D01*
X1460549Y20706D01*
X1460859Y20553D01*
X1461118Y20323D01*
X1461221Y20054D01*
X1461118Y19748D01*
X1460808Y19479D01*
X1460343Y19326D01*
X1459826Y19288D01*
X1459154Y19364D01*
X1458793Y19479D01*
X1458431Y19671D01*
X1458173Y19939D01*
X1458121Y20208D01*
X1458224Y20476D01*
X1458483Y20668D01*
G01X1460601Y22273D02*
X1460963Y22503D01*
X1461169Y22809D01*
X1461221Y23154D01*
X1461169Y23461D01*
X1460911Y23768D01*
X1460601Y23959D01*
X1460291Y23998D01*
X1459929Y23921D01*
X1459671Y23653D01*
X1459568Y23384D01*
Y23039D01*
G01Y23384D02*
X1459413Y23614D01*
X1459154Y23806D01*
X1458844Y23883D01*
X1458534Y23806D01*
X1458276Y23614D01*
X1458121Y23269D01*
X1458173Y22924D01*
X1458379Y22579D01*
G01X1458296Y56888D02*
Y63088D01*
G01X1461496D02*
Y56888D01*
G01D02*
X1458296D01*
G01X1469505Y59963D02*
X1463305D01*
G01D02*
Y63163D01*
G01X1456920Y50571D02*
Y62775D01*
G01X1458296Y63088D02*
X1461496D01*
G01X1463305Y63163D02*
X1469505D01*
G01X1462671Y75621D02*
Y83889D01*
G01D02*
Y94125D01*
G01X1460703Y92156D02*
Y77589D01*
G01D02*
X1457036D01*
G01X1456149Y114543D02*
Y108343D01*
G01Y121543D02*
Y115343D01*
G01X1454142Y129842D02*
X1460342D01*
G01D02*
Y126642D01*
G01D02*
X1454142D01*
G01D02*
Y129842D01*
G01X1462108Y141043D02*
Y134843D01*
G01D02*
X1458908D01*
G01D02*
Y141043D01*
G01D02*
X1462108D01*
G01X1460848Y144378D02*
X1463070D01*
X1463535Y144531D01*
X1463845Y144838D01*
X1463948Y145221D01*
X1463845Y145604D01*
X1463535Y145911D01*
X1463070Y146064D01*
X1460848D01*
G01X1463948Y148321D02*
X1460848D01*
X1461468Y147861D01*
G01X1463948D02*
Y148781D01*
G01Y151421D02*
X1460848D01*
X1461468Y150961D01*
G01X1463948D02*
Y151881D01*
G01X1462656Y153793D02*
X1462295Y154061D01*
X1462088Y154291D01*
X1461985Y154598D01*
X1462088Y154866D01*
X1462295Y155058D01*
X1462605Y155211D01*
X1462966Y155249D01*
X1463276Y155211D01*
X1463586Y155058D01*
X1463845Y154828D01*
X1463948Y154559D01*
X1463845Y154253D01*
X1463535Y153984D01*
X1463070Y153831D01*
X1462553Y153793D01*
X1461881Y153869D01*
X1461520Y153984D01*
X1461158Y154176D01*
X1460900Y154444D01*
X1460848Y154713D01*
X1460951Y154981D01*
X1461210Y155173D01*
G01X1457308Y149881D02*
Y153200D01*
G01Y138484D02*
Y141803D01*
G01X1456369Y173317D02*
Y167117D01*
G01X1467496Y396845D02*
Y401845D01*
X1469016D01*
X1469523Y401595D01*
X1469903Y401012D01*
X1470030Y400345D01*
X1469903Y399678D01*
X1469586Y399178D01*
X1469016Y398928D01*
X1467496D01*
G01X1473863Y396845D02*
X1473356Y396928D01*
X1472913Y397262D01*
X1472533Y397762D01*
X1472280Y398345D01*
X1472153Y399012D01*
Y399678D01*
X1472280Y400345D01*
X1472533Y400928D01*
X1472913Y401428D01*
X1473356Y401762D01*
X1473863Y401845D01*
X1474370Y401762D01*
X1474813Y401428D01*
X1475193Y400928D01*
X1475446Y400345D01*
X1475573Y399678D01*
Y399012D01*
X1475446Y398345D01*
X1475193Y397762D01*
X1474813Y397262D01*
X1474370Y396928D01*
X1473863Y396845D01*
G01X1477633Y397512D02*
X1478140Y397095D01*
X1478710Y396845D01*
X1479216D01*
X1479723Y397095D01*
X1480103Y397512D01*
X1480293Y398095D01*
X1480166Y398678D01*
X1479850Y399178D01*
X1479280Y399512D01*
X1478520Y399678D01*
X1478076Y400012D01*
X1477886Y400595D01*
X1478013Y401178D01*
X1478330Y401595D01*
X1478773Y401845D01*
X1479216D01*
X1479660Y401678D01*
X1480040Y401262D01*
G01X1484063Y401845D02*
Y396845D01*
G01X1482606Y401845D02*
X1485520D01*
G01X1492996D02*
Y396845D01*
X1495530D01*
G01X1500630D02*
X1498096D01*
Y401845D01*
X1500630D01*
G01X1499616Y399428D02*
X1498096D01*
G01X1503070Y396845D02*
Y401845D01*
X1504336D01*
X1504843Y401595D01*
X1505223Y401262D01*
X1505540Y400762D01*
X1505793Y400178D01*
X1505856Y399345D01*
X1505793Y398512D01*
X1505540Y397928D01*
X1505223Y397428D01*
X1504843Y397095D01*
X1504336Y396845D01*
X1503070D01*
G01X1467306Y405445D02*
Y410445D01*
X1470220Y405445D01*
Y410445D01*
G01X1472723Y405278D02*
X1475003Y410445D01*
G01X1477380Y405445D02*
X1478963Y410445D01*
X1480546Y405445D01*
G01X1479976Y407195D02*
X1477950D01*
G01X1463074Y493600D02*
Y394600D01*
G01X1467560Y414045D02*
Y419045D01*
X1469966D01*
G01X1469080Y416628D02*
X1467560D01*
G01X1472596Y414045D02*
Y419045D01*
X1474116D01*
X1474623Y418795D01*
X1475003Y418212D01*
X1475130Y417545D01*
X1475003Y416878D01*
X1474686Y416378D01*
X1474116Y416128D01*
X1472596D01*
G01X1479343Y416545D02*
X1480610D01*
Y415045D01*
X1480230Y414545D01*
X1479786Y414212D01*
X1479153Y414045D01*
X1478520Y414212D01*
X1478076Y414545D01*
X1477696Y415045D01*
X1477443Y415628D01*
X1477316Y416295D01*
Y416878D01*
X1477443Y417378D01*
X1477696Y417962D01*
X1478076Y418462D01*
X1478456Y418795D01*
X1478963Y419045D01*
X1479406D01*
X1479913Y418878D01*
X1480293Y418545D01*
G01X1482480Y414045D02*
X1484063Y419045D01*
X1485646Y414045D01*
G01X1485076Y415795D02*
X1483050D01*
G01X1495656Y418628D02*
X1495276Y418878D01*
X1494833Y419045D01*
X1494326D01*
X1493756Y418795D01*
X1493313Y418378D01*
X1492996Y417878D01*
X1492743Y417045D01*
X1492680Y416295D01*
X1492806Y415545D01*
X1492996Y415045D01*
X1493376Y414545D01*
X1493820Y414212D01*
X1494263Y414045D01*
X1494706D01*
X1495150Y414212D01*
X1495530Y414462D01*
X1495846Y414795D01*
G01X1499363Y419045D02*
Y414045D01*
G01X1497906Y419045D02*
X1500820D01*
G01X1503196Y414045D02*
Y419045D01*
X1504780D01*
X1505286Y418795D01*
X1505603Y418462D01*
X1505730Y417795D01*
X1505603Y417128D01*
X1505223Y416712D01*
X1504780Y416462D01*
X1503196D01*
G01X1504780D02*
X1505730Y414045D01*
G01X1508296Y419045D02*
Y414045D01*
X1510830D01*
G01X1467370Y432245D02*
Y437245D01*
X1468636D01*
X1469143Y436995D01*
X1469523Y436662D01*
X1469840Y436162D01*
X1470093Y435578D01*
X1470156Y434745D01*
X1470093Y433912D01*
X1469840Y433328D01*
X1469523Y432828D01*
X1469143Y432495D01*
X1468636Y432245D01*
X1467370D01*
G01X1473103Y437245D02*
X1474623D01*
G01X1473863D02*
Y432245D01*
G01X1473103D02*
X1474623D01*
G01X1477633Y432912D02*
X1478140Y432495D01*
X1478710Y432245D01*
X1479216D01*
X1479723Y432495D01*
X1480103Y432912D01*
X1480293Y433495D01*
X1480166Y434078D01*
X1479850Y434578D01*
X1479280Y434912D01*
X1478520Y435078D01*
X1478076Y435412D01*
X1477886Y435995D01*
X1478013Y436578D01*
X1478330Y436995D01*
X1478773Y437245D01*
X1479216D01*
X1479660Y437078D01*
X1480040Y436662D01*
G01X1482480Y432245D02*
X1484063Y437245D01*
X1485646Y432245D01*
G01X1485076Y433995D02*
X1483050D01*
G01X1489670Y434912D02*
X1489923Y435162D01*
X1490113Y435578D01*
X1490240Y436162D01*
X1490113Y436662D01*
X1489860Y436995D01*
X1489416Y437245D01*
X1487706D01*
Y432245D01*
X1489796D01*
X1490240Y432578D01*
X1490493Y433078D01*
X1490620Y433662D01*
X1490493Y434245D01*
X1490113Y434745D01*
X1489670Y434912D01*
X1487706D01*
G01X1492996Y437245D02*
Y432245D01*
X1495530D01*
G01X1500630D02*
X1498096D01*
Y437245D01*
X1500630D01*
G01X1499616Y434828D02*
X1498096D01*
G01X1467560Y423645D02*
Y428645D01*
X1469966D01*
G01X1469080Y426228D02*
X1467560D01*
G01X1472596Y423645D02*
Y428645D01*
X1474116D01*
X1474623Y428395D01*
X1475003Y427812D01*
X1475130Y427145D01*
X1475003Y426478D01*
X1474686Y425978D01*
X1474116Y425728D01*
X1472596D01*
G01X1479343Y426145D02*
X1480610D01*
Y424645D01*
X1480230Y424145D01*
X1479786Y423812D01*
X1479153Y423645D01*
X1478520Y423812D01*
X1478076Y424145D01*
X1477696Y424645D01*
X1477443Y425228D01*
X1477316Y425895D01*
Y426478D01*
X1477443Y426978D01*
X1477696Y427562D01*
X1478076Y428062D01*
X1478456Y428395D01*
X1478963Y428645D01*
X1479406D01*
X1479913Y428478D01*
X1480293Y428145D01*
G01X1482480Y423645D02*
X1484063Y428645D01*
X1485646Y423645D01*
G01X1485076Y425395D02*
X1483050D01*
G01X1495656Y428228D02*
X1495276Y428478D01*
X1494833Y428645D01*
X1494326D01*
X1493756Y428395D01*
X1493313Y427978D01*
X1492996Y427478D01*
X1492743Y426645D01*
X1492680Y425895D01*
X1492806Y425145D01*
X1492996Y424645D01*
X1493376Y424145D01*
X1493820Y423812D01*
X1494263Y423645D01*
X1494706D01*
X1495150Y423812D01*
X1495530Y424062D01*
X1495846Y424395D01*
G01X1499363Y428645D02*
Y423645D01*
G01X1497906Y428645D02*
X1500820D01*
G01X1503196Y423645D02*
Y428645D01*
X1504780D01*
X1505286Y428395D01*
X1505603Y428062D01*
X1505730Y427395D01*
X1505603Y426728D01*
X1505223Y426312D01*
X1504780Y426062D01*
X1503196D01*
G01X1504780D02*
X1505730Y423645D01*
G01X1508296Y428645D02*
Y423645D01*
X1510830D01*
G01X1467306Y440845D02*
Y445845D01*
X1470220Y440845D01*
Y445845D01*
G01X1473863Y440845D02*
X1473356Y440928D01*
X1472913Y441262D01*
X1472533Y441762D01*
X1472280Y442345D01*
X1472153Y443012D01*
Y443678D01*
X1472280Y444345D01*
X1472533Y444928D01*
X1472913Y445428D01*
X1473356Y445762D01*
X1473863Y445845D01*
X1474370Y445762D01*
X1474813Y445428D01*
X1475193Y444928D01*
X1475446Y444345D01*
X1475573Y443678D01*
Y443012D01*
X1475446Y442345D01*
X1475193Y441762D01*
X1474813Y441262D01*
X1474370Y440928D01*
X1473863Y440845D01*
G01X1477696D02*
Y445845D01*
X1479280D01*
X1479786Y445595D01*
X1480103Y445262D01*
X1480230Y444595D01*
X1480103Y443928D01*
X1479723Y443512D01*
X1479280Y443262D01*
X1477696D01*
G01X1479280D02*
X1480230Y440845D01*
G01X1482416D02*
Y445845D01*
X1484063Y441678D01*
X1485710Y445845D01*
Y440845D01*
G01X1487580D02*
X1489163Y445845D01*
X1490746Y440845D01*
G01X1490176Y442595D02*
X1488150D01*
G01X1492996Y445845D02*
Y440845D01*
X1495530D01*
G01X1467560Y459545D02*
Y464545D01*
X1469966D01*
G01X1469080Y462128D02*
X1467560D01*
G01X1472596Y459545D02*
Y464545D01*
X1474116D01*
X1474623Y464295D01*
X1475003Y463712D01*
X1475130Y463045D01*
X1475003Y462378D01*
X1474686Y461878D01*
X1474116Y461628D01*
X1472596D01*
G01X1479343Y462045D02*
X1480610D01*
Y460545D01*
X1480230Y460045D01*
X1479786Y459712D01*
X1479153Y459545D01*
X1478520Y459712D01*
X1478076Y460045D01*
X1477696Y460545D01*
X1477443Y461128D01*
X1477316Y461795D01*
Y462378D01*
X1477443Y462878D01*
X1477696Y463462D01*
X1478076Y463962D01*
X1478456Y464295D01*
X1478963Y464545D01*
X1479406D01*
X1479913Y464378D01*
X1480293Y464045D01*
G01X1482480Y459545D02*
X1484063Y464545D01*
X1485646Y459545D01*
G01X1485076Y461295D02*
X1483050D01*
G01X1467306Y450445D02*
Y455445D01*
X1470220Y450445D01*
Y455445D01*
G01X1473863Y450445D02*
X1473356Y450528D01*
X1472913Y450862D01*
X1472533Y451362D01*
X1472280Y451945D01*
X1472153Y452612D01*
Y453278D01*
X1472280Y453945D01*
X1472533Y454528D01*
X1472913Y455028D01*
X1473356Y455362D01*
X1473863Y455445D01*
X1474370Y455362D01*
X1474813Y455028D01*
X1475193Y454528D01*
X1475446Y453945D01*
X1475573Y453278D01*
Y452612D01*
X1475446Y451945D01*
X1475193Y451362D01*
X1474813Y450862D01*
X1474370Y450528D01*
X1473863Y450445D01*
G01X1477696D02*
Y455445D01*
X1479280D01*
X1479786Y455195D01*
X1480103Y454862D01*
X1480230Y454195D01*
X1480103Y453528D01*
X1479723Y453112D01*
X1479280Y452862D01*
X1477696D01*
G01X1479280D02*
X1480230Y450445D01*
G01X1482416D02*
Y455445D01*
X1484063Y451278D01*
X1485710Y455445D01*
Y450445D01*
G01X1487580D02*
X1489163Y455445D01*
X1490746Y450445D01*
G01X1490176Y452195D02*
X1488150D01*
G01X1492996Y455445D02*
Y450445D01*
X1495530D01*
G01X1470156Y481828D02*
X1469776Y482078D01*
X1469333Y482245D01*
X1468826D01*
X1468256Y481995D01*
X1467813Y481578D01*
X1467496Y481078D01*
X1467243Y480245D01*
X1467180Y479495D01*
X1467306Y478745D01*
X1467496Y478245D01*
X1467876Y477745D01*
X1468320Y477412D01*
X1468763Y477245D01*
X1469206D01*
X1469650Y477412D01*
X1470030Y477662D01*
X1470346Y477995D01*
G01X1472596Y477245D02*
Y482245D01*
X1474116D01*
X1474623Y481995D01*
X1475003Y481412D01*
X1475130Y480745D01*
X1475003Y480078D01*
X1474686Y479578D01*
X1474116Y479328D01*
X1472596D01*
G01X1477570Y482245D02*
Y478662D01*
X1477823Y477912D01*
X1478330Y477412D01*
X1478963Y477245D01*
X1479596Y477412D01*
X1480103Y477912D01*
X1480356Y478662D01*
Y482245D01*
G01X1467370Y468145D02*
Y473145D01*
X1468636D01*
X1469143Y472895D01*
X1469523Y472562D01*
X1469840Y472062D01*
X1470093Y471478D01*
X1470156Y470645D01*
X1470093Y469812D01*
X1469840Y469228D01*
X1469523Y468728D01*
X1469143Y468395D01*
X1468636Y468145D01*
X1467370D01*
G01X1473103Y473145D02*
X1474623D01*
G01X1473863D02*
Y468145D01*
G01X1473103D02*
X1474623D01*
G01X1477633Y468812D02*
X1478140Y468395D01*
X1478710Y468145D01*
X1479216D01*
X1479723Y468395D01*
X1480103Y468812D01*
X1480293Y469395D01*
X1480166Y469978D01*
X1479850Y470478D01*
X1479280Y470812D01*
X1478520Y470978D01*
X1478076Y471312D01*
X1477886Y471895D01*
X1478013Y472478D01*
X1478330Y472895D01*
X1478773Y473145D01*
X1479216D01*
X1479660Y472978D01*
X1480040Y472562D01*
G01X1482480Y468145D02*
X1484063Y473145D01*
X1485646Y468145D01*
G01X1485076Y469895D02*
X1483050D01*
G01X1489670Y470812D02*
X1489923Y471062D01*
X1490113Y471478D01*
X1490240Y472062D01*
X1490113Y472562D01*
X1489860Y472895D01*
X1489416Y473145D01*
X1487706D01*
Y468145D01*
X1489796D01*
X1490240Y468478D01*
X1490493Y468978D01*
X1490620Y469562D01*
X1490493Y470145D01*
X1490113Y470645D01*
X1489670Y470812D01*
X1487706D01*
G01X1492996Y473145D02*
Y468145D01*
X1495530D01*
G01X1500630D02*
X1498096D01*
Y473145D01*
X1500630D01*
G01X1499616Y470728D02*
X1498096D01*
G01X1468763Y486845D02*
X1468256Y486928D01*
X1467813Y487262D01*
X1467433Y487762D01*
X1467180Y488345D01*
X1467053Y489012D01*
Y489678D01*
X1467180Y490345D01*
X1467433Y490928D01*
X1467813Y491428D01*
X1468256Y491762D01*
X1468763Y491845D01*
X1469270Y491762D01*
X1469713Y491428D01*
X1470093Y490928D01*
X1470346Y490345D01*
X1470473Y489678D01*
Y489012D01*
X1470346Y488345D01*
X1470093Y487762D01*
X1469713Y487262D01*
X1469270Y486928D01*
X1468763Y486845D01*
G01X1472660D02*
Y491845D01*
X1475066D01*
G01X1474180Y489428D02*
X1472660D01*
G01X1477760Y486845D02*
Y491845D01*
X1480166D01*
G01X1479280Y489428D02*
X1477760D01*
G01X1488846Y485178D02*
X1488213Y486012D01*
X1487896Y486845D01*
Y490178D01*
X1488213Y491012D01*
X1488846Y491845D01*
G01X1492870Y486845D02*
Y491845D01*
X1494136D01*
X1494643Y491595D01*
X1495023Y491262D01*
X1495340Y490762D01*
X1495593Y490178D01*
X1495656Y489345D01*
X1495593Y488512D01*
X1495340Y487928D01*
X1495023Y487428D01*
X1494643Y487095D01*
X1494136Y486845D01*
X1492870D01*
G01X1500630D02*
X1498096D01*
Y491845D01*
X1500630D01*
G01X1499616Y489428D02*
X1498096D01*
G01X1503260Y486845D02*
Y491845D01*
X1505666D01*
G01X1504780Y489428D02*
X1503260D01*
G01X1507980Y486845D02*
X1509563Y491845D01*
X1511146Y486845D01*
G01X1510576Y488595D02*
X1508550D01*
G01X1513270Y491845D02*
Y488262D01*
X1513523Y487512D01*
X1514030Y487012D01*
X1514663Y486845D01*
X1515296Y487012D01*
X1515803Y487512D01*
X1516056Y488262D01*
Y491845D01*
G01X1518496D02*
Y486845D01*
X1521030D01*
G01X1524863Y491845D02*
Y486845D01*
G01X1523406Y491845D02*
X1526320D01*
G01X1530280Y485178D02*
X1530913Y486012D01*
X1531230Y486845D01*
Y490178D01*
X1530913Y491012D01*
X1530280Y491845D01*
G01X1454065Y496939D02*
X1454572Y496522D01*
X1455142Y496272D01*
X1455648D01*
X1456155Y496522D01*
X1456535Y496939D01*
X1456725Y497522D01*
X1456598Y498105D01*
X1456282Y498605D01*
X1455712Y498939D01*
X1454952Y499105D01*
X1454508Y499439D01*
X1454318Y500022D01*
X1454445Y500605D01*
X1454762Y501022D01*
X1455205Y501272D01*
X1455648D01*
X1456092Y501105D01*
X1456472Y500689D01*
G01X1458595Y501272D02*
X1459482Y496272D01*
X1460495Y501272D01*
X1461508Y496272D01*
X1462395Y501272D01*
G01X1465595Y496272D02*
Y501272D01*
X1464835Y500272D01*
G01Y496272D02*
X1466355D01*
G01X1475478Y494605D02*
X1474845Y495439D01*
X1474528Y496272D01*
Y499605D01*
X1474845Y500439D01*
X1475478Y501272D01*
G01X1479502Y496272D02*
Y501272D01*
X1480768D01*
X1481275Y501022D01*
X1481655Y500689D01*
X1481972Y500189D01*
X1482225Y499605D01*
X1482288Y498772D01*
X1482225Y497939D01*
X1481972Y497355D01*
X1481655Y496855D01*
X1481275Y496522D01*
X1480768Y496272D01*
X1479502D01*
G01X1487262D02*
X1484728D01*
Y501272D01*
X1487262D01*
G01X1486248Y498855D02*
X1484728D01*
G01X1491602Y498939D02*
X1491855Y499189D01*
X1492045Y499605D01*
X1492172Y500189D01*
X1492045Y500689D01*
X1491792Y501022D01*
X1491348Y501272D01*
X1489638D01*
Y496272D01*
X1491728D01*
X1492172Y496605D01*
X1492425Y497105D01*
X1492552Y497689D01*
X1492425Y498272D01*
X1492045Y498772D01*
X1491602Y498939D01*
X1489638D01*
G01X1494802Y501272D02*
Y497689D01*
X1495055Y496939D01*
X1495562Y496439D01*
X1496195Y496272D01*
X1496828Y496439D01*
X1497335Y496939D01*
X1497588Y497689D01*
Y501272D01*
G01X1501675Y498772D02*
X1502942D01*
Y497272D01*
X1502562Y496772D01*
X1502118Y496439D01*
X1501485Y496272D01*
X1500852Y496439D01*
X1500408Y496772D01*
X1500028Y497272D01*
X1499775Y497855D01*
X1499648Y498522D01*
Y499105D01*
X1499775Y499605D01*
X1500028Y500189D01*
X1500408Y500689D01*
X1500788Y501022D01*
X1501295Y501272D01*
X1501738D01*
X1502245Y501105D01*
X1502625Y500772D01*
G01X1506712Y494605D02*
X1507345Y495439D01*
X1507662Y496272D01*
Y499605D01*
X1507345Y500439D01*
X1506712Y501272D01*
G01X1467357Y536227D02*
X1461157D01*
G01D02*
Y539427D01*
G01X1467357D02*
Y536227D01*
G01X1461157Y539427D02*
X1467357D01*
G01X1465157Y550577D02*
X1471357D01*
G01Y547377D02*
X1465157D01*
G01D02*
Y550577D01*
G01X1471357Y551377D02*
X1465157D01*
G01D02*
Y554577D01*
G01Y546577D02*
X1471357D01*
G01Y543377D02*
X1465157D01*
G01D02*
Y546577D01*
G01X1457157Y566577D02*
X1463357D01*
G01D02*
Y563377D01*
G01D02*
X1457157D01*
G01D02*
Y566577D01*
G01X1465157Y554577D02*
X1471357D01*
G01Y567377D02*
X1465157D01*
G01D02*
Y570577D01*
G01Y558577D02*
X1471357D01*
G01Y555377D02*
X1465157D01*
G01D02*
Y558577D01*
G01Y562577D02*
X1471357D01*
G01Y559377D02*
X1465157D01*
G01D02*
Y562577D01*
G01Y566577D02*
X1471357D01*
G01Y563377D02*
X1465157D01*
G01D02*
Y566577D01*
G01X1471357Y579377D02*
X1465157D01*
G01D02*
Y582577D01*
G01D02*
X1471357D01*
G01Y571377D02*
X1465157D01*
G01D02*
Y574577D01*
G01D02*
X1471357D01*
G01X1465157Y570577D02*
X1471357D01*
G01Y575377D02*
X1465157D01*
G01D02*
Y578577D01*
G01D02*
X1471357D01*
G01X1463357Y575377D02*
X1457157D01*
G01D02*
Y578577D01*
G01D02*
X1463357D01*
G01D02*
Y575377D01*
G01X1465868Y617550D02*
Y641566D01*
G01X1459757Y617550D02*
X1465868D01*
G01Y641566D02*
X1459757D01*
G01X1458594Y698050D02*
Y704250D01*
G01X1461794D02*
Y698050D01*
G01D02*
X1458594D01*
G01X1460657Y696865D02*
X1466857D01*
G01D02*
Y693665D01*
G01D02*
X1460657D01*
G01D02*
Y696865D01*
G01X1465836Y704250D02*
Y698050D01*
G01D02*
X1462636D01*
G01D02*
Y704250D01*
G01X1467660Y689938D02*
Y693038D01*
X1468580D01*
X1468887Y692883D01*
X1469117Y692521D01*
X1469194Y692108D01*
X1469117Y691695D01*
X1468925Y691385D01*
X1468580Y691230D01*
X1467660D01*
G01X1470684Y693038D02*
Y690816D01*
X1470837Y690351D01*
X1471144Y690041D01*
X1471527Y689938D01*
X1471910Y690041D01*
X1472217Y690351D01*
X1472370Y690816D01*
Y693038D01*
G01X1475087Y689938D02*
Y693038D01*
X1473669Y690816D01*
X1475585D01*
G01X1476884Y690558D02*
X1477114Y690196D01*
X1477420Y689990D01*
X1477765Y689938D01*
X1478072Y689990D01*
X1478379Y690248D01*
X1478570Y690558D01*
X1478609Y690868D01*
X1478532Y691230D01*
X1478264Y691488D01*
X1477995Y691591D01*
X1477650D01*
G01X1477995D02*
X1478225Y691746D01*
X1478417Y692005D01*
X1478494Y692315D01*
X1478417Y692625D01*
X1478225Y692883D01*
X1477880Y693038D01*
X1477535Y692986D01*
X1477190Y692780D01*
G01X1454365Y722007D02*
Y715807D01*
G01X1458594Y704250D02*
X1461794D01*
G01X1462636D02*
X1465836D01*
G01X1458115Y707653D02*
X1457382D01*
G01D02*
Y709844D01*
G01Y728675D02*
Y731275D01*
G01D02*
X1458175D01*
G01X1454934Y1276592D02*
Y1270392D01*
G01X1462167Y1599659D02*
X1461607Y1600034D01*
X1460954Y1600284D01*
X1460207D01*
X1459367Y1599909D01*
X1458714Y1599284D01*
X1458247Y1598534D01*
X1457874Y1597284D01*
X1457781Y1596159D01*
X1457967Y1595034D01*
X1458247Y1594284D01*
X1458807Y1593534D01*
X1459461Y1593034D01*
X1460114Y1592784D01*
X1460767D01*
X1461421Y1593034D01*
X1461981Y1593409D01*
X1462447Y1593909D01*
G01X1465747Y1592784D02*
Y1600284D01*
X1467987D01*
X1468734Y1599909D01*
X1469294Y1599034D01*
X1469481Y1598034D01*
X1469294Y1597034D01*
X1468827Y1596284D01*
X1467987Y1595909D01*
X1465747D01*
G01X1473061Y1600284D02*
Y1594909D01*
X1473434Y1593784D01*
X1474181Y1593034D01*
X1475114Y1592784D01*
X1476047Y1593034D01*
X1476794Y1593784D01*
X1477167Y1594909D01*
Y1600284D01*
G01X1482614D02*
X1481867Y1600034D01*
X1481307Y1599409D01*
X1480934Y1598659D01*
X1480654Y1597659D01*
X1480561Y1596534D01*
X1480654Y1595409D01*
X1480934Y1594409D01*
X1481307Y1593659D01*
X1481867Y1593034D01*
X1482614Y1592784D01*
X1483361Y1593034D01*
X1483921Y1593659D01*
X1484294Y1594409D01*
X1484574Y1595409D01*
X1484667Y1596534D01*
X1484574Y1597659D01*
X1484294Y1598659D01*
X1483921Y1599409D01*
X1483361Y1600034D01*
X1482614Y1600284D01*
G01X1503247Y1592784D02*
Y1600284D01*
X1505487D01*
X1506234Y1599909D01*
X1506794Y1599034D01*
X1506981Y1598034D01*
X1506794Y1597034D01*
X1506327Y1596284D01*
X1505487Y1595909D01*
X1503247D01*
G01X1514667Y1599659D02*
X1514107Y1600034D01*
X1513454Y1600284D01*
X1512707D01*
X1511867Y1599909D01*
X1511214Y1599284D01*
X1510747Y1598534D01*
X1510374Y1597284D01*
X1510281Y1596159D01*
X1510467Y1595034D01*
X1510747Y1594284D01*
X1511307Y1593534D01*
X1511961Y1593034D01*
X1512614Y1592784D01*
X1513267D01*
X1513921Y1593034D01*
X1514481Y1593409D01*
X1514947Y1593909D01*
G01X1518994Y1600284D02*
X1521234D01*
G01X1520114D02*
Y1592784D01*
G01X1518994D02*
X1521234D01*
G01X1526214Y1596159D02*
X1529201D01*
X1528921Y1597034D01*
X1528454Y1597534D01*
X1527801Y1597784D01*
X1527147Y1597659D01*
X1526587Y1597284D01*
X1526214Y1596409D01*
X1526027Y1595659D01*
Y1594909D01*
X1526214Y1594159D01*
X1526681Y1593409D01*
X1527241Y1592909D01*
X1527894Y1592784D01*
X1528547Y1593034D01*
X1529201Y1593784D01*
G01X1548247Y1592784D02*
Y1600284D01*
X1550487D01*
X1551234Y1599909D01*
X1551794Y1599034D01*
X1551981Y1598034D01*
X1551794Y1597034D01*
X1551327Y1596284D01*
X1550487Y1595909D01*
X1548247D01*
G01X1555841Y1599034D02*
X1556401Y1599784D01*
X1557054Y1600159D01*
X1557801Y1600284D01*
X1558734Y1600034D01*
X1559387Y1599409D01*
X1559574Y1598659D01*
X1559481Y1597909D01*
X1559107Y1597284D01*
X1557241Y1596034D01*
X1556401Y1595159D01*
X1555841Y1593909D01*
X1555654Y1592784D01*
X1559574D01*
G01X1572427Y1591409D02*
X1572801Y1593034D01*
G01X1585747Y1592784D02*
Y1600284D01*
X1587987D01*
X1588734Y1599909D01*
X1589294Y1599034D01*
X1589481Y1598034D01*
X1589294Y1597034D01*
X1588827Y1596284D01*
X1587987Y1595909D01*
X1585747D01*
G01X1593061Y1594284D02*
X1593621Y1593409D01*
X1594367Y1592909D01*
X1595207Y1592784D01*
X1595954Y1592909D01*
X1596701Y1593534D01*
X1597167Y1594284D01*
X1597261Y1595034D01*
X1597074Y1595909D01*
X1596421Y1596534D01*
X1595767Y1596784D01*
X1594927D01*
G01X1595767D02*
X1596327Y1597159D01*
X1596794Y1597784D01*
X1596981Y1598534D01*
X1596794Y1599284D01*
X1596327Y1599909D01*
X1595487Y1600284D01*
X1594647Y1600159D01*
X1593807Y1599659D01*
G01X1461315Y1589794D02*
Y1587572D01*
X1461468Y1587107D01*
X1461775Y1586797D01*
X1462158Y1586694D01*
X1462541Y1586797D01*
X1462848Y1587107D01*
X1463001Y1587572D01*
Y1589794D01*
G01X1464530Y1587986D02*
X1464798Y1588347D01*
X1465028Y1588554D01*
X1465335Y1588657D01*
X1465603Y1588554D01*
X1465795Y1588347D01*
X1465948Y1588037D01*
X1465986Y1587676D01*
X1465948Y1587366D01*
X1465795Y1587056D01*
X1465565Y1586797D01*
X1465296Y1586694D01*
X1464990Y1586797D01*
X1464721Y1587107D01*
X1464568Y1587572D01*
X1464530Y1588089D01*
X1464606Y1588761D01*
X1464721Y1589122D01*
X1464913Y1589484D01*
X1465181Y1589742D01*
X1465450Y1589794D01*
X1465718Y1589691D01*
X1465910Y1589432D01*
G01X1468358Y1589794D02*
X1468051Y1589691D01*
X1467821Y1589432D01*
X1467668Y1589122D01*
X1467553Y1588709D01*
X1467515Y1588244D01*
X1467553Y1587779D01*
X1467668Y1587366D01*
X1467821Y1587056D01*
X1468051Y1586797D01*
X1468358Y1586694D01*
X1468665Y1586797D01*
X1468895Y1587056D01*
X1469048Y1587366D01*
X1469163Y1587779D01*
X1469201Y1588244D01*
X1469163Y1588709D01*
X1469048Y1589122D01*
X1468895Y1589432D01*
X1468665Y1589691D01*
X1468358Y1589794D01*
G01X1471458Y1586694D02*
Y1589794D01*
X1470998Y1589174D01*
G01Y1586694D02*
X1471918D01*
G01X1473715Y1587314D02*
X1473945Y1586952D01*
X1474251Y1586746D01*
X1474596Y1586694D01*
X1474903Y1586746D01*
X1475210Y1587004D01*
X1475401Y1587314D01*
X1475440Y1587624D01*
X1475363Y1587986D01*
X1475095Y1588244D01*
X1474826Y1588347D01*
X1474481D01*
G01X1474826D02*
X1475056Y1588502D01*
X1475248Y1588761D01*
X1475325Y1589071D01*
X1475248Y1589381D01*
X1475056Y1589639D01*
X1474711Y1589794D01*
X1474366Y1589742D01*
X1474021Y1589536D01*
G01X1457922Y1637196D02*
Y1664344D01*
G01X1463302Y1666288D02*
X1460102D01*
G01X1463302Y1672488D02*
Y1666288D01*
G01X1460102D02*
Y1672488D01*
G01X1454179Y1672403D02*
Y1666203D01*
G01X1459179D02*
X1455979D01*
G01D02*
Y1672403D01*
G01X1459179D02*
Y1666203D01*
G01X1467902Y1683471D02*
X1478016D01*
G01X1467902Y1675331D02*
Y1683471D01*
G01X1478016Y1675331D02*
X1467902D01*
G01X1460102Y1672488D02*
X1463302D01*
G01X1455979Y1672403D02*
X1459179D01*
G01X1476505Y63163D02*
Y59963D01*
G01D02*
X1470305D01*
G01D02*
Y63163D01*
G01X1469505D02*
Y59963D01*
G01X1470305Y63163D02*
X1476505D01*
G01X1480103Y108792D02*
Y111892D01*
G01X1481713D02*
Y108792D01*
G01Y110342D02*
X1480103D01*
G01X1484008Y108792D02*
X1484276Y108844D01*
X1484583Y108999D01*
X1484775Y109257D01*
X1484851Y109619D01*
X1484775Y109980D01*
X1484545Y110290D01*
X1484200Y110445D01*
X1483816D01*
X1483586Y110549D01*
X1483395Y110807D01*
X1483318Y111169D01*
X1483433Y111530D01*
X1483701Y111789D01*
X1484008Y111892D01*
X1484315Y111789D01*
X1484583Y111530D01*
X1484698Y111169D01*
X1484621Y110807D01*
X1484430Y110549D01*
X1484200Y110445D01*
X1483816D01*
X1483471Y110290D01*
X1483241Y109980D01*
X1483165Y109619D01*
X1483241Y109257D01*
X1483433Y108999D01*
X1483740Y108844D01*
X1484008Y108792D01*
G01X1487031D02*
X1487108Y109464D01*
X1487223Y110032D01*
X1487376Y110549D01*
X1487568Y111117D01*
X1487875Y111892D01*
X1486341D01*
G01X1485420Y124158D02*
X1482220D01*
G01D02*
Y130358D01*
G01D02*
X1485420D01*
G01X1471357Y550577D02*
Y547377D01*
G01Y554577D02*
Y551377D01*
G01Y546577D02*
Y543377D01*
G01Y570577D02*
Y567377D01*
G01Y558577D02*
Y555377D01*
G01Y562577D02*
Y559377D01*
G01Y566577D02*
Y563377D01*
G01Y582577D02*
Y579377D01*
G01Y574577D02*
Y571377D01*
G01Y578577D02*
Y575377D01*
G01X1477006Y627322D02*
Y630422D01*
X1477926D01*
X1478233Y630267D01*
X1478463Y629905D01*
X1478540Y629492D01*
X1478463Y629079D01*
X1478271Y628769D01*
X1477926Y628614D01*
X1477006D01*
G01X1481716Y630164D02*
X1481486Y630319D01*
X1481218Y630422D01*
X1480911D01*
X1480566Y630267D01*
X1480298Y630009D01*
X1480106Y629699D01*
X1479953Y629182D01*
X1479915Y628717D01*
X1479991Y628252D01*
X1480106Y627942D01*
X1480336Y627632D01*
X1480605Y627425D01*
X1480873Y627322D01*
X1481141D01*
X1481410Y627425D01*
X1481640Y627580D01*
X1481831Y627787D01*
G01X1484433Y627322D02*
Y630422D01*
X1483015Y628200D01*
X1484931D01*
G01X1486421Y627684D02*
X1486690Y627425D01*
X1486996Y627322D01*
X1487303Y627425D01*
X1487571Y627735D01*
X1487763Y628200D01*
X1487840Y628665D01*
Y629234D01*
X1487763Y629699D01*
X1487571Y630112D01*
X1487341Y630319D01*
X1487073Y630422D01*
X1486766Y630319D01*
X1486536Y630112D01*
X1486383Y629802D01*
X1486306Y629389D01*
X1486383Y629027D01*
X1486575Y628665D01*
X1486805Y628459D01*
X1487073Y628407D01*
X1487380Y628510D01*
X1487610Y628769D01*
X1487840Y629234D01*
G01X1490173Y627322D02*
Y630422D01*
X1489713Y629802D01*
G01Y627322D02*
X1490633D01*
G01X1501063Y645066D02*
G02I-13386J0D01*
G01D02*
X1474291D01*
G01X1479431Y703440D02*
Y697240D01*
G01D02*
X1476231D01*
G01D02*
Y703440D01*
G01X1486609Y700603D02*
X1480409D01*
G01D02*
Y703803D01*
G01X1469261Y700546D02*
X1475461D01*
G01D02*
Y697346D01*
G01D02*
X1469261D01*
G01D02*
Y700546D01*
G01X1476231Y703440D02*
X1479431D01*
G01X1480409Y703803D02*
X1486609D01*
G01X1483325Y705871D02*
X1480125D01*
G01D02*
Y707400D01*
G01Y712071D02*
X1483325D01*
G01X1480125Y709800D02*
Y712071D01*
G01Y716371D02*
Y722571D01*
G01X1483325Y716371D02*
X1480125D01*
G01X1477068Y709507D02*
Y707653D01*
G01D02*
X1476060D01*
G01X1480125Y722571D02*
X1483325D01*
G01X1478668Y729692D02*
Y732892D01*
G01X1484868Y729692D02*
X1478668D01*
G01X1480102Y729392D02*
X1483302D01*
G01X1480102Y723192D02*
Y729392D01*
G01X1483302Y723192D02*
X1480102D01*
G01X1476275Y731275D02*
X1477068D01*
G01D02*
Y728675D01*
G01Y722064D02*
Y720366D01*
G01X1478668Y732892D02*
X1484868D01*
G01X1481525Y734492D02*
X1476184D01*
G01X1481525Y777800D02*
Y734492D01*
G01X1476184Y777800D02*
X1481525D01*
G01X1473396Y1662605D02*
X1473588Y1662295D01*
X1473818Y1662088D01*
X1474086Y1661985D01*
X1474393Y1662088D01*
X1474623Y1662295D01*
X1474853Y1662605D01*
X1474930Y1663018D01*
Y1665085D01*
G01X1477263Y1661985D02*
Y1665085D01*
X1476803Y1664465D01*
G01Y1661985D02*
X1477723D01*
G01X1480363Y1665085D02*
X1480056Y1664982D01*
X1479826Y1664723D01*
X1479673Y1664413D01*
X1479558Y1664000D01*
X1479520Y1663535D01*
X1479558Y1663070D01*
X1479673Y1662657D01*
X1479826Y1662347D01*
X1480056Y1662088D01*
X1480363Y1661985D01*
X1480670Y1662088D01*
X1480900Y1662347D01*
X1481053Y1662657D01*
X1481168Y1663070D01*
X1481206Y1663535D01*
X1481168Y1664000D01*
X1481053Y1664413D01*
X1480900Y1664723D01*
X1480670Y1664982D01*
X1480363Y1665085D01*
G01X1482735Y1663277D02*
X1483003Y1663638D01*
X1483233Y1663845D01*
X1483540Y1663948D01*
X1483808Y1663845D01*
X1484000Y1663638D01*
X1484153Y1663328D01*
X1484191Y1662967D01*
X1484153Y1662657D01*
X1484000Y1662347D01*
X1483770Y1662088D01*
X1483501Y1661985D01*
X1483195Y1662088D01*
X1482926Y1662398D01*
X1482773Y1662863D01*
X1482735Y1663380D01*
X1482811Y1664052D01*
X1482926Y1664413D01*
X1483118Y1664775D01*
X1483386Y1665033D01*
X1483655Y1665085D01*
X1483923Y1664982D01*
X1484115Y1664723D01*
G01X1478016Y1683471D02*
Y1675331D01*
G01X1469479Y1693154D02*
Y1690932D01*
X1469632Y1690467D01*
X1469939Y1690157D01*
X1470322Y1690054D01*
X1470705Y1690157D01*
X1471012Y1690467D01*
X1471165Y1690932D01*
Y1693154D01*
G01X1473882Y1690054D02*
Y1693154D01*
X1472464Y1690932D01*
X1474380D01*
G01X1475794Y1691346D02*
X1476062Y1691707D01*
X1476292Y1691914D01*
X1476599Y1692017D01*
X1476867Y1691914D01*
X1477059Y1691707D01*
X1477212Y1691397D01*
X1477250Y1691036D01*
X1477212Y1690726D01*
X1477059Y1690416D01*
X1476829Y1690157D01*
X1476560Y1690054D01*
X1476254Y1690157D01*
X1475985Y1690467D01*
X1475832Y1690932D01*
X1475794Y1691449D01*
X1475870Y1692121D01*
X1475985Y1692482D01*
X1476177Y1692844D01*
X1476445Y1693102D01*
X1476714Y1693154D01*
X1476982Y1693051D01*
X1477174Y1692792D01*
G01X1485420Y130358D02*
Y124158D01*
G01X1505620Y124720D02*
X1489620D01*
G01D02*
Y136924D01*
G01X1493643Y142776D02*
Y140554D01*
X1493796Y140089D01*
X1494103Y139779D01*
X1494486Y139676D01*
X1494869Y139779D01*
X1495176Y140089D01*
X1495329Y140554D01*
Y142776D01*
G01X1496743Y140296D02*
X1496973Y139934D01*
X1497279Y139728D01*
X1497624Y139676D01*
X1497931Y139728D01*
X1498238Y139986D01*
X1498429Y140296D01*
X1498468Y140606D01*
X1498391Y140968D01*
X1498123Y141226D01*
X1497854Y141329D01*
X1497509D01*
G01X1497854D02*
X1498084Y141484D01*
X1498276Y141743D01*
X1498353Y142053D01*
X1498276Y142363D01*
X1498084Y142621D01*
X1497739Y142776D01*
X1497394Y142724D01*
X1497049Y142518D01*
G01X1499958Y142259D02*
X1500188Y142569D01*
X1500456Y142724D01*
X1500763Y142776D01*
X1501146Y142673D01*
X1501414Y142414D01*
X1501491Y142104D01*
X1501453Y141794D01*
X1501299Y141536D01*
X1500533Y141019D01*
X1500188Y140658D01*
X1499958Y140141D01*
X1499881Y139676D01*
X1501491D01*
G01X1503786Y142776D02*
X1503479Y142673D01*
X1503249Y142414D01*
X1503096Y142104D01*
X1502981Y141691D01*
X1502943Y141226D01*
X1502981Y140761D01*
X1503096Y140348D01*
X1503249Y140038D01*
X1503479Y139779D01*
X1503786Y139676D01*
X1504093Y139779D01*
X1504323Y140038D01*
X1504476Y140348D01*
X1504591Y140761D01*
X1504629Y141226D01*
X1504591Y141691D01*
X1504476Y142104D01*
X1504323Y142414D01*
X1504093Y142673D01*
X1503786Y142776D01*
G01X1489620Y136924D02*
X1505620D01*
G01X1494449Y297843D02*
X1500449D01*
Y303843D01*
G01Y311528D02*
Y317528D01*
X1494449D01*
G01X1493160Y599137D02*
Y592937D01*
G01D02*
X1489960D01*
G01D02*
Y599137D01*
G01D02*
X1493160D01*
G01X1491676Y698050D02*
Y704250D01*
G01X1494876D02*
Y698050D01*
G01D02*
X1491676D01*
G01X1486609Y703803D02*
Y700603D01*
G01X1498918Y698050D02*
X1495718D01*
G01D02*
Y704250D01*
G01X1493336Y690394D02*
Y693494D01*
X1494256D01*
X1494563Y693339D01*
X1494793Y692977D01*
X1494870Y692564D01*
X1494793Y692151D01*
X1494601Y691841D01*
X1494256Y691686D01*
X1493336D01*
G01X1496360Y693494D02*
Y691272D01*
X1496513Y690807D01*
X1496820Y690497D01*
X1497203Y690394D01*
X1497586Y690497D01*
X1497893Y690807D01*
X1498046Y691272D01*
Y693494D01*
G01X1500763Y690394D02*
Y693494D01*
X1499345Y691272D01*
X1501261D01*
G01X1502675Y691686D02*
X1502943Y692047D01*
X1503173Y692254D01*
X1503480Y692357D01*
X1503748Y692254D01*
X1503940Y692047D01*
X1504093Y691737D01*
X1504131Y691376D01*
X1504093Y691066D01*
X1503940Y690756D01*
X1503710Y690497D01*
X1503441Y690394D01*
X1503135Y690497D01*
X1502866Y690807D01*
X1502713Y691272D01*
X1502675Y691789D01*
X1502751Y692461D01*
X1502866Y692822D01*
X1503058Y693184D01*
X1503326Y693442D01*
X1503595Y693494D01*
X1503863Y693391D01*
X1504055Y693132D01*
G01X1484297Y716038D02*
Y722238D01*
G01X1487497D02*
Y716038D01*
G01D02*
X1484297D01*
G01X1491676Y704250D02*
X1494876D01*
G01X1483325Y712071D02*
Y705871D01*
G01Y722571D02*
Y716371D01*
G01X1495718Y704250D02*
X1498918D01*
G01X1491197Y707821D02*
X1490464D01*
G01D02*
Y710012D01*
G01X1484297Y722238D02*
X1487497D01*
G01X1484868Y732892D02*
Y729692D01*
G01X1483302Y729392D02*
Y723192D01*
G01X1490464Y728843D02*
Y731443D01*
G01D02*
X1491257D01*
G01X1485079Y734492D02*
X1490420D01*
G01X1485079Y777800D02*
Y734492D01*
G01X1490420Y777800D02*
X1485079D01*
G01X1558535Y870788D02*
X1485700D01*
G01X1495400Y1646023D02*
X1488000D01*
G01X1486220Y1658800D02*
Y1736118D01*
G01X1495474Y1686125D02*
X1492374D01*
G01Y1687581D02*
X1494286Y1686125D01*
G01X1495474Y1687811D02*
X1493407Y1686776D01*
G01X1492374Y1681476D02*
X1495474D01*
Y1683010D01*
G01Y1676522D02*
X1492374D01*
X1494957Y1677519D01*
X1492374Y1678516D01*
X1495474D01*
G01Y1671913D02*
X1492374D01*
X1495474Y1673677D01*
X1492374D01*
G01X1490101Y1693428D02*
X1487001D01*
Y1694348D01*
X1487156Y1694655D01*
X1487518Y1694885D01*
X1487931Y1694962D01*
X1488344Y1694885D01*
X1488654Y1694693D01*
X1488809Y1694348D01*
Y1693428D01*
G01X1490101Y1696528D02*
X1487001D01*
Y1697487D01*
X1487156Y1697793D01*
X1487363Y1697985D01*
X1487776Y1698062D01*
X1488189Y1697985D01*
X1488448Y1697755D01*
X1488603Y1697487D01*
Y1696528D01*
G01Y1697487D02*
X1490101Y1698062D01*
G01Y1701162D02*
Y1699628D01*
X1487001D01*
Y1701162D01*
G01X1488499Y1700548D02*
Y1699628D01*
G01X1489688Y1702690D02*
X1489946Y1702997D01*
X1490101Y1703342D01*
Y1703648D01*
X1489946Y1703955D01*
X1489688Y1704185D01*
X1489326Y1704300D01*
X1488964Y1704223D01*
X1488654Y1704032D01*
X1488448Y1703687D01*
X1488344Y1703227D01*
X1488138Y1702958D01*
X1487776Y1702843D01*
X1487414Y1702920D01*
X1487156Y1703112D01*
X1487001Y1703380D01*
Y1703648D01*
X1487104Y1703917D01*
X1487363Y1704147D01*
G01X1489688Y1705790D02*
X1489946Y1706097D01*
X1490101Y1706442D01*
Y1706748D01*
X1489946Y1707055D01*
X1489688Y1707285D01*
X1489326Y1707400D01*
X1488964Y1707323D01*
X1488654Y1707132D01*
X1488448Y1706787D01*
X1488344Y1706327D01*
X1488138Y1706058D01*
X1487776Y1705943D01*
X1487414Y1706020D01*
X1487156Y1706212D01*
X1487001Y1706480D01*
Y1706748D01*
X1487104Y1707017D01*
X1487363Y1707247D01*
G01X1489068Y1709197D02*
Y1710193D01*
G01X1490101Y1712067D02*
X1487001D01*
Y1713523D01*
G01X1488499Y1712987D02*
Y1712067D01*
G01X1487001Y1715435D02*
Y1716355D01*
G01Y1715895D02*
X1490101D01*
G01Y1715435D02*
Y1716355D01*
G01X1487001Y1718995D02*
X1490101D01*
G01X1487001Y1718113D02*
Y1719877D01*
G01X1494854Y1690925D02*
X1495164Y1691117D01*
X1495371Y1691347D01*
X1495474Y1691615D01*
X1495371Y1691922D01*
X1495164Y1692152D01*
X1494854Y1692382D01*
X1494441Y1692459D01*
X1492374D01*
G01X1495474Y1700336D02*
X1492374D01*
G01Y1701946D02*
X1495474D01*
G01X1493924D02*
Y1700336D01*
G01X1492374Y1695957D02*
Y1696877D01*
G01Y1696417D02*
X1495474D01*
G01Y1695957D02*
Y1696877D01*
G01Y1716081D02*
Y1714547D01*
X1492374D01*
Y1716081D01*
G01X1493872Y1715467D02*
Y1714547D01*
G01X1495474Y1709862D02*
X1492374D01*
Y1711318D01*
G01X1493872Y1710782D02*
Y1709862D01*
G01X1493924Y1706096D02*
Y1706863D01*
X1494854D01*
X1495164Y1706633D01*
X1495371Y1706364D01*
X1495474Y1705981D01*
X1495371Y1705598D01*
X1495164Y1705329D01*
X1494854Y1705099D01*
X1494492Y1704946D01*
X1494079Y1704869D01*
X1493717D01*
X1493407Y1704946D01*
X1493046Y1705099D01*
X1492736Y1705329D01*
X1492529Y1705559D01*
X1492374Y1705866D01*
Y1706134D01*
X1492477Y1706441D01*
X1492684Y1706671D01*
G01X1495474Y1719196D02*
X1492374D01*
Y1719962D01*
X1492529Y1720269D01*
X1492736Y1720499D01*
X1493046Y1720691D01*
X1493407Y1720844D01*
X1493924Y1720882D01*
X1494441Y1720844D01*
X1494802Y1720691D01*
X1495112Y1720499D01*
X1495319Y1720269D01*
X1495474Y1719962D01*
Y1719196D01*
G01X1493821Y1729795D02*
X1493666Y1729948D01*
X1493407Y1730063D01*
X1493046Y1730140D01*
X1492736Y1730063D01*
X1492529Y1729910D01*
X1492374Y1729641D01*
Y1728606D01*
X1495474D01*
Y1729871D01*
X1495267Y1730140D01*
X1494957Y1730293D01*
X1494596Y1730370D01*
X1494234Y1730293D01*
X1493924Y1730063D01*
X1493821Y1729795D01*
Y1728606D01*
G01X1492632Y1725606D02*
X1492477Y1725376D01*
X1492374Y1725108D01*
Y1724801D01*
X1492529Y1724456D01*
X1492787Y1724188D01*
X1493097Y1723996D01*
X1493614Y1723843D01*
X1494079Y1723805D01*
X1494544Y1723881D01*
X1494854Y1723996D01*
X1495164Y1724226D01*
X1495371Y1724495D01*
X1495474Y1724763D01*
Y1725031D01*
X1495371Y1725300D01*
X1495216Y1725530D01*
X1495009Y1725721D01*
G01X1519042Y129213D02*
X1512842D01*
G01D02*
Y132413D01*
G01D02*
X1519042D01*
G01X1505620Y136924D02*
Y124720D01*
G01X1515244Y220575D02*
X1512044D01*
G01D02*
Y226775D01*
G01X1515244Y211725D02*
X1512044D01*
G01D02*
Y217925D01*
G01D02*
X1515244D01*
G01X1512044Y226775D02*
X1515244D01*
G01X1512044Y244825D02*
Y251025D01*
G01D02*
X1515244D01*
G01Y244825D02*
X1512044D01*
G01X1514948Y254938D02*
X1511748D01*
G01D02*
Y261138D01*
G01D02*
X1514948D01*
G01X1515357Y546377D02*
X1509157D01*
G01D02*
Y549577D01*
G01D02*
X1515357D01*
G01X1509157Y545577D02*
X1515357D01*
G01Y542377D02*
X1509157D01*
G01D02*
Y545577D01*
G01X1515357Y550377D02*
X1509157D01*
G01D02*
Y553577D01*
G01X1505357Y554877D02*
X1499157D01*
G01D02*
Y558077D01*
G01D02*
X1505357D01*
G01D02*
Y554877D01*
G01X1509157Y553577D02*
X1515357D01*
G01X1505457Y560077D02*
X1499257D01*
G01D02*
Y563277D01*
G01D02*
X1505457D01*
G01D02*
Y560077D01*
G01X1515357Y562377D02*
X1509157D01*
G01D02*
Y565577D01*
G01D02*
X1515357D01*
G01X1498059Y597527D02*
X1522075D01*
G01X1498059Y603638D02*
Y597527D01*
G01X1498716Y622529D02*
Y625629D01*
X1499636D01*
X1499943Y625474D01*
X1500173Y625112D01*
X1500250Y624699D01*
X1500173Y624286D01*
X1499981Y623976D01*
X1499636Y623821D01*
X1498716D01*
G01X1501816Y625629D02*
Y622529D01*
X1503350D01*
G01X1504955Y623821D02*
X1505223Y624182D01*
X1505453Y624389D01*
X1505760Y624492D01*
X1506028Y624389D01*
X1506220Y624182D01*
X1506373Y623872D01*
X1506411Y623511D01*
X1506373Y623201D01*
X1506220Y622891D01*
X1505990Y622632D01*
X1505721Y622529D01*
X1505415Y622632D01*
X1505146Y622942D01*
X1504993Y623407D01*
X1504955Y623924D01*
X1505031Y624596D01*
X1505146Y624957D01*
X1505338Y625319D01*
X1505606Y625577D01*
X1505875Y625629D01*
X1506143Y625526D01*
X1506335Y625267D01*
G01X1507940Y622994D02*
X1508170Y622736D01*
X1508438Y622581D01*
X1508783Y622529D01*
X1509128Y622632D01*
X1509396Y622839D01*
X1509588Y623201D01*
X1509626Y623614D01*
X1509550Y624027D01*
X1509358Y624286D01*
X1509090Y624492D01*
X1508821Y624544D01*
X1508553Y624492D01*
X1508208Y624286D01*
X1508323Y625629D01*
X1509358D01*
G01X1522075Y621149D02*
X1498059D01*
G01D02*
Y615038D01*
G01X1537823Y645286D02*
G02I-13386J0D01*
G01D02*
X1511051D01*
G01X1511408Y671707D02*
Y674807D01*
G01X1513018D02*
Y671707D01*
G01Y673257D02*
X1511408D01*
G01X1514470Y672327D02*
X1514700Y671965D01*
X1515006Y671759D01*
X1515351Y671707D01*
X1515658Y671759D01*
X1515965Y672017D01*
X1516156Y672327D01*
X1516195Y672637D01*
X1516118Y672999D01*
X1515850Y673257D01*
X1515581Y673360D01*
X1515236D01*
G01X1515581D02*
X1515811Y673515D01*
X1516003Y673774D01*
X1516080Y674084D01*
X1516003Y674394D01*
X1515811Y674652D01*
X1515466Y674807D01*
X1515121Y674755D01*
X1514776Y674549D01*
G01X1518413Y671707D02*
X1518681Y671759D01*
X1518988Y671914D01*
X1519180Y672172D01*
X1519256Y672534D01*
X1519180Y672895D01*
X1518950Y673205D01*
X1518605Y673360D01*
X1518221D01*
X1517991Y673464D01*
X1517800Y673722D01*
X1517723Y674084D01*
X1517838Y674445D01*
X1518106Y674704D01*
X1518413Y674807D01*
X1518720Y674704D01*
X1518988Y674445D01*
X1519103Y674084D01*
X1519026Y673722D01*
X1518835Y673464D01*
X1518605Y673360D01*
X1518221D01*
X1517876Y673205D01*
X1517646Y672895D01*
X1517570Y672534D01*
X1517646Y672172D01*
X1517838Y671914D01*
X1518145Y671759D01*
X1518413Y671707D01*
G01X1512513Y703440D02*
Y697240D01*
G01D02*
X1509313D01*
G01D02*
Y703440D01*
G01X1502343Y700546D02*
X1508543D01*
G01D02*
Y697346D01*
G01D02*
X1502343D01*
G01D02*
Y700546D01*
G01X1498918Y704250D02*
Y698050D01*
G01X1509313Y703440D02*
X1512513D01*
G01X1510150Y709675D02*
Y707821D01*
G01D02*
X1509142D01*
G01X1511750Y729692D02*
Y732892D01*
G01X1517950Y729692D02*
X1511750D01*
G01X1509357Y731443D02*
X1510150D01*
G01D02*
Y728843D01*
G01Y722232D02*
Y720534D01*
G01X1511750Y732892D02*
X1517950D01*
G01X1514607Y734492D02*
X1509266D01*
G01Y777800D02*
X1514607D01*
G01X1509323Y857796D02*
G03X1511291Y855827I1968J-1D01*
G01X1509323Y857796D02*
Y870788D01*
G01X1523102Y855827D02*
X1511291D01*
G01X1503614Y1167638D02*
Y1180630D01*
G01X1505583Y1182599D02*
X1517394D01*
G01X1505583D02*
G03X1503614Y1180630I-1J-1968D01*
G01X1507077Y1269288D02*
X1503877D01*
G01X1507077Y1275488D02*
Y1269288D01*
G01X1503877Y1275488D02*
X1507077D01*
G01X1503877Y1269288D02*
Y1275488D01*
G01X1505721Y1619129D02*
X1505491Y1619284D01*
X1505223Y1619387D01*
X1504916D01*
X1504571Y1619232D01*
X1504303Y1618974D01*
X1504111Y1618664D01*
X1503958Y1618147D01*
X1503920Y1617682D01*
X1503996Y1617217D01*
X1504111Y1616907D01*
X1504341Y1616597D01*
X1504610Y1616390D01*
X1504878Y1616287D01*
X1505146D01*
X1505415Y1616390D01*
X1505645Y1616545D01*
X1505836Y1616752D01*
G01X1507901Y1616287D02*
X1507978Y1616959D01*
X1508093Y1617527D01*
X1508246Y1618044D01*
X1508438Y1618612D01*
X1508745Y1619387D01*
X1507211D01*
G01X1511078D02*
X1510771Y1619284D01*
X1510541Y1619025D01*
X1510388Y1618715D01*
X1510273Y1618302D01*
X1510235Y1617837D01*
X1510273Y1617372D01*
X1510388Y1616959D01*
X1510541Y1616649D01*
X1510771Y1616390D01*
X1511078Y1616287D01*
X1511385Y1616390D01*
X1511615Y1616649D01*
X1511768Y1616959D01*
X1511883Y1617372D01*
X1511921Y1617837D01*
X1511883Y1618302D01*
X1511768Y1618715D01*
X1511615Y1619025D01*
X1511385Y1619284D01*
X1511078Y1619387D01*
G01X1514178D02*
X1513871Y1619284D01*
X1513641Y1619025D01*
X1513488Y1618715D01*
X1513373Y1618302D01*
X1513335Y1617837D01*
X1513373Y1617372D01*
X1513488Y1616959D01*
X1513641Y1616649D01*
X1513871Y1616390D01*
X1514178Y1616287D01*
X1514485Y1616390D01*
X1514715Y1616649D01*
X1514868Y1616959D01*
X1514983Y1617372D01*
X1515021Y1617837D01*
X1514983Y1618302D01*
X1514868Y1618715D01*
X1514715Y1619025D01*
X1514485Y1619284D01*
X1514178Y1619387D01*
G01X1517278Y1616287D02*
Y1619387D01*
X1516818Y1618767D01*
G01Y1616287D02*
X1517738D01*
G01X1512617Y1654672D02*
X1512307Y1654902D01*
X1512152Y1655170D01*
X1512100Y1655477D01*
X1512203Y1655860D01*
X1512462Y1656128D01*
X1512772Y1656205D01*
X1513082Y1656167D01*
X1513340Y1656013D01*
X1513857Y1655247D01*
X1514218Y1654902D01*
X1514735Y1654672D01*
X1515200Y1654595D01*
Y1656205D01*
G01X1504785Y1656012D02*
X1501685D01*
X1502305Y1655552D01*
G01X1504785D02*
Y1656472D01*
G01X1507500Y1646023D02*
X1500900D01*
G01X1498031Y1736118D02*
Y1657834D01*
G01X1501600D02*
X1506600D01*
G01X1513135Y1736629D02*
X1512069D01*
Y1739129D01*
X1513135D01*
G01X1512709Y1737921D02*
X1512069D01*
G01X1514215Y1736629D02*
Y1739129D01*
X1514749D01*
X1514962Y1739004D01*
X1515122Y1738837D01*
X1515255Y1738587D01*
X1515362Y1738296D01*
X1515389Y1737879D01*
X1515362Y1737462D01*
X1515255Y1737171D01*
X1515122Y1736921D01*
X1514962Y1736754D01*
X1514749Y1736629D01*
X1514215D01*
G01X1517162Y1737879D02*
X1517695D01*
Y1737129D01*
X1517535Y1736879D01*
X1517349Y1736712D01*
X1517082Y1736629D01*
X1516815Y1736712D01*
X1516629Y1736879D01*
X1516469Y1737129D01*
X1516362Y1737421D01*
X1516309Y1737754D01*
Y1738046D01*
X1516362Y1738296D01*
X1516469Y1738587D01*
X1516629Y1738837D01*
X1516789Y1739004D01*
X1517002Y1739129D01*
X1517189D01*
X1517402Y1739046D01*
X1517562Y1738879D01*
G01X1519735Y1736629D02*
X1518669D01*
Y1739129D01*
X1519735D01*
G01X1519309Y1737921D02*
X1518669D01*
G01X1523602Y1736629D02*
X1523389Y1736671D01*
X1523202Y1736837D01*
X1523042Y1737087D01*
X1522935Y1737379D01*
X1522882Y1737712D01*
Y1738046D01*
X1522935Y1738379D01*
X1523042Y1738671D01*
X1523202Y1738921D01*
X1523389Y1739087D01*
X1523602Y1739129D01*
X1523815Y1739087D01*
X1524002Y1738921D01*
X1524162Y1738671D01*
X1524269Y1738379D01*
X1524322Y1738046D01*
Y1737712D01*
X1524269Y1737379D01*
X1524162Y1737087D01*
X1524002Y1736837D01*
X1523815Y1736671D01*
X1523602Y1736629D01*
G01X1525295D02*
Y1739129D01*
X1526309D01*
G01X1525935Y1737921D02*
X1525295D01*
G01X1529615Y1736629D02*
Y1739129D01*
X1530149D01*
X1530362Y1739004D01*
X1530522Y1738837D01*
X1530655Y1738587D01*
X1530762Y1738296D01*
X1530789Y1737879D01*
X1530762Y1737462D01*
X1530655Y1737171D01*
X1530522Y1736921D01*
X1530362Y1736754D01*
X1530149Y1736629D01*
X1529615D01*
G01X1531735D02*
X1532402Y1739129D01*
X1533069Y1736629D01*
G01X1532829Y1737504D02*
X1531975D01*
G01X1534015Y1739129D02*
Y1737337D01*
X1534122Y1736962D01*
X1534335Y1736712D01*
X1534602Y1736629D01*
X1534869Y1736712D01*
X1535082Y1736962D01*
X1535189Y1737337D01*
Y1739129D01*
G01X1536962Y1737879D02*
X1537495D01*
Y1737129D01*
X1537335Y1736879D01*
X1537149Y1736712D01*
X1536882Y1736629D01*
X1536615Y1736712D01*
X1536429Y1736879D01*
X1536269Y1737129D01*
X1536162Y1737421D01*
X1536109Y1737754D01*
Y1738046D01*
X1536162Y1738296D01*
X1536269Y1738587D01*
X1536429Y1738837D01*
X1536589Y1739004D01*
X1536802Y1739129D01*
X1536989D01*
X1537202Y1739046D01*
X1537362Y1738879D01*
G01X1538442Y1736629D02*
Y1739129D01*
G01X1539562D02*
Y1736629D01*
G01Y1737879D02*
X1538442D01*
G01X1541202Y1739129D02*
Y1736629D01*
G01X1540589Y1739129D02*
X1541815D01*
G01X1543935Y1736629D02*
X1542869D01*
Y1739129D01*
X1543935D01*
G01X1543509Y1737921D02*
X1542869D01*
G01X1545069Y1736629D02*
Y1739129D01*
X1545735D01*
X1545949Y1739004D01*
X1546082Y1738837D01*
X1546135Y1738504D01*
X1546082Y1738171D01*
X1545922Y1737962D01*
X1545735Y1737837D01*
X1545069D01*
G01X1545735D02*
X1546135Y1736629D01*
G01X1550589Y1738921D02*
X1550429Y1739046D01*
X1550242Y1739129D01*
X1550029D01*
X1549789Y1739004D01*
X1549602Y1738796D01*
X1549469Y1738546D01*
X1549362Y1738129D01*
X1549335Y1737754D01*
X1549389Y1737379D01*
X1549469Y1737129D01*
X1549629Y1736879D01*
X1549815Y1736712D01*
X1550002Y1736629D01*
X1550189D01*
X1550375Y1736712D01*
X1550535Y1736837D01*
X1550669Y1737004D01*
G01X1551535Y1736629D02*
X1552202Y1739129D01*
X1552869Y1736629D01*
G01X1552629Y1737504D02*
X1551775D01*
G01X1553869Y1736629D02*
Y1739129D01*
X1554535D01*
X1554749Y1739004D01*
X1554882Y1738837D01*
X1554935Y1738504D01*
X1554882Y1738171D01*
X1554722Y1737962D01*
X1554535Y1737837D01*
X1553869D01*
G01X1554535D02*
X1554935Y1736629D01*
G01X1556015D02*
Y1739129D01*
X1556549D01*
X1556762Y1739004D01*
X1556922Y1738837D01*
X1557055Y1738587D01*
X1557162Y1738296D01*
X1557189Y1737879D01*
X1557162Y1737462D01*
X1557055Y1737171D01*
X1556922Y1736921D01*
X1556762Y1736754D01*
X1556549Y1736629D01*
X1556015D01*
G01X1498031Y1740118D02*
X1564566D01*
G01X1510052Y1736412D02*
X1510952Y1737312D01*
G01X1505052Y1736412D02*
X1510052D01*
G01X1505052Y1739812D02*
Y1736412D01*
G01X1507052Y1737812D02*
X1505052Y1739812D01*
G01X1503052Y1737812D02*
X1507052D01*
G01X1505052Y1739812D02*
X1503052Y1737812D01*
G01X1515904Y-27500D02*
X1516214Y-27308D01*
X1516421Y-27078D01*
X1516524Y-26810D01*
X1516421Y-26503D01*
X1516214Y-26273D01*
X1515904Y-26043D01*
X1515491Y-25966D01*
X1513424D01*
G01X1516524Y-23710D02*
X1515852Y-23633D01*
X1515284Y-23518D01*
X1514767Y-23365D01*
X1514199Y-23173D01*
X1513424Y-22866D01*
Y-24400D01*
G01X1513941Y-21261D02*
X1513631Y-21031D01*
X1513476Y-20763D01*
X1513424Y-20456D01*
X1513527Y-20073D01*
X1513786Y-19805D01*
X1514096Y-19728D01*
X1514406Y-19766D01*
X1514664Y-19920D01*
X1515181Y-20686D01*
X1515542Y-21031D01*
X1516059Y-21261D01*
X1516524Y-21338D01*
Y-19728D01*
G01X1525755Y-2520D02*
X1796307D01*
G01X1525755Y48800D02*
Y-2520D01*
G01X1519042Y132413D02*
Y129213D01*
G01X1522219Y202850D02*
X1528419D01*
G01Y199650D02*
X1522219D01*
G01D02*
Y202850D01*
G01X1523619Y207650D02*
X1517419D01*
G01D02*
Y210850D01*
G01X1523619D02*
Y207650D01*
G01X1515244Y226775D02*
Y220575D01*
G01X1523619Y211650D02*
X1517419D01*
G01D02*
Y214850D01*
G01D02*
X1523619D01*
G01D02*
Y211650D01*
G01Y219650D02*
X1517419D01*
G01D02*
Y222850D01*
G01D02*
X1523619D01*
G01D02*
Y219650D01*
G01X1517419Y210850D02*
X1523619D01*
G01X1515244Y217925D02*
Y211725D01*
G01X1523619Y223650D02*
X1517419D01*
G01D02*
Y226850D01*
G01X1523619D02*
Y223650D01*
G01Y229650D02*
X1517419D01*
G01D02*
Y232850D01*
G01D02*
X1523619D01*
G01D02*
Y229650D01*
G01Y236417D02*
X1517419D01*
G01D02*
Y239617D01*
G01D02*
X1523619D01*
G01D02*
Y236417D01*
G01X1517419Y226850D02*
X1523619D01*
G01X1515244Y251025D02*
Y244825D01*
G01X1523619Y247650D02*
X1517419D01*
G01D02*
Y250850D01*
G01D02*
X1523619D01*
G01D02*
Y247650D01*
G01Y242650D02*
X1517419D01*
G01D02*
Y245850D01*
G01D02*
X1523619D01*
G01D02*
Y242650D01*
G01Y251650D02*
X1517419D01*
G01D02*
Y254850D01*
G01D02*
X1523619D01*
G01D02*
Y251650D01*
G01X1514948Y261138D02*
Y254938D01*
G01X1515357Y549577D02*
Y546377D01*
G01Y545577D02*
Y542377D01*
G01Y553577D02*
Y550377D01*
G01Y565577D02*
Y562377D01*
G01X1526253Y567364D02*
X1529453D01*
G01Y561164D02*
X1526253D01*
G01D02*
Y567364D01*
G01X1525180Y576432D02*
Y586274D01*
G01X1555574Y576432D02*
X1525180D01*
G01X1522075Y597527D02*
Y603638D01*
G01X1525180Y586274D02*
X1555574D01*
G01X1522075Y615038D02*
Y621149D01*
G01X1517746Y627602D02*
Y630702D01*
X1518666D01*
X1518973Y630547D01*
X1519203Y630185D01*
X1519280Y629772D01*
X1519203Y629359D01*
X1519011Y629049D01*
X1518666Y628894D01*
X1517746D01*
G01X1522456Y630444D02*
X1522226Y630599D01*
X1521958Y630702D01*
X1521651D01*
X1521306Y630547D01*
X1521038Y630289D01*
X1520846Y629979D01*
X1520693Y629462D01*
X1520655Y628997D01*
X1520731Y628532D01*
X1520846Y628222D01*
X1521076Y627912D01*
X1521345Y627705D01*
X1521613Y627602D01*
X1521881D01*
X1522150Y627705D01*
X1522380Y627860D01*
X1522571Y628067D01*
G01X1523870D02*
X1524100Y627809D01*
X1524368Y627654D01*
X1524713Y627602D01*
X1525058Y627705D01*
X1525326Y627912D01*
X1525518Y628274D01*
X1525556Y628687D01*
X1525480Y629100D01*
X1525288Y629359D01*
X1525020Y629565D01*
X1524751Y629617D01*
X1524483Y629565D01*
X1524138Y629359D01*
X1524253Y630702D01*
X1525288D01*
G01X1527161Y627964D02*
X1527430Y627705D01*
X1527736Y627602D01*
X1528043Y627705D01*
X1528311Y628015D01*
X1528503Y628480D01*
X1528580Y628945D01*
Y629514D01*
X1528503Y629979D01*
X1528311Y630392D01*
X1528081Y630599D01*
X1527813Y630702D01*
X1527506Y630599D01*
X1527276Y630392D01*
X1527123Y630082D01*
X1527046Y629669D01*
X1527123Y629307D01*
X1527315Y628945D01*
X1527545Y628739D01*
X1527813Y628687D01*
X1528120Y628790D01*
X1528350Y629049D01*
X1528580Y629514D01*
G01X1530185Y628894D02*
X1530453Y629255D01*
X1530683Y629462D01*
X1530990Y629565D01*
X1531258Y629462D01*
X1531450Y629255D01*
X1531603Y628945D01*
X1531641Y628584D01*
X1531603Y628274D01*
X1531450Y627964D01*
X1531220Y627705D01*
X1530951Y627602D01*
X1530645Y627705D01*
X1530376Y628015D01*
X1530223Y628480D01*
X1530185Y628997D01*
X1530261Y629669D01*
X1530376Y630030D01*
X1530568Y630392D01*
X1530836Y630650D01*
X1531105Y630702D01*
X1531373Y630599D01*
X1531565Y630340D01*
G01X1519691Y700603D02*
X1513491D01*
G01D02*
Y703803D01*
G01X1519691D02*
Y700603D01*
G01X1524476Y698050D02*
Y704250D01*
G01X1527676D02*
Y698050D01*
G01D02*
X1524476D01*
G01X1517189Y693736D02*
Y696836D01*
X1518109D01*
X1518416Y696681D01*
X1518646Y696319D01*
X1518723Y695906D01*
X1518646Y695493D01*
X1518454Y695183D01*
X1518109Y695028D01*
X1517189D01*
G01X1520213Y696836D02*
Y694614D01*
X1520366Y694149D01*
X1520673Y693839D01*
X1521056Y693736D01*
X1521439Y693839D01*
X1521746Y694149D01*
X1521899Y694614D01*
Y696836D01*
G01X1524616Y693736D02*
Y696836D01*
X1523198Y694614D01*
X1525114D01*
G01X1527179Y693736D02*
X1527256Y694408D01*
X1527371Y694976D01*
X1527524Y695493D01*
X1527716Y696061D01*
X1528023Y696836D01*
X1526489D01*
G01X1513491Y703803D02*
X1519691D01*
G01X1524476Y704250D02*
X1527676D01*
G01X1517097Y716038D02*
Y722238D01*
G01X1520297D02*
Y716038D01*
G01D02*
X1517097D01*
G01X1516407Y712071D02*
Y705871D01*
G01D02*
X1513207D01*
G01D02*
Y707000D01*
G01Y712071D02*
X1516407D01*
G01X1513207Y710400D02*
Y712071D01*
G01Y716371D02*
Y722571D01*
G01X1516407D02*
Y716371D01*
G01D02*
X1513207D01*
G01X1523997Y707653D02*
X1523264D01*
G01D02*
Y709844D01*
G01X1517097Y722238D02*
X1520297D01*
G01X1513207Y722571D02*
X1516407D01*
G01X1517950Y732892D02*
Y729692D01*
G01X1513184Y729392D02*
X1516384D01*
G01X1513184Y723192D02*
Y729392D01*
G01X1516384Y723192D02*
X1513184D01*
G01X1516384Y729392D02*
Y723192D01*
G01X1523264Y728675D02*
Y731275D01*
G01D02*
X1524057D01*
G01X1517879Y734492D02*
X1523220D01*
G01X1517879Y777800D02*
Y734492D01*
G01X1514607Y777800D02*
Y734492D01*
G01X1523220Y777800D02*
X1517879D01*
G01X1523102Y855827D02*
G03X1525071Y857796I0J1969D01*
G01Y870788D02*
Y857796D01*
G01X1519362Y1180630D02*
Y1167638D01*
G01Y1180630D02*
G03X1517394Y1182599I-1969J0D01*
G01X1517634Y1611053D02*
X1515208D01*
G01X1555172Y1602365D02*
X1519432D01*
Y1619295D01*
X1555172D01*
Y1602365D01*
G01X1527600Y1655760D02*
X1524500D01*
X1526722Y1654342D01*
Y1656258D01*
G01X1519280Y1654557D02*
X1519642Y1654787D01*
X1519848Y1655093D01*
X1519900Y1655438D01*
X1519848Y1655745D01*
X1519590Y1656052D01*
X1519280Y1656243D01*
X1518970Y1656282D01*
X1518608Y1656205D01*
X1518350Y1655937D01*
X1518247Y1655668D01*
Y1655323D01*
G01Y1655668D02*
X1518092Y1655898D01*
X1517833Y1656090D01*
X1517523Y1656167D01*
X1517213Y1656090D01*
X1516955Y1655898D01*
X1516800Y1655553D01*
X1516852Y1655208D01*
X1517058Y1654863D01*
G01X1531600Y1646023D02*
X1525000D01*
G01X1519700D02*
X1512900D01*
G01X1513500Y1657834D02*
X1518700D01*
G01X1525100D02*
X1531100D01*
G01X1538116Y-16072D02*
Y-32352D01*
X1528516D01*
Y-16072D01*
X1538116D01*
G01X1527881Y43779D02*
Y79D01*
G01D02*
X1794181D01*
G01X1530000Y43779D02*
X1527881D01*
G01X1539071D02*
X1535000D01*
G01X1545000Y51142D02*
X1530300D01*
G01X1533500Y86621D02*
X1531854D01*
G01D02*
Y92821D01*
G01X1539054Y86621D02*
X1537500D01*
G01X1539054Y92821D02*
Y86621D01*
G01X1531854Y92821D02*
X1533500D01*
G01X1537500D02*
X1539054D01*
G01X1532336Y191957D02*
Y199457D01*
G01X1536256D02*
Y191957D01*
G01Y195707D02*
X1532336D01*
G01X1539743Y191957D02*
Y199457D01*
X1541609D01*
X1542356Y199082D01*
X1542916Y198582D01*
X1543383Y197832D01*
X1543756Y196957D01*
X1543849Y195707D01*
X1543756Y194457D01*
X1543383Y193582D01*
X1542916Y192832D01*
X1542356Y192332D01*
X1541609Y191957D01*
X1539743D01*
G01X1549296Y199457D02*
Y191957D01*
G01X1547149Y199457D02*
X1551443D01*
G01X1566349Y198832D02*
X1565789Y199207D01*
X1565136Y199457D01*
X1564389D01*
X1563549Y199082D01*
X1562896Y198457D01*
X1562429Y197707D01*
X1562056Y196457D01*
X1561963Y195332D01*
X1562149Y194207D01*
X1562429Y193457D01*
X1562989Y192707D01*
X1563643Y192207D01*
X1564296Y191957D01*
X1564949D01*
X1565603Y192207D01*
X1566163Y192582D01*
X1566629Y193082D01*
G01X1571796Y191957D02*
X1571049Y192082D01*
X1570396Y192582D01*
X1569836Y193332D01*
X1569463Y194207D01*
X1569276Y195207D01*
Y196207D01*
X1569463Y197207D01*
X1569836Y198082D01*
X1570396Y198832D01*
X1571049Y199332D01*
X1571796Y199457D01*
X1572543Y199332D01*
X1573196Y198832D01*
X1573756Y198082D01*
X1574129Y197207D01*
X1574316Y196207D01*
Y195207D01*
X1574129Y194207D01*
X1573756Y193332D01*
X1573196Y192582D01*
X1572543Y192082D01*
X1571796Y191957D01*
G01X1577149D02*
Y199457D01*
X1581443Y191957D01*
Y199457D01*
G01X1584649Y191957D02*
Y199457D01*
X1588943Y191957D01*
Y199457D01*
G01X1528419Y202850D02*
Y199650D01*
G01X1537414Y290416D02*
X1543614D01*
G01X1537414Y287216D02*
Y290416D01*
G01X1543614Y287216D02*
X1537414D01*
G01X1537417Y294416D02*
X1543617D01*
G01X1537417Y291216D02*
Y294416D01*
G01X1543617Y291216D02*
X1537417D01*
G01Y299216D02*
Y302416D01*
G01X1543617Y299216D02*
X1537417D01*
G01X1543617Y295216D02*
X1537417D01*
Y298416D01*
X1543617D01*
Y295216D01*
G01X1537417Y302416D02*
X1543617D01*
G01X1537417Y307216D02*
Y310416D01*
G01X1543617Y307216D02*
X1537417D01*
G01Y310416D02*
X1543617D01*
G01X1537417Y303216D02*
Y306416D01*
G01X1543617Y303216D02*
X1537417D01*
G01Y306416D02*
X1543617D01*
G01X1542142Y396131D02*
Y401131D01*
X1544548D01*
G01X1543662Y398714D02*
X1542142D01*
G01X1547178Y396131D02*
Y401131D01*
X1548698D01*
X1549205Y400881D01*
X1549585Y400298D01*
X1549712Y399631D01*
X1549585Y398964D01*
X1549268Y398464D01*
X1548698Y398214D01*
X1547178D01*
G01X1553925Y398631D02*
X1555192D01*
Y397131D01*
X1554812Y396631D01*
X1554368Y396298D01*
X1553735Y396131D01*
X1553102Y396298D01*
X1552658Y396631D01*
X1552278Y397131D01*
X1552025Y397714D01*
X1551898Y398381D01*
Y398964D01*
X1552025Y399464D01*
X1552278Y400048D01*
X1552658Y400548D01*
X1553038Y400881D01*
X1553545Y401131D01*
X1553988D01*
X1554495Y400964D01*
X1554875Y400631D01*
G01X1557062Y396131D02*
X1558645Y401131D01*
X1560228Y396131D01*
G01X1559658Y397881D02*
X1557632D01*
G01X1567452Y396131D02*
Y401131D01*
X1568718D01*
X1569225Y400881D01*
X1569605Y400548D01*
X1569922Y400048D01*
X1570175Y399464D01*
X1570238Y398631D01*
X1570175Y397798D01*
X1569922Y397214D01*
X1569605Y396714D01*
X1569225Y396381D01*
X1568718Y396131D01*
X1567452D01*
G01X1575212D02*
X1572678D01*
Y401131D01*
X1575212D01*
G01X1574198Y398714D02*
X1572678D01*
G01X1579552Y398798D02*
X1579805Y399048D01*
X1579995Y399464D01*
X1580122Y400048D01*
X1579995Y400548D01*
X1579742Y400881D01*
X1579298Y401131D01*
X1577588D01*
Y396131D01*
X1579678D01*
X1580122Y396464D01*
X1580375Y396964D01*
X1580502Y397548D01*
X1580375Y398131D01*
X1579995Y398631D01*
X1579552Y398798D01*
X1577588D01*
G01X1582752Y401131D02*
Y397548D01*
X1583005Y396798D01*
X1583512Y396298D01*
X1584145Y396131D01*
X1584778Y396298D01*
X1585285Y396798D01*
X1585538Y397548D01*
Y401131D01*
G01X1589625Y398631D02*
X1590892D01*
Y397131D01*
X1590512Y396631D01*
X1590068Y396298D01*
X1589435Y396131D01*
X1588802Y396298D01*
X1588358Y396631D01*
X1587978Y397131D01*
X1587725Y397714D01*
X1587598Y398381D01*
Y398964D01*
X1587725Y399464D01*
X1587978Y400048D01*
X1588358Y400548D01*
X1588738Y400881D01*
X1589245Y401131D01*
X1589688D01*
X1590195Y400964D01*
X1590575Y400631D01*
G01X1598178Y401131D02*
Y396131D01*
X1600712D01*
G01X1605812D02*
X1603278D01*
Y401131D01*
X1605812D01*
G01X1604798Y398714D02*
X1603278D01*
G01X1608252Y396131D02*
Y401131D01*
X1609518D01*
X1610025Y400881D01*
X1610405Y400548D01*
X1610722Y400048D01*
X1610975Y399464D01*
X1611038Y398631D01*
X1610975Y397798D01*
X1610722Y397214D01*
X1610405Y396714D01*
X1610025Y396381D01*
X1609518Y396131D01*
X1608252D01*
G01X1535254Y493600D02*
Y394600D01*
G01X1544738Y418914D02*
X1544358Y419164D01*
X1543915Y419331D01*
X1543408D01*
X1542838Y419081D01*
X1542395Y418664D01*
X1542078Y418164D01*
X1541825Y417331D01*
X1541762Y416581D01*
X1541888Y415831D01*
X1542078Y415331D01*
X1542458Y414831D01*
X1542902Y414498D01*
X1543345Y414331D01*
X1543788D01*
X1544232Y414498D01*
X1544612Y414748D01*
X1544928Y415081D01*
G01X1547178Y414331D02*
Y419331D01*
X1548698D01*
X1549205Y419081D01*
X1549585Y418498D01*
X1549712Y417831D01*
X1549585Y417164D01*
X1549268Y416664D01*
X1548698Y416414D01*
X1547178D01*
G01X1552152Y419331D02*
Y415748D01*
X1552405Y414998D01*
X1552912Y414498D01*
X1553545Y414331D01*
X1554178Y414498D01*
X1554685Y414998D01*
X1554938Y415748D01*
Y419331D01*
G01X1558645Y414331D02*
Y419331D01*
X1557885Y418331D01*
G01Y414331D02*
X1559405D01*
G01X1544738Y410314D02*
X1544358Y410564D01*
X1543915Y410731D01*
X1543408D01*
X1542838Y410481D01*
X1542395Y410064D01*
X1542078Y409564D01*
X1541825Y408731D01*
X1541762Y407981D01*
X1541888Y407231D01*
X1542078Y406731D01*
X1542458Y406231D01*
X1542902Y405898D01*
X1543345Y405731D01*
X1543788D01*
X1544232Y405898D01*
X1544612Y406148D01*
X1544928Y406481D01*
G01X1547178Y410731D02*
Y405731D01*
X1549712D01*
G01X1552278D02*
Y410731D01*
X1553862D01*
X1554368Y410481D01*
X1554685Y410148D01*
X1554812Y409481D01*
X1554685Y408814D01*
X1554305Y408398D01*
X1553862Y408148D01*
X1552278D01*
G01X1553862D02*
X1554812Y405731D01*
G01X1562478D02*
Y410731D01*
X1563998D01*
X1564505Y410481D01*
X1564885Y409898D01*
X1565012Y409231D01*
X1564885Y408564D01*
X1564568Y408064D01*
X1563998Y407814D01*
X1562478D01*
G01X1566945Y410731D02*
X1567832Y405731D01*
X1568845Y410731D01*
X1569858Y405731D01*
X1570745Y410731D01*
G01X1572552Y405731D02*
Y410731D01*
X1573818D01*
X1574325Y410481D01*
X1574705Y410148D01*
X1575022Y409648D01*
X1575275Y409064D01*
X1575338Y408231D01*
X1575275Y407398D01*
X1575022Y406814D01*
X1574705Y406314D01*
X1574325Y405981D01*
X1573818Y405731D01*
X1572552D01*
G01X1544612Y432531D02*
X1542078D01*
Y437531D01*
X1544612D01*
G01X1543598Y435114D02*
X1542078D01*
G01X1546988Y432531D02*
Y437531D01*
X1549902Y432531D01*
Y437531D01*
G01X1551962Y432531D02*
X1553545Y437531D01*
X1555128Y432531D01*
G01X1554558Y434281D02*
X1552532D01*
G01X1559152Y435198D02*
X1559405Y435448D01*
X1559595Y435864D01*
X1559722Y436448D01*
X1559595Y436948D01*
X1559342Y437281D01*
X1558898Y437531D01*
X1557188D01*
Y432531D01*
X1559278D01*
X1559722Y432864D01*
X1559975Y433364D01*
X1560102Y433948D01*
X1559975Y434531D01*
X1559595Y435031D01*
X1559152Y435198D01*
X1557188D01*
G01X1562478Y437531D02*
Y432531D01*
X1565012D01*
G01X1570112D02*
X1567578D01*
Y437531D01*
X1570112D01*
G01X1569098Y435114D02*
X1567578D01*
G01X1544738Y428514D02*
X1544358Y428764D01*
X1543915Y428931D01*
X1543408D01*
X1542838Y428681D01*
X1542395Y428264D01*
X1542078Y427764D01*
X1541825Y426931D01*
X1541762Y426181D01*
X1541888Y425431D01*
X1542078Y424931D01*
X1542458Y424431D01*
X1542902Y424098D01*
X1543345Y423931D01*
X1543788D01*
X1544232Y424098D01*
X1544612Y424348D01*
X1544928Y424681D01*
G01X1547178Y423931D02*
Y428931D01*
X1548698D01*
X1549205Y428681D01*
X1549585Y428098D01*
X1549712Y427431D01*
X1549585Y426764D01*
X1549268Y426264D01*
X1548698Y426014D01*
X1547178D01*
G01X1552152Y428931D02*
Y425348D01*
X1552405Y424598D01*
X1552912Y424098D01*
X1553545Y423931D01*
X1554178Y424098D01*
X1554685Y424598D01*
X1554938Y425348D01*
Y428931D01*
G01X1558645D02*
X1558138Y428764D01*
X1557758Y428348D01*
X1557505Y427848D01*
X1557315Y427181D01*
X1557252Y426431D01*
X1557315Y425681D01*
X1557505Y425014D01*
X1557758Y424514D01*
X1558138Y424098D01*
X1558645Y423931D01*
X1559152Y424098D01*
X1559532Y424514D01*
X1559785Y425014D01*
X1559975Y425681D01*
X1560038Y426431D01*
X1559975Y427181D01*
X1559785Y427848D01*
X1559532Y428348D01*
X1559152Y428764D01*
X1558645Y428931D01*
G01X1542142Y441631D02*
Y446631D01*
X1544548D01*
G01X1543662Y444214D02*
X1542142D01*
G01X1547178Y441631D02*
Y446631D01*
X1548762D01*
X1549268Y446381D01*
X1549585Y446048D01*
X1549712Y445381D01*
X1549585Y444714D01*
X1549205Y444298D01*
X1548762Y444048D01*
X1547178D01*
G01X1548762D02*
X1549712Y441631D01*
G01X1552152Y446631D02*
Y443048D01*
X1552405Y442298D01*
X1552912Y441798D01*
X1553545Y441631D01*
X1554178Y441798D01*
X1554685Y442298D01*
X1554938Y443048D01*
Y446631D01*
G01X1542015Y459331D02*
Y464331D01*
G01X1544675D02*
Y459331D01*
G01Y461831D02*
X1542015D01*
G01X1547052Y459331D02*
Y464331D01*
X1548318D01*
X1548825Y464081D01*
X1549205Y463748D01*
X1549522Y463248D01*
X1549775Y462664D01*
X1549838Y461831D01*
X1549775Y460998D01*
X1549522Y460414D01*
X1549205Y459914D01*
X1548825Y459581D01*
X1548318Y459331D01*
X1547052D01*
G01X1553545Y464331D02*
Y459331D01*
G01X1552088Y464331D02*
X1555002D01*
G01X1542078Y450731D02*
Y455731D01*
X1543662D01*
X1544168Y455481D01*
X1544485Y455148D01*
X1544612Y454481D01*
X1544485Y453814D01*
X1544105Y453398D01*
X1543662Y453148D01*
X1542078D01*
G01X1543662D02*
X1544612Y450731D01*
G01X1549838Y455314D02*
X1549458Y455564D01*
X1549015Y455731D01*
X1548508D01*
X1547938Y455481D01*
X1547495Y455064D01*
X1547178Y454564D01*
X1546925Y453731D01*
X1546862Y452981D01*
X1546988Y452231D01*
X1547178Y451731D01*
X1547558Y451231D01*
X1548002Y450898D01*
X1548445Y450731D01*
X1548888D01*
X1549332Y450898D01*
X1549712Y451148D01*
X1550028Y451481D01*
G01X1551962Y455731D02*
X1553545Y450731D01*
X1555128Y455731D01*
G01X1558645Y450731D02*
Y452981D01*
X1557378Y455731D01*
G01X1559912D02*
X1558645Y452981D01*
G01X1543852Y480198D02*
X1544105Y480448D01*
X1544295Y480864D01*
X1544422Y481448D01*
X1544295Y481948D01*
X1544042Y482281D01*
X1543598Y482531D01*
X1541888D01*
Y477531D01*
X1543978D01*
X1544422Y477864D01*
X1544675Y478364D01*
X1544802Y478948D01*
X1544675Y479531D01*
X1544295Y480031D01*
X1543852Y480198D01*
X1541888D01*
G01X1546798Y477531D02*
Y482531D01*
X1548445Y478364D01*
X1550092Y482531D01*
Y477531D01*
G01X1554938Y482114D02*
X1554558Y482364D01*
X1554115Y482531D01*
X1553608D01*
X1553038Y482281D01*
X1552595Y481864D01*
X1552278Y481364D01*
X1552025Y480531D01*
X1551962Y479781D01*
X1552088Y479031D01*
X1552278Y478531D01*
X1552658Y478031D01*
X1553102Y477698D01*
X1553545Y477531D01*
X1553988D01*
X1554432Y477698D01*
X1554812Y477948D01*
X1555128Y478281D01*
G01X1544612Y468431D02*
X1542078D01*
Y473431D01*
X1544612D01*
G01X1543598Y471014D02*
X1542078D01*
G01X1546988Y468431D02*
Y473431D01*
X1549902Y468431D01*
Y473431D01*
G01X1551962Y468431D02*
X1553545Y473431D01*
X1555128Y468431D01*
G01X1554558Y470181D02*
X1552532D01*
G01X1559152Y471098D02*
X1559405Y471348D01*
X1559595Y471764D01*
X1559722Y472348D01*
X1559595Y472848D01*
X1559342Y473181D01*
X1558898Y473431D01*
X1557188D01*
Y468431D01*
X1559278D01*
X1559722Y468764D01*
X1559975Y469264D01*
X1560102Y469848D01*
X1559975Y470431D01*
X1559595Y470931D01*
X1559152Y471098D01*
X1557188D01*
G01X1562478Y473431D02*
Y468431D01*
X1565012D01*
G01X1570112D02*
X1567578D01*
Y473431D01*
X1570112D01*
G01X1569098Y471014D02*
X1567578D01*
G01X1543345Y486131D02*
X1542838Y486214D01*
X1542395Y486548D01*
X1542015Y487048D01*
X1541762Y487631D01*
X1541635Y488298D01*
Y488964D01*
X1541762Y489631D01*
X1542015Y490214D01*
X1542395Y490714D01*
X1542838Y491048D01*
X1543345Y491131D01*
X1543852Y491048D01*
X1544295Y490714D01*
X1544675Y490214D01*
X1544928Y489631D01*
X1545055Y488964D01*
Y488298D01*
X1544928Y487631D01*
X1544675Y487048D01*
X1544295Y486548D01*
X1543852Y486214D01*
X1543345Y486131D01*
G01X1546988D02*
Y491131D01*
X1549902Y486131D01*
Y491131D01*
G01X1541293Y542713D02*
Y536513D01*
G01D02*
X1538093D01*
G01D02*
Y542713D01*
G01D02*
X1541293D01*
G01X1538275Y552278D02*
X1539775Y551278D01*
G01D02*
X1538275Y550278D01*
G01X1547075Y544478D02*
X1538275D01*
G01Y558078D02*
Y552278D01*
G01Y550278D02*
Y544478D01*
G01X1541097Y560487D02*
Y566687D01*
G01D02*
X1544297D01*
G01Y560487D02*
X1541097D01*
G01X1536253Y567364D02*
X1539453D01*
G01D02*
Y561164D01*
G01D02*
X1536253D01*
G01D02*
Y567364D01*
G01X1529453D02*
Y561164D01*
G01X1538275Y558078D02*
X1547075D01*
G01X1538098Y589575D02*
X1544098D01*
G01D02*
X1541098Y586575D01*
G01X1529402Y588467D02*
X1529632Y588105D01*
X1529938Y587899D01*
X1530283Y587847D01*
X1530590Y587899D01*
X1530897Y588157D01*
X1531088Y588467D01*
X1531127Y588777D01*
X1531050Y589139D01*
X1530782Y589397D01*
X1530513Y589500D01*
X1530168D01*
G01X1530513D02*
X1530743Y589655D01*
X1530935Y589914D01*
X1531012Y590224D01*
X1530935Y590534D01*
X1530743Y590792D01*
X1530398Y590947D01*
X1530053Y590895D01*
X1529708Y590689D01*
G01X1545313Y697240D02*
X1542113D01*
G01D02*
Y703440D01*
G01X1535143Y700546D02*
X1541343D01*
G01D02*
Y697346D01*
G01D02*
X1535143D01*
G01D02*
Y700546D01*
G01X1531718Y704250D02*
Y698050D01*
G01D02*
X1528518D01*
G01D02*
Y704250D01*
G01X1542113Y703440D02*
X1545313D01*
G01X1528518Y704250D02*
X1531718D01*
G01X1542950Y707653D02*
X1541942D01*
G01X1542157Y731275D02*
X1542950D01*
G01X1547407Y734492D02*
X1542066D01*
G01Y777800D02*
X1547407D01*
G01X1528280Y1463430D02*
Y1424430D01*
G01D02*
X1618280D01*
G01X1539323Y1441393D02*
X1531823Y1443726D01*
X1539323Y1446059D01*
G01X1536698Y1445219D02*
Y1442233D01*
G01X1536198Y1449453D02*
X1535323Y1450106D01*
X1534823Y1450666D01*
X1534573Y1451413D01*
X1534823Y1452066D01*
X1535323Y1452533D01*
X1536073Y1452906D01*
X1536948Y1452999D01*
X1537698Y1452906D01*
X1538448Y1452533D01*
X1539073Y1451973D01*
X1539323Y1451319D01*
X1539073Y1450573D01*
X1538323Y1449919D01*
X1537198Y1449546D01*
X1535948Y1449453D01*
X1534323Y1449639D01*
X1533448Y1449919D01*
X1532573Y1450386D01*
X1531948Y1451039D01*
X1531823Y1451693D01*
X1532073Y1452346D01*
X1532698Y1452813D01*
G01X1528280Y1437930D02*
X1543280D01*
G01X1618280Y1463430D02*
X1528280D01*
G01X1539244Y1540451D02*
X1531900D01*
G01X1539244Y1575491D02*
Y1540451D01*
G01X1532400Y1575491D02*
X1539244D01*
G01X1543108Y1654672D02*
X1542747Y1654940D01*
X1542540Y1655170D01*
X1542437Y1655477D01*
X1542540Y1655745D01*
X1542747Y1655937D01*
X1543057Y1656090D01*
X1543418Y1656128D01*
X1543728Y1656090D01*
X1544038Y1655937D01*
X1544297Y1655707D01*
X1544400Y1655438D01*
X1544297Y1655132D01*
X1543987Y1654863D01*
X1543522Y1654710D01*
X1543005Y1654672D01*
X1542333Y1654748D01*
X1541972Y1654863D01*
X1541610Y1655055D01*
X1541352Y1655323D01*
X1541300Y1655592D01*
X1541403Y1655860D01*
X1541662Y1656052D01*
G01X1539335Y1654557D02*
X1539593Y1654787D01*
X1539748Y1655055D01*
X1539800Y1655400D01*
X1539697Y1655745D01*
X1539490Y1656013D01*
X1539128Y1656205D01*
X1538715Y1656243D01*
X1538302Y1656167D01*
X1538043Y1655975D01*
X1537837Y1655707D01*
X1537785Y1655438D01*
X1537837Y1655170D01*
X1538043Y1654825D01*
X1536700Y1654940D01*
Y1655975D01*
G01X1543500Y1646023D02*
X1536900D01*
G01X1537400Y1657834D02*
X1542700D01*
G01X1554500Y51142D02*
X1552000D01*
G01X1546796Y81257D02*
X1546049Y81382D01*
X1545396Y81882D01*
X1544836Y82632D01*
X1544463Y83507D01*
X1544276Y84507D01*
Y85507D01*
X1544463Y86507D01*
X1544836Y87382D01*
X1545396Y88132D01*
X1546049Y88632D01*
X1546796Y88757D01*
X1547543Y88632D01*
X1548196Y88132D01*
X1548756Y87382D01*
X1549129Y86507D01*
X1549316Y85507D01*
Y84507D01*
X1549129Y83507D01*
X1548756Y82632D01*
X1548196Y81882D01*
X1547543Y81382D01*
X1546796Y81257D01*
G01X1556349Y88132D02*
X1555789Y88507D01*
X1555136Y88757D01*
X1554389D01*
X1553549Y88382D01*
X1552896Y87757D01*
X1552429Y87007D01*
X1552056Y85757D01*
X1551963Y84632D01*
X1552149Y83507D01*
X1552429Y82757D01*
X1552989Y82007D01*
X1553643Y81507D01*
X1554296Y81257D01*
X1554949D01*
X1555603Y81507D01*
X1556163Y81882D01*
X1556629Y82382D01*
G01X1559929Y81257D02*
Y88757D01*
X1562169D01*
X1562916Y88382D01*
X1563476Y87507D01*
X1563663Y86507D01*
X1563476Y85507D01*
X1563009Y84757D01*
X1562169Y84382D01*
X1559929D01*
G01X1574649Y81257D02*
Y88757D01*
X1578943Y81257D01*
Y88757D01*
G01X1583176D02*
X1585416D01*
G01X1584296D02*
Y81257D01*
G01X1583176D02*
X1585416D01*
G01X1593849Y88132D02*
X1593289Y88507D01*
X1592636Y88757D01*
X1591889D01*
X1591049Y88382D01*
X1590396Y87757D01*
X1589929Y87007D01*
X1589556Y85757D01*
X1589463Y84632D01*
X1589649Y83507D01*
X1589929Y82757D01*
X1590489Y82007D01*
X1591143Y81507D01*
X1591796Y81257D01*
X1592449D01*
X1593103Y81507D01*
X1593663Y81882D01*
X1594129Y82382D01*
G01X1606796Y88757D02*
X1606049Y88507D01*
X1605489Y87882D01*
X1605116Y87132D01*
X1604836Y86132D01*
X1604743Y85007D01*
X1604836Y83882D01*
X1605116Y82882D01*
X1605489Y82132D01*
X1606049Y81507D01*
X1606796Y81257D01*
X1607543Y81507D01*
X1608103Y82132D01*
X1608476Y82882D01*
X1608756Y83882D01*
X1608849Y85007D01*
X1608756Y86132D01*
X1608476Y87132D01*
X1608103Y87882D01*
X1607543Y88507D01*
X1606796Y88757D01*
G01X1553462Y201277D02*
X1553654Y200967D01*
X1553884Y200760D01*
X1554152Y200657D01*
X1554459Y200760D01*
X1554689Y200967D01*
X1554919Y201277D01*
X1554996Y201690D01*
Y203757D01*
G01X1556486Y201122D02*
X1556716Y200864D01*
X1556984Y200709D01*
X1557329Y200657D01*
X1557674Y200760D01*
X1557942Y200967D01*
X1558134Y201329D01*
X1558172Y201742D01*
X1558096Y202155D01*
X1557904Y202414D01*
X1557636Y202620D01*
X1557367Y202672D01*
X1557099Y202620D01*
X1556754Y202414D01*
X1556869Y203757D01*
X1557904D01*
G01X1560889Y200657D02*
Y203757D01*
X1559471Y201535D01*
X1561387D01*
G01X1563769Y206750D02*
X1546053D01*
G01D02*
Y207050D01*
G01Y222050D02*
Y221450D01*
G01Y217050D02*
Y216450D01*
G01Y212050D02*
Y211450D01*
G01Y237050D02*
Y236450D01*
G01Y232050D02*
Y231450D01*
G01Y227050D02*
Y226450D01*
G01Y252050D02*
Y251450D01*
G01Y247050D02*
Y246450D01*
G01Y242050D02*
Y241450D01*
G01Y256450D02*
Y256750D01*
G01D02*
X1563769D01*
G01X1545264Y282975D02*
Y286175D01*
G01X1551464Y282975D02*
X1545264D01*
G01X1551464Y286175D02*
Y282975D01*
G01X1552164D02*
Y286175D01*
G01X1558364Y282975D02*
X1552164D01*
G01X1545264Y286175D02*
X1551464D01*
G01X1552164D02*
X1558364D01*
G01X1543614Y290416D02*
Y287216D01*
G01X1543617Y294416D02*
Y291216D01*
G01Y302416D02*
Y299216D01*
G01X1550311Y294510D02*
Y296463D01*
G01X1552264Y294510D02*
X1550311D01*
G01X1543617Y310416D02*
Y307216D01*
G01Y306416D02*
Y303216D01*
G01X1550202Y318581D02*
Y316359D01*
X1550355Y315894D01*
X1550662Y315584D01*
X1551045Y315481D01*
X1551428Y315584D01*
X1551735Y315894D01*
X1551888Y316359D01*
Y318581D01*
G01X1553302Y315946D02*
X1553532Y315688D01*
X1553800Y315533D01*
X1554145Y315481D01*
X1554490Y315584D01*
X1554758Y315791D01*
X1554950Y316153D01*
X1554988Y316566D01*
X1554912Y316979D01*
X1554720Y317238D01*
X1554452Y317444D01*
X1554183Y317496D01*
X1553915Y317444D01*
X1553570Y317238D01*
X1553685Y318581D01*
X1554720D01*
G01X1556402Y315946D02*
X1556632Y315688D01*
X1556900Y315533D01*
X1557245Y315481D01*
X1557590Y315584D01*
X1557858Y315791D01*
X1558050Y316153D01*
X1558088Y316566D01*
X1558012Y316979D01*
X1557820Y317238D01*
X1557552Y317444D01*
X1557283Y317496D01*
X1557015Y317444D01*
X1556670Y317238D01*
X1556785Y318581D01*
X1557820D01*
G01X1550311Y306322D02*
X1552264D01*
G01X1550311Y304369D02*
Y306322D01*
G01X1548875Y550335D02*
X1551097D01*
X1551562Y550488D01*
X1551872Y550795D01*
X1551975Y551178D01*
X1551872Y551561D01*
X1551562Y551868D01*
X1551097Y552021D01*
X1548875D01*
G01X1549392Y553550D02*
X1549082Y553780D01*
X1548927Y554048D01*
X1548875Y554355D01*
X1548978Y554738D01*
X1549237Y555006D01*
X1549547Y555083D01*
X1549857Y555045D01*
X1550115Y554891D01*
X1550632Y554125D01*
X1550993Y553780D01*
X1551510Y553550D01*
X1551975Y553473D01*
Y555083D01*
G01X1551613Y556726D02*
X1551872Y556995D01*
X1551975Y557301D01*
X1551872Y557608D01*
X1551562Y557876D01*
X1551097Y558068D01*
X1550632Y558145D01*
X1550063D01*
X1549598Y558068D01*
X1549185Y557876D01*
X1548978Y557646D01*
X1548875Y557378D01*
X1548978Y557071D01*
X1549185Y556841D01*
X1549495Y556688D01*
X1549908Y556611D01*
X1550270Y556688D01*
X1550632Y556880D01*
X1550838Y557110D01*
X1550890Y557378D01*
X1550787Y557685D01*
X1550528Y557915D01*
X1550063Y558145D01*
G01X1547075Y558078D02*
Y544478D01*
G01X1544297Y566687D02*
Y560487D01*
G01X1548078Y571964D02*
Y575064D01*
X1548998D01*
X1549305Y574909D01*
X1549535Y574547D01*
X1549612Y574134D01*
X1549535Y573721D01*
X1549343Y573411D01*
X1548998Y573256D01*
X1548078D01*
G01X1551178Y572584D02*
X1551370Y572274D01*
X1551600Y572067D01*
X1551868Y571964D01*
X1552175Y572067D01*
X1552405Y572274D01*
X1552635Y572584D01*
X1552712Y572997D01*
Y575064D01*
G01X1555045Y571964D02*
Y575064D01*
X1554585Y574444D01*
G01Y571964D02*
X1555505D01*
G01X1555574Y586274D02*
Y576432D01*
G01X1549566Y671176D02*
Y674276D01*
X1550486D01*
X1550793Y674121D01*
X1551023Y673759D01*
X1551100Y673346D01*
X1551023Y672933D01*
X1550831Y672623D01*
X1550486Y672468D01*
X1549566D01*
G01X1552590Y674276D02*
Y672054D01*
X1552743Y671589D01*
X1553050Y671279D01*
X1553433Y671176D01*
X1553816Y671279D01*
X1554123Y671589D01*
X1554276Y672054D01*
Y674276D01*
G01X1556993Y671176D02*
Y674276D01*
X1555575Y672054D01*
X1557491D01*
G01X1558981Y671538D02*
X1559250Y671279D01*
X1559556Y671176D01*
X1559863Y671279D01*
X1560131Y671589D01*
X1560323Y672054D01*
X1560400Y672519D01*
Y673088D01*
X1560323Y673553D01*
X1560131Y673966D01*
X1559901Y674173D01*
X1559633Y674276D01*
X1559326Y674173D01*
X1559096Y673966D01*
X1558943Y673656D01*
X1558866Y673243D01*
X1558943Y672881D01*
X1559135Y672519D01*
X1559365Y672313D01*
X1559633Y672261D01*
X1559940Y672364D01*
X1560170Y672623D01*
X1560400Y673088D01*
G01X1557127Y685713D02*
X1556394D01*
G01D02*
Y687904D01*
G01X1545313Y703440D02*
Y697240D01*
G01X1546227Y693930D02*
Y700130D01*
G01D02*
X1549427D01*
G01D02*
Y693930D01*
G01D02*
X1546227D01*
G01X1550227D02*
Y700130D01*
G01D02*
X1553427D01*
G01D02*
Y693930D01*
G01D02*
X1550227D01*
G01X1549207Y712071D02*
Y705871D01*
G01D02*
X1546007D01*
G01D02*
Y707200D01*
G01Y712071D02*
X1549207D01*
G01X1546007Y709500D02*
Y712071D01*
G01Y716371D02*
Y722571D01*
G01X1549207D02*
Y716371D01*
G01D02*
X1546007D01*
G01X1542950Y709507D02*
Y707653D01*
G01X1556394Y706735D02*
Y709335D01*
G01D02*
X1557187D01*
G01X1552350Y755860D02*
Y712552D01*
G01D02*
X1557691D01*
G01X1546007Y722571D02*
X1549207D01*
G01X1544550Y729692D02*
Y732892D01*
G01X1550750Y729692D02*
X1544550D01*
G01X1550750Y732892D02*
Y729692D01*
G01X1545984Y729392D02*
X1549184D01*
G01X1545984Y723192D02*
Y729392D01*
G01X1549184Y723192D02*
X1545984D01*
G01X1549184Y729392D02*
Y723192D01*
G01X1542950Y731275D02*
Y728675D01*
G01Y722064D02*
Y720366D01*
G01X1544550Y732892D02*
X1550750D01*
G01X1547407Y777800D02*
Y734492D01*
G01X1557691Y755860D02*
X1552350D01*
G01X1556212Y768786D02*
X1553112D01*
Y769706D01*
X1553267Y770013D01*
X1553629Y770243D01*
X1554042Y770320D01*
X1554455Y770243D01*
X1554765Y770051D01*
X1554920Y769706D01*
Y768786D01*
G01X1553112Y771886D02*
X1556212D01*
Y773420D01*
G01X1554920Y775025D02*
X1554559Y775293D01*
X1554352Y775523D01*
X1554249Y775830D01*
X1554352Y776098D01*
X1554559Y776290D01*
X1554869Y776443D01*
X1555230Y776481D01*
X1555540Y776443D01*
X1555850Y776290D01*
X1556109Y776060D01*
X1556212Y775791D01*
X1556109Y775485D01*
X1555799Y775216D01*
X1555334Y775063D01*
X1554817Y775025D01*
X1554145Y775101D01*
X1553784Y775216D01*
X1553422Y775408D01*
X1553164Y775676D01*
X1553112Y775945D01*
X1553215Y776213D01*
X1553474Y776405D01*
G01X1553112Y778853D02*
X1553215Y778546D01*
X1553474Y778316D01*
X1553784Y778163D01*
X1554197Y778048D01*
X1554662Y778010D01*
X1555127Y778048D01*
X1555540Y778163D01*
X1555850Y778316D01*
X1556109Y778546D01*
X1556212Y778853D01*
X1556109Y779160D01*
X1555850Y779390D01*
X1555540Y779543D01*
X1555127Y779658D01*
X1554662Y779696D01*
X1554197Y779658D01*
X1553784Y779543D01*
X1553474Y779390D01*
X1553215Y779160D01*
X1553112Y778853D01*
G01X1551792Y768906D02*
X1548692D01*
Y769826D01*
X1548847Y770133D01*
X1549209Y770363D01*
X1549622Y770440D01*
X1550035Y770363D01*
X1550345Y770171D01*
X1550500Y769826D01*
Y768906D01*
G01X1548692Y772006D02*
X1551792D01*
Y773540D01*
G01X1551327Y775030D02*
X1551585Y775260D01*
X1551740Y775528D01*
X1551792Y775873D01*
X1551689Y776218D01*
X1551482Y776486D01*
X1551120Y776678D01*
X1550707Y776716D01*
X1550294Y776640D01*
X1550035Y776448D01*
X1549829Y776180D01*
X1549777Y775911D01*
X1549829Y775643D01*
X1550035Y775298D01*
X1548692Y775413D01*
Y776448D01*
G01X1551430Y778321D02*
X1551689Y778590D01*
X1551792Y778896D01*
X1551689Y779203D01*
X1551379Y779471D01*
X1550914Y779663D01*
X1550449Y779740D01*
X1549880D01*
X1549415Y779663D01*
X1549002Y779471D01*
X1548795Y779241D01*
X1548692Y778973D01*
X1548795Y778666D01*
X1549002Y778436D01*
X1549312Y778283D01*
X1549725Y778206D01*
X1550087Y778283D01*
X1550449Y778475D01*
X1550655Y778705D01*
X1550707Y778973D01*
X1550604Y779280D01*
X1550345Y779510D01*
X1549880Y779740D01*
G01X1551737Y1263914D02*
Y1260714D01*
G01X1545537Y1263914D02*
X1551737D01*
G01X1545537Y1260714D02*
Y1263914D01*
G01X1551737Y1260714D02*
X1545537D01*
G01X1557778Y1261263D02*
X1554578D01*
G01Y1267463D02*
X1557778D01*
G01X1554578Y1261263D02*
Y1267463D01*
G01X1545574Y1264671D02*
Y1267871D01*
G01X1551774Y1264671D02*
X1545574D01*
G01X1551774Y1267871D02*
Y1264671D01*
G01X1545574Y1267871D02*
X1551774D01*
G01X1551777Y1271788D02*
Y1268588D01*
G01X1545577D02*
Y1271788D01*
G01X1551777Y1268588D02*
X1545577D01*
G01Y1271788D02*
X1551777D01*
G01X1545577Y1280588D02*
Y1283788D01*
G01X1551777Y1280588D02*
X1545577D01*
G01X1551777Y1283788D02*
Y1280588D01*
G01X1559677Y1271688D02*
X1556477D01*
G01Y1277888D02*
X1559677D01*
G01X1556477Y1271688D02*
Y1277888D01*
G01X1555977Y1271688D02*
X1552777D01*
G01X1555977Y1277888D02*
Y1271688D01*
G01X1552777Y1277888D02*
X1555977D01*
G01X1552777Y1271688D02*
Y1277888D01*
G01X1551777Y1275788D02*
Y1272588D01*
G01X1545577Y1275788D02*
X1551777D01*
G01X1545577Y1272588D02*
Y1275788D01*
G01X1551777Y1272588D02*
X1545577D01*
G01Y1276588D02*
Y1279788D01*
G01X1551777Y1276588D02*
X1545577D01*
G01X1551777Y1279788D02*
Y1276588D01*
G01X1545577Y1279788D02*
X1551777D01*
G01X1545577Y1284588D02*
Y1287788D01*
G01X1551777Y1284588D02*
X1545577D01*
G01X1551777Y1287788D02*
Y1284588D01*
G01X1545577Y1287788D02*
X1551777D01*
G01X1545577Y1283788D02*
X1551777D01*
G01X1556448Y1304209D02*
X1562648D01*
G01X1556448Y1301009D02*
Y1304209D01*
G01X1562648Y1301009D02*
X1556448D01*
G01X1554323Y1441393D02*
X1546823Y1443726D01*
X1554323Y1446059D01*
G01X1551698Y1445219D02*
Y1442233D01*
G01X1554323Y1451039D02*
X1552698Y1451226D01*
X1551323Y1451506D01*
X1550073Y1451879D01*
X1548698Y1452346D01*
X1546823Y1453093D01*
Y1449359D01*
G01X1558280Y1437930D02*
X1543280D01*
G01D02*
Y1463430D01*
G01X1547246Y1550620D02*
X1553246D01*
Y1547620D01*
X1547246D01*
Y1550620D01*
G01X1544044Y1551320D02*
Y1557520D01*
X1547244D01*
Y1551320D01*
X1544044D01*
G01X1549946D02*
Y1557520D01*
X1553146D01*
Y1551320D01*
X1549946D01*
G01X1553346Y1543620D02*
X1547146D01*
Y1546820D01*
X1553346D01*
Y1543620D01*
G01X1550196D02*
X1543996D01*
Y1546820D01*
X1550196D01*
Y1543620D01*
G01Y1547520D02*
X1543996D01*
Y1550720D01*
X1550196D01*
Y1547520D01*
G01X1551184Y1569503D02*
Y1572911D01*
G01X1568900Y1569503D02*
X1551184D01*
G01X1546282Y1584035D02*
X1549382D01*
Y1585569D01*
G01X1546799Y1587174D02*
X1546489Y1587404D01*
X1546334Y1587672D01*
X1546282Y1587979D01*
X1546385Y1588362D01*
X1546644Y1588630D01*
X1546954Y1588707D01*
X1547264Y1588669D01*
X1547522Y1588515D01*
X1548039Y1587749D01*
X1548400Y1587404D01*
X1548917Y1587174D01*
X1549382Y1587097D01*
Y1588707D01*
G01Y1591002D02*
X1546282D01*
X1546902Y1590542D01*
G01X1549382D02*
Y1591462D01*
G01X1551184Y1587219D02*
X1568900D01*
G01X1551184Y1583811D02*
Y1587219D01*
G01X1557074Y1620742D02*
X1563074D01*
Y1608742D01*
X1557074D01*
Y1620742D01*
G01X1559247Y1605518D02*
X1557007D01*
G01X1558220Y1603893D02*
Y1607143D01*
G01X1556372Y1602363D02*
X1555172D01*
G01X1556372D02*
X1556366Y1619346D01*
G01X1555772Y1602363D02*
X1555776Y1619338D01*
G01X1555172Y1602363D02*
X1555175Y1619303D01*
G01X1556322Y1619296D02*
X1554813Y1619292D01*
G01X1553150Y1646023D02*
Y1736118D01*
G01X1555800Y1646023D02*
X1553150D01*
G01X1551800Y1655123D02*
X1551128Y1655200D01*
X1550560Y1655315D01*
X1550043Y1655468D01*
X1549475Y1655660D01*
X1548700Y1655967D01*
Y1654433D01*
G01X1555800Y1646023D02*
X1549300D01*
G01X1549500Y1657834D02*
X1555200D01*
G01X1569500Y51142D02*
X1567000D01*
G01X1562000D02*
X1560000D01*
G01X1563769Y207050D02*
Y206750D01*
G01Y212050D02*
Y211450D01*
G01Y217050D02*
Y216450D01*
G01Y222050D02*
Y221450D01*
G01Y227050D02*
Y226450D01*
G01Y232050D02*
Y231450D01*
G01Y237050D02*
Y236450D01*
G01Y242050D02*
Y241450D01*
G01Y247050D02*
Y246450D01*
G01Y252050D02*
Y251450D01*
G01Y256750D02*
Y256450D01*
G01X1558364Y286175D02*
Y282975D01*
G01X1564917Y295716D02*
Y298916D01*
G01X1571117Y295716D02*
X1564917D01*
G01X1571117Y298916D02*
Y295716D01*
G01X1564917Y298916D02*
X1571117D01*
G01X1562123Y294510D02*
X1560170D01*
G01X1562123Y296463D02*
Y294510D01*
G01X1564917Y300216D02*
Y303416D01*
G01X1571117Y300216D02*
X1564917D01*
G01X1571117Y303416D02*
Y300216D01*
G01X1564917Y303416D02*
X1571117D01*
G01X1562123Y306322D02*
Y304369D01*
G01X1560170Y306322D02*
X1562123D01*
G01X1605020Y331505D02*
X1563633D01*
G01D02*
Y394600D01*
G01X1574743Y529620D02*
X1568543D01*
G01D02*
Y532820D01*
G01D02*
X1574743D01*
G01X1562945Y579298D02*
Y573098D01*
G01D02*
X1559745D01*
G01D02*
Y579298D01*
G01D02*
X1562945D01*
G01X1570175Y581388D02*
Y569388D01*
G01D02*
X1564175D01*
G01D02*
Y581388D01*
G01D02*
X1570175D01*
G01X1557606Y676110D02*
Y682310D01*
G01D02*
X1560806D01*
G01D02*
Y676110D01*
G01D02*
X1557606D01*
G01X1568273Y678606D02*
X1574473D01*
G01Y675406D02*
X1568273D01*
G01D02*
Y678606D01*
G01X1564848Y682310D02*
Y676110D01*
G01D02*
X1561648D01*
G01D02*
Y682310D01*
G01D02*
X1564848D01*
G01X1568602Y901200D02*
Y860720D01*
G01X1558535Y886300D02*
Y870788D01*
G01Y911200D02*
Y896700D01*
G01X1568602Y925700D02*
Y911700D01*
G01X1558535Y931300D02*
Y920100D01*
G01X1568602Y951300D02*
Y935300D01*
G01X1558535Y951100D02*
Y939400D01*
G01X1568602Y969500D02*
Y959000D01*
G01X1558535Y969200D02*
Y959000D01*
G01X1568602Y1008300D02*
Y976800D01*
G01X1558535Y1008300D02*
Y976800D01*
G01X1568602Y1064100D02*
Y1013400D01*
G01X1558535Y1064000D02*
Y1013400D01*
G01X1568602Y1083700D02*
Y1071300D01*
G01X1558535Y1083900D02*
Y1071500D01*
G01X1568602Y1101800D02*
Y1091300D01*
G01X1558535Y1101400D02*
Y1091200D01*
G01X1568602Y1124300D02*
Y1111400D01*
G01X1558535Y1121900D02*
Y1111000D01*
G01Y1141100D02*
Y1130000D01*
G01X1568602Y1141300D02*
Y1135000D01*
G01Y1175982D02*
Y1150400D01*
G01X1558535Y1167638D02*
Y1150400D01*
G01X1557778Y1267463D02*
Y1261263D01*
G01X1561757D02*
X1558557D01*
G01X1561757Y1267463D02*
Y1261263D01*
G01X1558557Y1267463D02*
X1561757D01*
G01X1558557Y1261263D02*
Y1267463D01*
G01X1559677Y1277888D02*
Y1271688D01*
G01X1569192Y1272978D02*
X1575392D01*
G01X1569192Y1269778D02*
Y1272978D01*
G01X1575392Y1269778D02*
X1569192D01*
G01X1560388Y1271845D02*
Y1275045D01*
G01X1566588Y1271845D02*
X1560388D01*
G01X1566588Y1275045D02*
Y1271845D01*
G01X1560388Y1275045D02*
X1566588D01*
G01X1562648Y1304209D02*
Y1301009D01*
G01X1560525Y1427643D02*
Y1435143D01*
X1562391D01*
X1563138Y1434768D01*
X1563698Y1434268D01*
X1564165Y1433518D01*
X1564538Y1432643D01*
X1564631Y1431393D01*
X1564538Y1430143D01*
X1564165Y1429268D01*
X1563698Y1428518D01*
X1563138Y1428018D01*
X1562391Y1427643D01*
X1560525D01*
G01X1568958Y1435143D02*
X1571198D01*
G01X1570078D02*
Y1427643D01*
G01X1568958D02*
X1571198D01*
G01X1575151D02*
Y1435143D01*
X1577578Y1428893D01*
X1580005Y1435143D01*
Y1427643D01*
G01X1582651D02*
Y1435143D01*
X1585078Y1428893D01*
X1587505Y1435143D01*
Y1427643D01*
G01X1569323Y1441393D02*
X1561823Y1443726D01*
X1569323Y1446059D01*
G01X1566698Y1445219D02*
Y1442233D01*
G01X1569323Y1451226D02*
X1569198Y1451879D01*
X1568823Y1452626D01*
X1568198Y1453093D01*
X1567323Y1453279D01*
X1566448Y1453093D01*
X1565698Y1452533D01*
X1565323Y1451693D01*
Y1450759D01*
X1565073Y1450199D01*
X1564448Y1449733D01*
X1563573Y1449546D01*
X1562698Y1449826D01*
X1562073Y1450479D01*
X1561823Y1451226D01*
X1562073Y1451973D01*
X1562698Y1452626D01*
X1563573Y1452906D01*
X1564448Y1452719D01*
X1565073Y1452253D01*
X1565323Y1451693D01*
Y1450759D01*
X1565698Y1449919D01*
X1566448Y1449359D01*
X1567323Y1449173D01*
X1568198Y1449359D01*
X1568823Y1449826D01*
X1569198Y1450573D01*
X1569323Y1451226D01*
G01X1573280Y1437930D02*
X1558280D01*
G01D02*
Y1463430D01*
G01X1568900Y1572911D02*
Y1569503D01*
G01Y1587219D02*
Y1583811D01*
G01X1563978Y1620864D02*
X1569978D01*
Y1608864D01*
X1563978D01*
Y1620864D01*
G01X1568800Y1655500D02*
X1565700D01*
X1566320Y1655040D01*
G01X1568800D02*
Y1655960D01*
G01X1567800Y1646023D02*
X1561300D01*
G01X1563400Y1655200D02*
X1563348Y1655468D01*
X1563193Y1655775D01*
X1562935Y1655967D01*
X1562573Y1656043D01*
X1562212Y1655967D01*
X1561902Y1655737D01*
X1561747Y1655392D01*
Y1655008D01*
X1561643Y1654778D01*
X1561385Y1654587D01*
X1561023Y1654510D01*
X1560662Y1654625D01*
X1560403Y1654893D01*
X1560300Y1655200D01*
X1560403Y1655507D01*
X1560662Y1655775D01*
X1561023Y1655890D01*
X1561385Y1655813D01*
X1561643Y1655622D01*
X1561747Y1655392D01*
Y1655008D01*
X1561902Y1654663D01*
X1562212Y1654433D01*
X1562573Y1654357D01*
X1562935Y1654433D01*
X1563193Y1654625D01*
X1563348Y1654932D01*
X1563400Y1655200D01*
G01X1567800Y1646023D02*
X1561300D01*
G01X1564961Y1667000D02*
Y1657834D01*
G01D02*
X1567500D01*
G01X1564566D02*
Y1667000D01*
G01X1561600Y1657834D02*
X1564566D01*
G01X1564961Y1740118D02*
X1631496D01*
G01X1571982Y1736412D02*
X1576982D01*
G01X1571982Y1739812D02*
Y1736412D01*
G01X1573982Y1737812D02*
X1571982Y1739812D01*
G01X1569982Y1737812D02*
X1573982D01*
G01X1571982Y1739812D02*
X1569982Y1737812D01*
G01X1585000Y51142D02*
X1582500D01*
G01X1577000D02*
X1575000D01*
G01X1592403Y223650D02*
X1586203D01*
G01D02*
Y226850D01*
G01X1592403Y212650D02*
X1586203D01*
G01D02*
Y215850D01*
G01D02*
X1592403D01*
G01Y227650D02*
X1586203D01*
G01D02*
Y230850D01*
G01D02*
X1592403D01*
G01Y232650D02*
X1586203D01*
G01D02*
Y235850D01*
G01D02*
X1592403D01*
G01Y237650D02*
X1586203D01*
G01D02*
Y240850D01*
G01Y226850D02*
X1592403D01*
G01Y242650D02*
X1586203D01*
G01D02*
Y245850D01*
G01D02*
X1592403D01*
G01X1586203Y240850D02*
X1592403D01*
G01X1587200Y302071D02*
Y308271D01*
G01D02*
X1590400D01*
G01Y302071D02*
X1587200D01*
G01X1574743Y532820D02*
Y529620D01*
G01X1584767Y529454D02*
X1581420D01*
G01Y538116D02*
X1591914D01*
G01X1581420Y529454D02*
Y538116D01*
G01X1586667Y531654D02*
X1584767Y529454D01*
G01X1588567D02*
X1586667Y531654D01*
G01X1584986Y540290D02*
X1584679Y540342D01*
X1584411Y540548D01*
X1584181Y540858D01*
X1584028Y541220D01*
X1583951Y541633D01*
Y542047D01*
X1584028Y542460D01*
X1584181Y542822D01*
X1584411Y543132D01*
X1584679Y543338D01*
X1584986Y543390D01*
X1585293Y543338D01*
X1585561Y543132D01*
X1585791Y542822D01*
X1585944Y542460D01*
X1586021Y542047D01*
Y541633D01*
X1585944Y541220D01*
X1585791Y540858D01*
X1585561Y540548D01*
X1585293Y540342D01*
X1584986Y540290D01*
G01X1585293Y541117D02*
X1585753Y540290D01*
G01X1587243Y540755D02*
X1587473Y540497D01*
X1587741Y540342D01*
X1588086Y540290D01*
X1588431Y540393D01*
X1588699Y540600D01*
X1588891Y540962D01*
X1588929Y541375D01*
X1588853Y541788D01*
X1588661Y542047D01*
X1588393Y542253D01*
X1588124Y542305D01*
X1587856Y542253D01*
X1587511Y542047D01*
X1587626Y543390D01*
X1588661D01*
G01X1591186D02*
X1590879Y543287D01*
X1590649Y543028D01*
X1590496Y542718D01*
X1590381Y542305D01*
X1590343Y541840D01*
X1590381Y541375D01*
X1590496Y540962D01*
X1590649Y540652D01*
X1590879Y540393D01*
X1591186Y540290D01*
X1591493Y540393D01*
X1591723Y540652D01*
X1591876Y540962D01*
X1591991Y541375D01*
X1592029Y541840D01*
X1591991Y542305D01*
X1591876Y542718D01*
X1591723Y543028D01*
X1591493Y543287D01*
X1591186Y543390D01*
G01X1585679Y566208D02*
Y560008D01*
G01X1582479D02*
Y566208D01*
G01D02*
X1585679D01*
G01Y560008D02*
X1582479D01*
G01X1593399Y556488D02*
X1587399D01*
G01D02*
Y568488D01*
G01D02*
X1593399D01*
G01X1597743Y571089D02*
X1579239D01*
G01D02*
Y572022D01*
G01X1580891Y593790D02*
X1580584Y593842D01*
X1580316Y594048D01*
X1580086Y594358D01*
X1579933Y594720D01*
X1579856Y595133D01*
Y595547D01*
X1579933Y595960D01*
X1580086Y596322D01*
X1580316Y596632D01*
X1580584Y596838D01*
X1580891Y596890D01*
X1581198Y596838D01*
X1581466Y596632D01*
X1581696Y596322D01*
X1581849Y595960D01*
X1581926Y595547D01*
Y595133D01*
X1581849Y594720D01*
X1581696Y594358D01*
X1581466Y594048D01*
X1581198Y593842D01*
X1580891Y593790D01*
G01X1581198Y594617D02*
X1581658Y593790D01*
G01X1583148Y594255D02*
X1583378Y593997D01*
X1583646Y593842D01*
X1583991Y593790D01*
X1584336Y593893D01*
X1584604Y594100D01*
X1584796Y594462D01*
X1584834Y594875D01*
X1584758Y595288D01*
X1584566Y595547D01*
X1584298Y595753D01*
X1584029Y595805D01*
X1583761Y595753D01*
X1583416Y595547D01*
X1583531Y596890D01*
X1584566D01*
G01X1587014Y593790D02*
X1587091Y594462D01*
X1587206Y595030D01*
X1587359Y595547D01*
X1587551Y596115D01*
X1587858Y596890D01*
X1586324D01*
G01X1579239Y591122D02*
Y591955D01*
G01D02*
X1597743D01*
G01X1577202Y643449D02*
Y646549D01*
X1578122D01*
X1578429Y646394D01*
X1578659Y646032D01*
X1578736Y645619D01*
X1578659Y645206D01*
X1578467Y644896D01*
X1578122Y644741D01*
X1577202D01*
G01X1580226Y646549D02*
Y644327D01*
X1580379Y643862D01*
X1580686Y643552D01*
X1581069Y643449D01*
X1581452Y643552D01*
X1581759Y643862D01*
X1581912Y644327D01*
Y646549D01*
G01X1583326Y643914D02*
X1583556Y643656D01*
X1583824Y643501D01*
X1584169Y643449D01*
X1584514Y643552D01*
X1584782Y643759D01*
X1584974Y644121D01*
X1585012Y644534D01*
X1584936Y644947D01*
X1584744Y645206D01*
X1584476Y645412D01*
X1584207Y645464D01*
X1583939Y645412D01*
X1583594Y645206D01*
X1583709Y646549D01*
X1584744D01*
G01X1587269D02*
X1586962Y646446D01*
X1586732Y646187D01*
X1586579Y645877D01*
X1586464Y645464D01*
X1586426Y644999D01*
X1586464Y644534D01*
X1586579Y644121D01*
X1586732Y643811D01*
X1586962Y643552D01*
X1587269Y643449D01*
X1587576Y643552D01*
X1587806Y643811D01*
X1587959Y644121D01*
X1588074Y644534D01*
X1588112Y644999D01*
X1588074Y645464D01*
X1587959Y645877D01*
X1587806Y646187D01*
X1587576Y646446D01*
X1587269Y646549D01*
G01X1582997Y660329D02*
Y666529D01*
G01D02*
X1586197D01*
G01D02*
Y660329D01*
G01D02*
X1582997D01*
G01X1578997D02*
Y666529D01*
G01D02*
X1582197D01*
G01D02*
Y660329D01*
G01D02*
X1578997D01*
G01X1578443Y681500D02*
Y675300D01*
G01D02*
X1575243D01*
G01D02*
Y681500D01*
G01D02*
X1578443D01*
G01X1582337Y690131D02*
Y683931D01*
G01D02*
X1579137D01*
G01D02*
Y685000D01*
G01X1574473Y678606D02*
Y675406D01*
G01X1576080Y687567D02*
Y685713D01*
G01D02*
X1575072D01*
G01X1585480Y722091D02*
Y678783D01*
G01D02*
X1590821D01*
G01X1579137Y690131D02*
X1582337D01*
G01X1579137Y688300D02*
Y690131D01*
G01Y694431D02*
Y700631D01*
G01D02*
X1582337D01*
G01D02*
Y694431D01*
G01D02*
X1579137D01*
G01X1582314Y707452D02*
Y701252D01*
G01D02*
X1579114D01*
G01D02*
Y707452D01*
G01X1576080Y700124D02*
Y698426D01*
G01X1577680Y710952D02*
X1583880D01*
G01D02*
Y707752D01*
G01D02*
X1577680D01*
G01D02*
Y710952D01*
G01X1579114Y707452D02*
X1582314D01*
G01X1575287Y709335D02*
X1576080D01*
G01D02*
Y706735D01*
G01X1581878Y755860D02*
Y712552D01*
G01D02*
X1576537D01*
G01X1590821Y722091D02*
X1585480D01*
G01X1586632Y745605D02*
X1583532D01*
Y746525D01*
X1583687Y746832D01*
X1584049Y747062D01*
X1584462Y747139D01*
X1584875Y747062D01*
X1585185Y746870D01*
X1585340Y746525D01*
Y745605D01*
G01X1583532Y748705D02*
X1586632D01*
Y750239D01*
G01X1585340Y751844D02*
X1584979Y752112D01*
X1584772Y752342D01*
X1584669Y752649D01*
X1584772Y752917D01*
X1584979Y753109D01*
X1585289Y753262D01*
X1585650Y753300D01*
X1585960Y753262D01*
X1586270Y753109D01*
X1586529Y752879D01*
X1586632Y752610D01*
X1586529Y752304D01*
X1586219Y752035D01*
X1585754Y751882D01*
X1585237Y751844D01*
X1584565Y751920D01*
X1584204Y752035D01*
X1583842Y752227D01*
X1583584Y752495D01*
X1583532Y752764D01*
X1583635Y753032D01*
X1583894Y753224D01*
G01X1586012Y754829D02*
X1586374Y755059D01*
X1586580Y755365D01*
X1586632Y755710D01*
X1586580Y756017D01*
X1586322Y756324D01*
X1586012Y756515D01*
X1585702Y756554D01*
X1585340Y756477D01*
X1585082Y756209D01*
X1584979Y755940D01*
Y755595D01*
G01Y755940D02*
X1584824Y756170D01*
X1584565Y756362D01*
X1584255Y756439D01*
X1583945Y756362D01*
X1583687Y756170D01*
X1583532Y755825D01*
X1583584Y755480D01*
X1583790Y755135D01*
G01X1576537Y755860D02*
X1581878D01*
G01X1584777Y1260688D02*
X1581577D01*
G01X1584777Y1266888D02*
Y1260688D01*
G01X1581577Y1266888D02*
X1584777D01*
G01X1581577Y1260688D02*
Y1266888D01*
G01X1577577D02*
X1580777D01*
G01X1577577Y1260688D02*
Y1266888D01*
G01X1580777Y1260688D02*
X1577577D01*
G01X1580777Y1266888D02*
Y1260688D01*
G01X1588777D02*
X1585577D01*
G01Y1266888D02*
X1588777D01*
G01X1585577Y1260688D02*
Y1266888D01*
G01X1586777Y1280588D02*
Y1277388D01*
G01X1580577Y1280588D02*
X1586777D01*
G01X1580577Y1277388D02*
Y1280588D01*
G01X1586777Y1277388D02*
X1580577D01*
G01X1587077Y1280588D02*
X1593277D01*
G01X1587077Y1277388D02*
Y1280588D01*
G01X1593277Y1277388D02*
X1587077D01*
G01X1575392Y1272978D02*
Y1269778D01*
G01X1579805Y1277054D02*
Y1273854D01*
G01X1573605Y1277054D02*
X1579805D01*
G01X1573605Y1273854D02*
Y1277054D01*
G01X1579805Y1273854D02*
X1573605D01*
G01X1586777Y1294588D02*
Y1291388D01*
G01X1580577Y1294588D02*
X1586777D01*
G01X1580577Y1291388D02*
Y1294588D01*
G01X1586777Y1291388D02*
X1580577D01*
G01X1586372Y1299878D02*
Y1296678D01*
G01X1580172D02*
Y1299878D01*
G01X1586372Y1296678D02*
X1580172D01*
G01X1579507Y1290558D02*
Y1287358D01*
G01X1573307Y1290558D02*
X1579507D01*
G01X1573307Y1287358D02*
Y1290558D01*
G01X1579507Y1287358D02*
X1573307D01*
G01X1577280Y1298379D02*
X1574080D01*
G01X1577280Y1304579D02*
Y1298379D01*
G01X1574080D02*
Y1304579D01*
G01X1580172Y1299878D02*
X1586372D01*
G01X1580172Y1300678D02*
Y1303878D01*
G01X1586372Y1300678D02*
X1580172D01*
G01X1586372Y1303878D02*
Y1300678D01*
G01X1580172Y1303878D02*
X1586372D01*
G01X1574080Y1304579D02*
X1577280D01*
G01X1584323Y1441393D02*
X1576823Y1443726D01*
X1584323Y1446059D01*
G01X1581698Y1445219D02*
Y1442233D01*
G01X1583448Y1449639D02*
X1584073Y1450293D01*
X1584323Y1451039D01*
X1584073Y1451786D01*
X1583323Y1452439D01*
X1582198Y1452906D01*
X1581073Y1453093D01*
X1579698D01*
X1578573Y1452906D01*
X1577573Y1452439D01*
X1577073Y1451879D01*
X1576823Y1451226D01*
X1577073Y1450479D01*
X1577573Y1449919D01*
X1578323Y1449546D01*
X1579323Y1449359D01*
X1580198Y1449546D01*
X1581073Y1450013D01*
X1581573Y1450573D01*
X1581698Y1451226D01*
X1581448Y1451973D01*
X1580823Y1452533D01*
X1579698Y1453093D01*
G01X1588280Y1437930D02*
X1573280D01*
G01D02*
Y1463430D01*
G01X1577542Y1540451D02*
Y1556900D01*
G01X1583900Y1540451D02*
X1577542D01*
G01Y1561100D02*
Y1575491D01*
G01D02*
X1584400D01*
G01X1587580Y1654857D02*
X1587942Y1655087D01*
X1588148Y1655393D01*
X1588200Y1655738D01*
X1588148Y1656045D01*
X1587890Y1656352D01*
X1587580Y1656543D01*
X1587270Y1656582D01*
X1586908Y1656505D01*
X1586650Y1656237D01*
X1586547Y1655968D01*
Y1655623D01*
G01Y1655968D02*
X1586392Y1656198D01*
X1586133Y1656390D01*
X1585823Y1656467D01*
X1585513Y1656390D01*
X1585255Y1656198D01*
X1585100Y1655853D01*
X1585152Y1655508D01*
X1585358Y1655163D01*
G01X1577006Y1655284D02*
X1576696Y1655514D01*
X1576541Y1655782D01*
X1576489Y1656089D01*
X1576592Y1656472D01*
X1576851Y1656740D01*
X1577161Y1656817D01*
X1577471Y1656779D01*
X1577729Y1656625D01*
X1578246Y1655859D01*
X1578607Y1655514D01*
X1579124Y1655284D01*
X1579589Y1655207D01*
Y1656817D01*
G01X1579700Y1646023D02*
X1573200D01*
G01X1591900D02*
X1585100D01*
G01X1576377D02*
X1573200D01*
G01X1576377Y1667630D02*
Y1646023D01*
G01X1573600Y1657834D02*
X1579300D01*
G01X1585600D02*
X1591300D01*
G01X1580065Y1736629D02*
X1578999D01*
Y1739129D01*
X1580065D01*
G01X1579639Y1737921D02*
X1578999D01*
G01X1581145Y1736629D02*
Y1739129D01*
X1581679D01*
X1581892Y1739004D01*
X1582052Y1738837D01*
X1582185Y1738587D01*
X1582292Y1738296D01*
X1582319Y1737879D01*
X1582292Y1737462D01*
X1582185Y1737171D01*
X1582052Y1736921D01*
X1581892Y1736754D01*
X1581679Y1736629D01*
X1581145D01*
G01X1584092Y1737879D02*
X1584625D01*
Y1737129D01*
X1584465Y1736879D01*
X1584279Y1736712D01*
X1584012Y1736629D01*
X1583745Y1736712D01*
X1583559Y1736879D01*
X1583399Y1737129D01*
X1583292Y1737421D01*
X1583239Y1737754D01*
Y1738046D01*
X1583292Y1738296D01*
X1583399Y1738587D01*
X1583559Y1738837D01*
X1583719Y1739004D01*
X1583932Y1739129D01*
X1584119D01*
X1584332Y1739046D01*
X1584492Y1738879D01*
G01X1586665Y1736629D02*
X1585599D01*
Y1739129D01*
X1586665D01*
G01X1586239Y1737921D02*
X1585599D01*
G01X1590532Y1736629D02*
X1590319Y1736671D01*
X1590132Y1736837D01*
X1589972Y1737087D01*
X1589865Y1737379D01*
X1589812Y1737712D01*
Y1738046D01*
X1589865Y1738379D01*
X1589972Y1738671D01*
X1590132Y1738921D01*
X1590319Y1739087D01*
X1590532Y1739129D01*
X1590745Y1739087D01*
X1590932Y1738921D01*
X1591092Y1738671D01*
X1591199Y1738379D01*
X1591252Y1738046D01*
Y1737712D01*
X1591199Y1737379D01*
X1591092Y1737087D01*
X1590932Y1736837D01*
X1590745Y1736671D01*
X1590532Y1736629D01*
G01X1592225D02*
Y1739129D01*
X1593239D01*
G01X1592865Y1737921D02*
X1592225D01*
G01X1596545Y1736629D02*
Y1739129D01*
X1597079D01*
X1597292Y1739004D01*
X1597452Y1738837D01*
X1597585Y1738587D01*
X1597692Y1738296D01*
X1597719Y1737879D01*
X1597692Y1737462D01*
X1597585Y1737171D01*
X1597452Y1736921D01*
X1597292Y1736754D01*
X1597079Y1736629D01*
X1596545D01*
G01X1598665D02*
X1599332Y1739129D01*
X1599999Y1736629D01*
G01X1599759Y1737504D02*
X1598905D01*
G01X1600945Y1739129D02*
Y1737337D01*
X1601052Y1736962D01*
X1601265Y1736712D01*
X1601532Y1736629D01*
X1601799Y1736712D01*
X1602012Y1736962D01*
X1602119Y1737337D01*
Y1739129D01*
G01X1603892Y1737879D02*
X1604425D01*
Y1737129D01*
X1604265Y1736879D01*
X1604079Y1736712D01*
X1603812Y1736629D01*
X1603545Y1736712D01*
X1603359Y1736879D01*
X1603199Y1737129D01*
X1603092Y1737421D01*
X1603039Y1737754D01*
Y1738046D01*
X1603092Y1738296D01*
X1603199Y1738587D01*
X1603359Y1738837D01*
X1603519Y1739004D01*
X1603732Y1739129D01*
X1603919D01*
X1604132Y1739046D01*
X1604292Y1738879D01*
G01X1605372Y1736629D02*
Y1739129D01*
G01X1606492D02*
Y1736629D01*
G01Y1737879D02*
X1605372D01*
G01X1608132Y1739129D02*
Y1736629D01*
G01X1607519Y1739129D02*
X1608745D01*
G01X1610865Y1736629D02*
X1609799D01*
Y1739129D01*
X1610865D01*
G01X1610439Y1737921D02*
X1609799D01*
G01X1611999Y1736629D02*
Y1739129D01*
X1612665D01*
X1612879Y1739004D01*
X1613012Y1738837D01*
X1613065Y1738504D01*
X1613012Y1738171D01*
X1612852Y1737962D01*
X1612665Y1737837D01*
X1611999D01*
G01X1612665D02*
X1613065Y1736629D01*
G01X1617519Y1738921D02*
X1617359Y1739046D01*
X1617172Y1739129D01*
X1616959D01*
X1616719Y1739004D01*
X1616532Y1738796D01*
X1616399Y1738546D01*
X1616292Y1738129D01*
X1616265Y1737754D01*
X1616319Y1737379D01*
X1616399Y1737129D01*
X1616559Y1736879D01*
X1616745Y1736712D01*
X1616932Y1736629D01*
X1617119D01*
X1617305Y1736712D01*
X1617465Y1736837D01*
X1617599Y1737004D01*
G01X1618465Y1736629D02*
X1619132Y1739129D01*
X1619799Y1736629D01*
G01X1619559Y1737504D02*
X1618705D01*
G01X1620799Y1736629D02*
Y1739129D01*
X1621465D01*
X1621679Y1739004D01*
X1621812Y1738837D01*
X1621865Y1738504D01*
X1621812Y1738171D01*
X1621652Y1737962D01*
X1621465Y1737837D01*
X1620799D01*
G01X1621465D02*
X1621865Y1736629D01*
G01X1622945D02*
Y1739129D01*
X1623479D01*
X1623692Y1739004D01*
X1623852Y1738837D01*
X1623985Y1738587D01*
X1624092Y1738296D01*
X1624119Y1737879D01*
X1624092Y1737462D01*
X1623985Y1737171D01*
X1623852Y1736921D01*
X1623692Y1736754D01*
X1623479Y1736629D01*
X1622945D01*
G01X1576982Y1736412D02*
X1577882Y1737312D01*
G01X1599500Y51142D02*
X1597500D01*
G01X1592000D02*
X1589500D01*
G01X1600553Y226850D02*
Y223650D01*
G01D02*
X1594353D01*
G01D02*
Y226850D01*
G01X1592403D02*
Y223650D01*
G01Y215850D02*
Y212650D01*
G01X1594353Y226850D02*
X1600553D01*
G01X1592403Y230850D02*
Y227650D01*
G01Y235850D02*
Y232650D01*
G01Y240850D02*
Y237650D01*
G01Y245850D02*
Y242650D01*
G01X1597338Y293360D02*
Y305564D01*
G01X1603000Y293360D02*
X1597338D01*
G01X1591207Y312529D02*
Y310307D01*
X1591360Y309842D01*
X1591667Y309532D01*
X1592050Y309429D01*
X1592433Y309532D01*
X1592740Y309842D01*
X1592893Y310307D01*
Y312529D01*
G01X1594422Y312012D02*
X1594652Y312322D01*
X1594920Y312477D01*
X1595227Y312529D01*
X1595610Y312426D01*
X1595878Y312167D01*
X1595955Y311857D01*
X1595917Y311547D01*
X1595763Y311289D01*
X1594997Y310772D01*
X1594652Y310411D01*
X1594422Y309894D01*
X1594345Y309429D01*
X1595955D01*
G01X1597407Y310049D02*
X1597637Y309687D01*
X1597943Y309481D01*
X1598288Y309429D01*
X1598595Y309481D01*
X1598902Y309739D01*
X1599093Y310049D01*
X1599132Y310359D01*
X1599055Y310721D01*
X1598787Y310979D01*
X1598518Y311082D01*
X1598173D01*
G01X1598518D02*
X1598748Y311237D01*
X1598940Y311496D01*
X1599017Y311806D01*
X1598940Y312116D01*
X1598748Y312374D01*
X1598403Y312529D01*
X1598058Y312477D01*
X1597713Y312271D01*
G01X1600622Y310721D02*
X1600890Y311082D01*
X1601120Y311289D01*
X1601427Y311392D01*
X1601695Y311289D01*
X1601887Y311082D01*
X1602040Y310772D01*
X1602078Y310411D01*
X1602040Y310101D01*
X1601887Y309791D01*
X1601657Y309532D01*
X1601388Y309429D01*
X1601082Y309532D01*
X1600813Y309842D01*
X1600660Y310307D01*
X1600622Y310824D01*
X1600698Y311496D01*
X1600813Y311857D01*
X1601005Y312219D01*
X1601273Y312477D01*
X1601542Y312529D01*
X1601810Y312426D01*
X1602002Y312167D01*
G01X1597338Y305564D02*
X1599998D01*
G01D02*
X1603000Y302562D01*
G01X1590400Y308271D02*
Y302071D01*
G01X1597199Y537944D02*
X1603399D01*
G01X1597199Y534744D02*
Y537944D01*
G01X1603399Y534744D02*
X1597199D01*
G01X1603399Y529626D02*
X1597199D01*
G01Y532826D02*
X1603399D01*
G01X1597199Y529626D02*
Y532826D01*
G01X1591914Y529454D02*
X1588567D01*
G01X1591914Y538116D02*
Y529454D01*
G01X1600499Y556488D02*
X1594499D01*
G01D02*
Y568488D01*
G01X1600499D02*
Y556488D01*
G01X1593399Y568488D02*
Y556488D01*
G01X1594499Y568488D02*
X1600499D01*
G01X1597743Y571722D02*
Y571089D01*
G01Y591955D02*
Y591322D01*
G01X1605000Y598383D02*
X1601900D01*
Y599303D01*
X1602055Y599610D01*
X1602417Y599840D01*
X1602830Y599917D01*
X1603243Y599840D01*
X1603553Y599648D01*
X1603708Y599303D01*
Y598383D01*
G01X1601900Y601483D02*
X1605000D01*
Y603017D01*
G01Y605350D02*
X1604948Y605618D01*
X1604793Y605925D01*
X1604535Y606117D01*
X1604173Y606193D01*
X1603812Y606117D01*
X1603502Y605887D01*
X1603347Y605542D01*
Y605158D01*
X1603243Y604928D01*
X1602985Y604737D01*
X1602623Y604660D01*
X1602262Y604775D01*
X1602003Y605043D01*
X1601900Y605350D01*
X1602003Y605657D01*
X1602262Y605925D01*
X1602623Y606040D01*
X1602985Y605963D01*
X1603243Y605772D01*
X1603347Y605542D01*
Y605158D01*
X1603502Y604813D01*
X1603812Y604583D01*
X1604173Y604507D01*
X1604535Y604583D01*
X1604793Y604775D01*
X1604948Y605082D01*
X1605000Y605350D01*
G01X1601900Y608450D02*
X1602003Y608143D01*
X1602262Y607913D01*
X1602572Y607760D01*
X1602985Y607645D01*
X1603450Y607607D01*
X1603915Y607645D01*
X1604328Y607760D01*
X1604638Y607913D01*
X1604897Y608143D01*
X1605000Y608450D01*
X1604897Y608757D01*
X1604638Y608987D01*
X1604328Y609140D01*
X1603915Y609255D01*
X1603450Y609293D01*
X1602985Y609255D01*
X1602572Y609140D01*
X1602262Y608987D01*
X1602003Y608757D01*
X1601900Y608450D01*
G01X1603708Y610822D02*
X1603347Y611090D01*
X1603140Y611320D01*
X1603037Y611627D01*
X1603140Y611895D01*
X1603347Y612087D01*
X1603657Y612240D01*
X1604018Y612278D01*
X1604328Y612240D01*
X1604638Y612087D01*
X1604897Y611857D01*
X1605000Y611588D01*
X1604897Y611282D01*
X1604587Y611013D01*
X1604122Y610860D01*
X1603605Y610822D01*
X1602933Y610898D01*
X1602572Y611013D01*
X1602210Y611205D01*
X1601952Y611473D01*
X1601900Y611742D01*
X1602003Y612010D01*
X1602262Y612202D01*
G01X1604535Y613807D02*
X1604793Y614037D01*
X1604948Y614305D01*
X1605000Y614650D01*
X1604897Y614995D01*
X1604690Y615263D01*
X1604328Y615455D01*
X1603915Y615493D01*
X1603502Y615417D01*
X1603243Y615225D01*
X1603037Y614957D01*
X1602985Y614688D01*
X1603037Y614420D01*
X1603243Y614075D01*
X1601900Y614190D01*
Y615225D01*
G01X1590376Y642341D02*
Y648541D01*
G01X1593576D02*
Y642341D01*
G01D02*
X1590376D01*
G01X1607243Y641637D02*
X1601043D01*
G01D02*
Y644837D01*
G01X1597618Y648541D02*
Y642341D01*
G01D02*
X1594418D01*
G01D02*
Y648541D01*
G01X1590376D02*
X1593576D01*
G01X1601043Y644837D02*
X1607243D01*
G01X1594418Y648541D02*
X1597618D01*
G01X1589897Y651944D02*
X1589164D01*
G01D02*
Y654135D01*
G01Y672966D02*
Y675566D01*
G01D02*
X1589957D01*
G01X1603500Y723883D02*
X1600400D01*
Y724803D01*
X1600555Y725110D01*
X1600917Y725340D01*
X1601330Y725417D01*
X1601743Y725340D01*
X1602053Y725148D01*
X1602208Y724803D01*
Y723883D01*
G01X1600400Y726983D02*
X1603500D01*
Y728517D01*
G01X1602208Y730122D02*
X1601847Y730390D01*
X1601640Y730620D01*
X1601537Y730927D01*
X1601640Y731195D01*
X1601847Y731387D01*
X1602157Y731540D01*
X1602518Y731578D01*
X1602828Y731540D01*
X1603138Y731387D01*
X1603397Y731157D01*
X1603500Y730888D01*
X1603397Y730582D01*
X1603087Y730313D01*
X1602622Y730160D01*
X1602105Y730122D01*
X1601433Y730198D01*
X1601072Y730313D01*
X1600710Y730505D01*
X1600452Y730773D01*
X1600400Y731042D01*
X1600503Y731310D01*
X1600762Y731502D01*
G01X1603500Y734410D02*
X1600400D01*
X1602622Y732992D01*
Y734908D01*
G01X1593115Y776482D02*
Y774260D01*
X1593268Y773795D01*
X1593575Y773485D01*
X1593958Y773382D01*
X1594341Y773485D01*
X1594648Y773795D01*
X1594801Y774260D01*
Y776482D01*
G01X1596330Y775965D02*
X1596560Y776275D01*
X1596828Y776430D01*
X1597135Y776482D01*
X1597518Y776379D01*
X1597786Y776120D01*
X1597863Y775810D01*
X1597825Y775500D01*
X1597671Y775242D01*
X1596905Y774725D01*
X1596560Y774364D01*
X1596330Y773847D01*
X1596253Y773382D01*
X1597863D01*
G01X1599315Y773847D02*
X1599545Y773589D01*
X1599813Y773434D01*
X1600158Y773382D01*
X1600503Y773485D01*
X1600771Y773692D01*
X1600963Y774054D01*
X1601001Y774467D01*
X1600925Y774880D01*
X1600733Y775139D01*
X1600465Y775345D01*
X1600196Y775397D01*
X1599928Y775345D01*
X1599583Y775139D01*
X1599698Y776482D01*
X1600733D01*
G01X1600661Y802500D02*
Y781811D01*
G01Y836200D02*
Y819700D01*
G01Y875800D02*
Y854000D01*
G01Y927000D02*
Y903300D01*
G01Y951700D02*
Y938900D01*
G01Y1004400D02*
Y969900D01*
G01Y1062600D02*
Y1014300D01*
G01Y1095800D02*
Y1079100D01*
G01Y1131200D02*
Y1114000D01*
G01Y1172000D02*
Y1141600D01*
G01Y1206500D02*
Y1188300D01*
G01Y1256024D02*
Y1223200D01*
G01X1592777Y1260688D02*
X1589577D01*
G01Y1266888D02*
X1592777D01*
G01X1589577Y1260688D02*
Y1266888D01*
G01X1592777D02*
Y1260688D01*
G01X1588777Y1266888D02*
Y1260688D01*
G01X1600661Y1393819D02*
Y1256024D01*
G01X1593277Y1280588D02*
Y1277388D01*
G01X1599323Y1441393D02*
X1591823Y1443726D01*
X1599323Y1446059D01*
G01X1596698Y1445219D02*
Y1442233D01*
G01X1599323Y1451226D02*
X1591823D01*
X1593323Y1450106D01*
G01X1599323D02*
Y1452346D01*
G01X1591823Y1458726D02*
X1592073Y1457979D01*
X1592698Y1457419D01*
X1593448Y1457046D01*
X1594448Y1456766D01*
X1595573Y1456673D01*
X1596698Y1456766D01*
X1597698Y1457046D01*
X1598448Y1457419D01*
X1599073Y1457979D01*
X1599323Y1458726D01*
X1599073Y1459473D01*
X1598448Y1460033D01*
X1597698Y1460406D01*
X1596698Y1460686D01*
X1595573Y1460779D01*
X1594448Y1460686D01*
X1593448Y1460406D01*
X1592698Y1460033D01*
X1592073Y1459473D01*
X1591823Y1458726D01*
G01X1603280Y1437930D02*
X1588280D01*
G01D02*
Y1463430D01*
G01X1591201Y1589794D02*
Y1587572D01*
X1591354Y1587107D01*
X1591661Y1586797D01*
X1592044Y1586694D01*
X1592427Y1586797D01*
X1592734Y1587107D01*
X1592887Y1587572D01*
Y1589794D01*
G01X1594416Y1587986D02*
X1594684Y1588347D01*
X1594914Y1588554D01*
X1595221Y1588657D01*
X1595489Y1588554D01*
X1595681Y1588347D01*
X1595834Y1588037D01*
X1595872Y1587676D01*
X1595834Y1587366D01*
X1595681Y1587056D01*
X1595451Y1586797D01*
X1595182Y1586694D01*
X1594876Y1586797D01*
X1594607Y1587107D01*
X1594454Y1587572D01*
X1594416Y1588089D01*
X1594492Y1588761D01*
X1594607Y1589122D01*
X1594799Y1589484D01*
X1595067Y1589742D01*
X1595336Y1589794D01*
X1595604Y1589691D01*
X1595796Y1589432D01*
G01X1598244Y1589794D02*
X1597937Y1589691D01*
X1597707Y1589432D01*
X1597554Y1589122D01*
X1597439Y1588709D01*
X1597401Y1588244D01*
X1597439Y1587779D01*
X1597554Y1587366D01*
X1597707Y1587056D01*
X1597937Y1586797D01*
X1598244Y1586694D01*
X1598551Y1586797D01*
X1598781Y1587056D01*
X1598934Y1587366D01*
X1599049Y1587779D01*
X1599087Y1588244D01*
X1599049Y1588709D01*
X1598934Y1589122D01*
X1598781Y1589432D01*
X1598551Y1589691D01*
X1598244Y1589794D01*
G01X1601344Y1586694D02*
Y1589794D01*
X1600884Y1589174D01*
G01Y1586694D02*
X1601804D01*
G01X1603716Y1589277D02*
X1603946Y1589587D01*
X1604214Y1589742D01*
X1604521Y1589794D01*
X1604904Y1589691D01*
X1605172Y1589432D01*
X1605249Y1589122D01*
X1605211Y1588812D01*
X1605057Y1588554D01*
X1604291Y1588037D01*
X1603946Y1587676D01*
X1603716Y1587159D01*
X1603639Y1586694D01*
X1605249D01*
G01X1599400Y1655760D02*
X1596300D01*
X1598522Y1654342D01*
Y1656258D01*
G01X1603635Y1654657D02*
X1603893Y1654887D01*
X1604048Y1655155D01*
X1604100Y1655500D01*
X1603997Y1655845D01*
X1603790Y1656113D01*
X1603428Y1656305D01*
X1603015Y1656343D01*
X1602602Y1656267D01*
X1602343Y1656075D01*
X1602137Y1655807D01*
X1602085Y1655538D01*
X1602137Y1655270D01*
X1602343Y1654925D01*
X1601000Y1655040D01*
Y1656075D01*
G01X1603800Y1646023D02*
X1597200D01*
G01X1597800Y1657834D02*
X1603400D01*
G01X1622131Y43779D02*
X1605391D01*
G01X1625500Y51142D02*
X1605500D01*
G01X1608862Y293360D02*
X1607400D01*
G01X1608862Y305564D02*
Y293360D01*
G01X1607400Y305564D02*
X1608862D01*
G01X1615800Y302071D02*
Y308271D01*
G01D02*
X1619000D01*
G01Y302071D02*
X1615800D01*
G01X1638000Y331505D02*
X1613070D01*
G01X1611820Y403600D02*
Y394600D01*
G01Y412600D02*
Y403600D01*
G01Y421600D02*
Y412600D01*
G01Y439600D02*
Y430600D01*
G01D02*
Y421600D01*
G01Y448600D02*
Y439600D01*
G01Y457600D02*
Y448600D01*
G01Y466600D02*
Y457600D01*
G01Y484600D02*
Y475600D01*
G01D02*
Y466600D01*
G01Y493600D02*
Y484600D01*
G01Y502600D02*
Y493600D01*
G01X1620409Y529139D02*
X1614209D01*
G01D02*
Y532339D01*
G01D02*
X1620409D01*
G01X1603399Y537944D02*
Y534744D01*
G01Y532826D02*
Y529626D01*
G01X1615165Y540323D02*
Y537123D01*
G01X1608965D02*
Y540323D01*
G01X1615165Y537123D02*
X1608965D01*
G01X1612859Y523662D02*
Y528262D01*
G01D02*
X1622859D01*
G01X1612859Y528162D02*
Y528262D01*
G01X1622859Y523662D02*
X1612859D01*
G01X1615048Y556264D02*
Y553064D01*
G01X1608848D02*
Y556264D01*
G01X1615048Y553064D02*
X1608848D01*
G01X1603686Y551773D02*
X1606886D01*
G01X1603686Y545573D02*
Y551773D01*
G01X1606886Y545573D02*
X1603686D01*
G01X1606886Y551773D02*
Y545573D01*
G01X1614953Y545571D02*
X1611753Y545575D01*
G01X1614959Y551771D02*
X1614953Y545571D01*
G01X1611759Y551775D02*
X1614959Y551771D01*
G01X1611753Y545575D02*
X1611759Y551775D01*
G01X1607686Y551773D02*
X1610886D01*
G01X1607686Y545573D02*
Y551773D01*
G01X1610886Y545573D02*
X1607686D01*
G01X1610886Y551773D02*
Y545573D01*
G01X1615219Y544333D02*
Y541133D01*
G01X1609019D02*
Y544333D01*
G01X1615219Y541133D02*
X1609019D01*
G01Y544333D02*
X1615219D01*
G01X1608965Y540323D02*
X1615165D01*
G01X1608848Y556264D02*
X1615048D01*
G01X1619106Y563326D02*
X1615906D01*
G01D02*
Y569526D01*
G01X1615111Y557492D02*
X1608911D01*
G01X1615111Y560692D02*
Y557492D01*
G01X1608911Y560692D02*
X1615111D01*
G01X1608911Y557492D02*
Y560692D01*
G01X1615906Y569526D02*
X1619106D01*
G01X1606903Y571933D02*
X1619879D01*
G01X1606903Y615933D02*
Y571933D01*
G01X1611234Y624154D02*
Y627254D01*
X1612154D01*
X1612461Y627099D01*
X1612691Y626737D01*
X1612768Y626324D01*
X1612691Y625911D01*
X1612499Y625601D01*
X1612154Y625446D01*
X1611234D01*
G01X1614258Y627254D02*
Y625032D01*
X1614411Y624567D01*
X1614718Y624257D01*
X1615101Y624154D01*
X1615484Y624257D01*
X1615791Y624567D01*
X1615944Y625032D01*
Y627254D01*
G01X1617358Y624619D02*
X1617588Y624361D01*
X1617856Y624206D01*
X1618201Y624154D01*
X1618546Y624257D01*
X1618814Y624464D01*
X1619006Y624826D01*
X1619044Y625239D01*
X1618968Y625652D01*
X1618776Y625911D01*
X1618508Y626117D01*
X1618239Y626169D01*
X1617971Y626117D01*
X1617626Y625911D01*
X1617741Y627254D01*
X1618776D01*
G01X1621301Y624154D02*
Y627254D01*
X1620841Y626634D01*
G01Y624154D02*
X1621761D01*
G01X1619979Y615933D02*
X1606903D01*
G01X1611213Y647731D02*
Y641531D01*
G01D02*
X1608013D01*
G01D02*
Y647731D01*
G01X1615997Y641329D02*
Y647529D01*
G01X1619197Y641329D02*
X1615997D01*
G01X1611997D02*
Y647529D01*
G01X1615197D02*
Y641329D01*
G01D02*
X1611997D01*
G01X1607243Y644837D02*
Y641637D01*
G01X1608013Y647731D02*
X1611213D01*
G01X1615997Y647529D02*
X1619197D01*
G01X1611997D02*
X1615197D01*
G01X1615107Y656362D02*
Y650162D01*
G01D02*
X1611907D01*
G01D02*
Y651500D01*
G01Y656362D02*
X1615107D01*
G01X1611907Y654400D02*
Y656362D01*
G01X1608850Y653798D02*
Y651944D01*
G01D02*
X1607842D01*
G01X1611907Y660662D02*
Y666862D01*
G01D02*
X1615107D01*
G01D02*
Y660662D01*
G01D02*
X1611907D01*
G01X1615084Y673683D02*
Y667483D01*
G01D02*
X1611884D01*
G01D02*
Y673683D01*
G01X1608850Y666355D02*
Y664657D01*
G01X1610450Y677183D02*
X1616650D01*
G01D02*
Y673983D01*
G01D02*
X1610450D01*
G01D02*
Y677183D01*
G01X1611884Y673683D02*
X1615084D01*
G01X1608057Y675566D02*
X1608850D01*
G01D02*
Y672966D01*
G01X1615008Y722091D02*
Y678783D01*
G01D02*
X1609667D01*
G01Y722091D02*
X1615008D01*
G01X1610740Y1315318D02*
Y1312218D01*
G01X1609858Y1315318D02*
X1611622D01*
G01X1613073Y1312218D02*
Y1315318D01*
X1613993D01*
X1614300Y1315163D01*
X1614530Y1314801D01*
X1614607Y1314388D01*
X1614530Y1313975D01*
X1614338Y1313665D01*
X1613993Y1313510D01*
X1613073D01*
G01X1616940Y1312218D02*
X1617208Y1312270D01*
X1617515Y1312425D01*
X1617707Y1312683D01*
X1617783Y1313045D01*
X1617707Y1313406D01*
X1617477Y1313716D01*
X1617132Y1313871D01*
X1616748D01*
X1616518Y1313975D01*
X1616327Y1314233D01*
X1616250Y1314595D01*
X1616365Y1314956D01*
X1616633Y1315215D01*
X1616940Y1315318D01*
X1617247Y1315215D01*
X1617515Y1314956D01*
X1617630Y1314595D01*
X1617553Y1314233D01*
X1617362Y1313975D01*
X1617132Y1313871D01*
X1616748D01*
X1616403Y1313716D01*
X1616173Y1313406D01*
X1616097Y1313045D01*
X1616173Y1312683D01*
X1616365Y1312425D01*
X1616672Y1312270D01*
X1616940Y1312218D01*
G01X1613638Y1399590D02*
Y1402690D01*
G01X1615248D02*
Y1399590D01*
G01Y1401140D02*
X1613638D01*
G01X1616700Y1400210D02*
X1616930Y1399848D01*
X1617236Y1399642D01*
X1617581Y1399590D01*
X1617888Y1399642D01*
X1618195Y1399900D01*
X1618386Y1400210D01*
X1618425Y1400520D01*
X1618348Y1400882D01*
X1618080Y1401140D01*
X1617811Y1401243D01*
X1617466D01*
G01X1617811D02*
X1618041Y1401398D01*
X1618233Y1401657D01*
X1618310Y1401967D01*
X1618233Y1402277D01*
X1618041Y1402535D01*
X1617696Y1402690D01*
X1617351Y1402638D01*
X1617006Y1402432D01*
G01X1619800Y1400210D02*
X1620030Y1399848D01*
X1620336Y1399642D01*
X1620681Y1399590D01*
X1620988Y1399642D01*
X1621295Y1399900D01*
X1621486Y1400210D01*
X1621525Y1400520D01*
X1621448Y1400882D01*
X1621180Y1401140D01*
X1620911Y1401243D01*
X1620566D01*
G01X1620911D02*
X1621141Y1401398D01*
X1621333Y1401657D01*
X1621410Y1401967D01*
X1621333Y1402277D01*
X1621141Y1402535D01*
X1620796Y1402690D01*
X1620451Y1402638D01*
X1620106Y1402432D01*
G01X1614323Y1441393D02*
X1606823Y1443726D01*
X1614323Y1446059D01*
G01X1611698Y1445219D02*
Y1442233D01*
G01X1614323Y1451226D02*
X1606823D01*
X1608323Y1450106D01*
G01X1614323D02*
Y1452346D01*
G01Y1458726D02*
X1606823D01*
X1608323Y1457606D01*
G01X1614323D02*
Y1459846D01*
G01X1603280Y1437930D02*
X1618280D01*
G01X1603280D02*
Y1463430D01*
G01X1617000Y1655223D02*
X1616328Y1655300D01*
X1615760Y1655415D01*
X1615243Y1655568D01*
X1614675Y1655760D01*
X1613900Y1656067D01*
Y1654533D01*
G01X1610608Y1654472D02*
X1610247Y1654740D01*
X1610040Y1654970D01*
X1609937Y1655277D01*
X1610040Y1655545D01*
X1610247Y1655737D01*
X1610557Y1655890D01*
X1610918Y1655928D01*
X1611228Y1655890D01*
X1611538Y1655737D01*
X1611797Y1655507D01*
X1611900Y1655238D01*
X1611797Y1654932D01*
X1611487Y1654663D01*
X1611022Y1654510D01*
X1610505Y1654472D01*
X1609833Y1654548D01*
X1609472Y1654663D01*
X1609110Y1654855D01*
X1608852Y1655123D01*
X1608800Y1655392D01*
X1608903Y1655660D01*
X1609162Y1655852D01*
G01X1616000Y1646023D02*
X1609300D01*
G01X1609700Y1657834D02*
X1615400D01*
G01X1633500Y51142D02*
X1631000D01*
G01X1664000Y132000D02*
X1620000D01*
G01D02*
Y249000D01*
G01X1630717Y236444D02*
Y234222D01*
X1630870Y233757D01*
X1631177Y233447D01*
X1631560Y233344D01*
X1631943Y233447D01*
X1632250Y233757D01*
X1632403Y234222D01*
Y236444D01*
G01X1633932Y235927D02*
X1634162Y236237D01*
X1634430Y236392D01*
X1634737Y236444D01*
X1635120Y236341D01*
X1635388Y236082D01*
X1635465Y235772D01*
X1635427Y235462D01*
X1635273Y235204D01*
X1634507Y234687D01*
X1634162Y234326D01*
X1633932Y233809D01*
X1633855Y233344D01*
X1635465D01*
G01X1638220D02*
Y236444D01*
X1636802Y234222D01*
X1638718D01*
G01X1640860Y236444D02*
X1640553Y236341D01*
X1640323Y236082D01*
X1640170Y235772D01*
X1640055Y235359D01*
X1640017Y234894D01*
X1640055Y234429D01*
X1640170Y234016D01*
X1640323Y233706D01*
X1640553Y233447D01*
X1640860Y233344D01*
X1641167Y233447D01*
X1641397Y233706D01*
X1641550Y234016D01*
X1641665Y234429D01*
X1641703Y234894D01*
X1641665Y235359D01*
X1641550Y235772D01*
X1641397Y236082D01*
X1641167Y236341D01*
X1640860Y236444D01*
G01X1620000Y249000D02*
X1638000D01*
G01X1620842Y281128D02*
Y284328D01*
G01X1627042Y281128D02*
X1620842D01*
G01X1627042Y284328D02*
Y281128D01*
G01X1620842Y284328D02*
X1627042D01*
G01X1620842Y280120D02*
X1627042D01*
Y276920D01*
X1620842D01*
Y280120D01*
G01X1620809Y289142D02*
Y292342D01*
G01X1627009Y289142D02*
X1620809D01*
G01Y292342D02*
X1627009D01*
G01D02*
Y289142D01*
G01Y293142D02*
X1620809D01*
G01D02*
Y296342D01*
G01D02*
X1627009D01*
G01D02*
Y293142D01*
G01Y297142D02*
X1620809D01*
G01D02*
Y300342D01*
G01X1627009D02*
Y297142D01*
G01X1620809Y288342D02*
X1627009D01*
G01D02*
Y285142D01*
G01D02*
X1620809D01*
G01D02*
Y288342D01*
G01X1619000Y308271D02*
Y302071D01*
G01X1627009Y301142D02*
X1620809D01*
G01D02*
Y304342D01*
G01D02*
X1627009D01*
G01D02*
Y301142D01*
G01X1620809Y300342D02*
X1627009D01*
G01X1630600Y384400D02*
X1627400D01*
G01X1630600Y390600D02*
Y384400D01*
G01X1627400D02*
Y390600D01*
G01X1623400Y384400D02*
Y390600D01*
G01X1626600Y384400D02*
X1623400D01*
G01X1626600Y390600D02*
Y384400D01*
G01X1630600Y391400D02*
X1627400D01*
G01X1630600Y397600D02*
Y391400D01*
G01X1627400Y397600D02*
X1630600D01*
G01X1627400Y391400D02*
Y397600D01*
G01Y390600D02*
X1630600D01*
G01X1623400D02*
X1626600D01*
G01X1623639Y523230D02*
Y529230D01*
G01X1635639Y523230D02*
X1623639D01*
G01X1620409Y532339D02*
Y529139D01*
G01X1623639Y536130D02*
X1635639D01*
G01X1623639Y530130D02*
Y536130D01*
G01X1635639Y530130D02*
X1623639D01*
G01Y529230D02*
X1635639D01*
G01X1623639Y537030D02*
Y543030D01*
G01X1635639Y537030D02*
X1623639D01*
G01X1622859Y523662D02*
Y528262D01*
G01X1627048Y546193D02*
X1633150D01*
Y546664D01*
G01X1620946Y546464D02*
Y546193D01*
G01D02*
X1624748D01*
G01X1623639Y543030D02*
X1635639D01*
G01X1619106Y569526D02*
Y563326D01*
G01X1627066Y568403D02*
Y565203D01*
G01X1620866D02*
Y568403D01*
G01X1627066Y565203D02*
X1620866D01*
G01X1633150Y562064D02*
Y562335D01*
X1629348D01*
G01X1624748D02*
X1620946D01*
Y562064D01*
G01X1620866Y568403D02*
X1627066D01*
G01X1623376Y623341D02*
Y629541D01*
G01X1626576D02*
Y623341D01*
G01D02*
X1623376D01*
G01X1630618Y629541D02*
Y623341D01*
G01D02*
X1627418D01*
G01D02*
Y629541D01*
G01X1619197Y647529D02*
Y641329D01*
G01X1623376Y629541D02*
X1626576D01*
G01X1627418D02*
X1630618D01*
G01X1622897Y632944D02*
X1622164D01*
G01D02*
Y635135D01*
G01Y653966D02*
Y656566D01*
G01D02*
X1622957D01*
G01X1618279Y703091D02*
Y659783D01*
G01D02*
X1623620D01*
G01X1618772Y705000D02*
Y777000D01*
G01X1634263Y704996D02*
X1631163D01*
Y705916D01*
X1631318Y706223D01*
X1631680Y706453D01*
X1632093Y706530D01*
X1632506Y706453D01*
X1632816Y706261D01*
X1632971Y705916D01*
Y704996D01*
G01X1631163Y708096D02*
X1634263D01*
Y709630D01*
G01X1632971Y711235D02*
X1632610Y711503D01*
X1632403Y711733D01*
X1632300Y712040D01*
X1632403Y712308D01*
X1632610Y712500D01*
X1632920Y712653D01*
X1633281Y712691D01*
X1633591Y712653D01*
X1633901Y712500D01*
X1634160Y712270D01*
X1634263Y712001D01*
X1634160Y711695D01*
X1633850Y711426D01*
X1633385Y711273D01*
X1632868Y711235D01*
X1632196Y711311D01*
X1631835Y711426D01*
X1631473Y711618D01*
X1631215Y711886D01*
X1631163Y712155D01*
X1631266Y712423D01*
X1631525Y712615D01*
G01X1632971Y714335D02*
X1632610Y714603D01*
X1632403Y714833D01*
X1632300Y715140D01*
X1632403Y715408D01*
X1632610Y715600D01*
X1632920Y715753D01*
X1633281Y715791D01*
X1633591Y715753D01*
X1633901Y715600D01*
X1634160Y715370D01*
X1634263Y715101D01*
X1634160Y714795D01*
X1633850Y714526D01*
X1633385Y714373D01*
X1632868Y714335D01*
X1632196Y714411D01*
X1631835Y714526D01*
X1631473Y714718D01*
X1631215Y714986D01*
X1631163Y715255D01*
X1631266Y715523D01*
X1631525Y715715D01*
G01X1623620Y703091D02*
X1618279D01*
G01X1644362Y720709D02*
X1618772D01*
G01Y1252500D02*
Y1325040D01*
G01X1644362Y1291575D02*
X1618772D01*
G01X1621896Y1327765D02*
X1622088Y1327455D01*
X1622318Y1327248D01*
X1622586Y1327145D01*
X1622893Y1327248D01*
X1623123Y1327455D01*
X1623353Y1327765D01*
X1623430Y1328178D01*
Y1330245D01*
G01X1625763Y1327145D02*
Y1330245D01*
X1625303Y1329625D01*
G01Y1327145D02*
X1626223D01*
G01X1628135Y1328437D02*
X1628403Y1328798D01*
X1628633Y1329005D01*
X1628940Y1329108D01*
X1629208Y1329005D01*
X1629400Y1328798D01*
X1629553Y1328488D01*
X1629591Y1328127D01*
X1629553Y1327817D01*
X1629400Y1327507D01*
X1629170Y1327248D01*
X1628901Y1327145D01*
X1628595Y1327248D01*
X1628326Y1327558D01*
X1628173Y1328023D01*
X1628135Y1328540D01*
X1628211Y1329212D01*
X1628326Y1329573D01*
X1628518Y1329935D01*
X1628786Y1330193D01*
X1629055Y1330245D01*
X1629323Y1330142D01*
X1629515Y1329883D01*
G01X1618772Y1325040D02*
X1644362D01*
G01X1631267Y1408433D02*
X1631107Y1408183D01*
X1630920Y1408058D01*
X1630707Y1408016D01*
X1630440Y1408099D01*
X1630253Y1408308D01*
X1630200Y1408558D01*
X1630227Y1408808D01*
X1630333Y1409016D01*
X1630867Y1409433D01*
X1631107Y1409724D01*
X1631267Y1410141D01*
X1631320Y1410516D01*
X1630200D01*
G01X1628560D02*
Y1408016D01*
X1628880Y1408516D01*
G01Y1410516D02*
X1628240D01*
G01X1630433Y1418048D02*
X1630683Y1417888D01*
X1630808Y1417701D01*
X1630850Y1417488D01*
X1630767Y1417221D01*
X1630558Y1417034D01*
X1630308Y1416981D01*
X1630058Y1417008D01*
X1629850Y1417114D01*
X1629433Y1417648D01*
X1629142Y1417888D01*
X1628725Y1418048D01*
X1628350Y1418101D01*
Y1416981D01*
G01X1630850Y1415341D02*
X1630767Y1415554D01*
X1630558Y1415714D01*
X1630308Y1415821D01*
X1629975Y1415901D01*
X1629600Y1415928D01*
X1629225Y1415901D01*
X1628892Y1415821D01*
X1628642Y1415714D01*
X1628433Y1415554D01*
X1628350Y1415341D01*
X1628433Y1415128D01*
X1628642Y1414968D01*
X1628892Y1414861D01*
X1629225Y1414781D01*
X1629600Y1414754D01*
X1629975Y1414781D01*
X1630308Y1414861D01*
X1630558Y1414968D01*
X1630767Y1415128D01*
X1630850Y1415341D01*
G01X1618280Y1424430D02*
Y1437930D01*
G01X1628128Y1430648D02*
Y1433848D01*
G01X1634328Y1430648D02*
X1628128D01*
G01X1628103Y1426066D02*
X1634303D01*
G01X1628103Y1422866D02*
Y1426066D01*
G01X1634303Y1422866D02*
X1628103D01*
G01Y1429966D02*
X1634303D01*
G01X1628103Y1426766D02*
Y1429966D01*
G01X1634303Y1426766D02*
X1628103D01*
G01X1619400Y1430900D02*
Y1437100D01*
G01X1622600Y1430900D02*
X1619400D01*
G01X1622600Y1437100D02*
Y1430900D01*
G01X1628149Y1418850D02*
Y1422050D01*
G01X1634349Y1418850D02*
X1628149D01*
G01Y1422050D02*
X1634349D01*
G01X1618280Y1437930D02*
Y1463430D01*
G01X1628128Y1433848D02*
X1634328D01*
G01X1628128Y1437748D02*
X1634328D01*
G01X1628128Y1434548D02*
Y1437748D01*
G01X1634328Y1434548D02*
X1628128D01*
G01X1628067Y1446416D02*
Y1449616D01*
G01X1634267Y1446416D02*
X1628067D01*
G01X1619400Y1437100D02*
X1622600D01*
G01X1628067Y1442416D02*
Y1445616D01*
G01X1634267Y1442416D02*
X1628067D01*
G01Y1445616D02*
X1634267D01*
G01X1628067Y1438416D02*
Y1441616D01*
G01X1634267Y1438416D02*
X1628067D01*
G01Y1441616D02*
X1634267D01*
G01X1628067Y1449616D02*
X1634267D01*
G01X1626700Y1655100D02*
X1626648Y1655368D01*
X1626493Y1655675D01*
X1626235Y1655867D01*
X1625873Y1655943D01*
X1625512Y1655867D01*
X1625202Y1655637D01*
X1625047Y1655292D01*
Y1654908D01*
X1624943Y1654678D01*
X1624685Y1654487D01*
X1624323Y1654410D01*
X1623962Y1654525D01*
X1623703Y1654793D01*
X1623600Y1655100D01*
X1623703Y1655407D01*
X1623962Y1655675D01*
X1624323Y1655790D01*
X1624685Y1655713D01*
X1624943Y1655522D01*
X1625047Y1655292D01*
Y1654908D01*
X1625202Y1654563D01*
X1625512Y1654333D01*
X1625873Y1654257D01*
X1626235Y1654333D01*
X1626493Y1654525D01*
X1626648Y1654832D01*
X1626700Y1655100D01*
G01X1628000Y1646023D02*
X1621500D01*
G01X1631496Y1657834D02*
Y1736118D01*
G01X1621800Y1657834D02*
X1627400D01*
G01X1649000Y51142D02*
X1646500D01*
G01X1641500D02*
X1639000D01*
G01X1635058Y231979D02*
Y219775D01*
G01D02*
X1644562D01*
G01D02*
Y231979D01*
G01X1639810Y228377D02*
X1636808Y231979D01*
G01D02*
X1635058D01*
G01X1644562D02*
X1642812D01*
G01D02*
X1639810Y228377D01*
G01X1638000Y249000D02*
Y331505D01*
G01X1640100Y383100D02*
Y379900D01*
G01X1633900Y383100D02*
X1640100D01*
G01X1633900Y379900D02*
Y383100D01*
G01X1640100Y379900D02*
X1633900D01*
G01X1646846Y385198D02*
X1649086D01*
G01X1647873Y386823D02*
Y383573D01*
G01X1644406Y398428D02*
Y384572D01*
G01X1632594D02*
Y398428D01*
G01X1644406Y384572D02*
X1632594D01*
G01X1632547Y405136D02*
Y402914D01*
X1632700Y402449D01*
X1633007Y402139D01*
X1633390Y402036D01*
X1633773Y402139D01*
X1634080Y402449D01*
X1634233Y402914D01*
Y405136D01*
G01X1636490Y402036D02*
X1636758Y402088D01*
X1637065Y402243D01*
X1637257Y402501D01*
X1637333Y402863D01*
X1637257Y403224D01*
X1637027Y403534D01*
X1636682Y403689D01*
X1636298D01*
X1636068Y403793D01*
X1635877Y404051D01*
X1635800Y404413D01*
X1635915Y404774D01*
X1636183Y405033D01*
X1636490Y405136D01*
X1636797Y405033D01*
X1637065Y404774D01*
X1637180Y404413D01*
X1637103Y404051D01*
X1636912Y403793D01*
X1636682Y403689D01*
X1636298D01*
X1635953Y403534D01*
X1635723Y403224D01*
X1635647Y402863D01*
X1635723Y402501D01*
X1635915Y402243D01*
X1636222Y402088D01*
X1636490Y402036D01*
G01X1639590Y405136D02*
X1639283Y405033D01*
X1639053Y404774D01*
X1638900Y404464D01*
X1638785Y404051D01*
X1638747Y403586D01*
X1638785Y403121D01*
X1638900Y402708D01*
X1639053Y402398D01*
X1639283Y402139D01*
X1639590Y402036D01*
X1639897Y402139D01*
X1640127Y402398D01*
X1640280Y402708D01*
X1640395Y403121D01*
X1640433Y403586D01*
X1640395Y404051D01*
X1640280Y404464D01*
X1640127Y404774D01*
X1639897Y405033D01*
X1639590Y405136D01*
G01X1642690D02*
X1642383Y405033D01*
X1642153Y404774D01*
X1642000Y404464D01*
X1641885Y404051D01*
X1641847Y403586D01*
X1641885Y403121D01*
X1642000Y402708D01*
X1642153Y402398D01*
X1642383Y402139D01*
X1642690Y402036D01*
X1642997Y402139D01*
X1643227Y402398D01*
X1643380Y402708D01*
X1643495Y403121D01*
X1643533Y403586D01*
X1643495Y404051D01*
X1643380Y404464D01*
X1643227Y404774D01*
X1642997Y405033D01*
X1642690Y405136D01*
G01X1645790Y402036D02*
Y405136D01*
X1645330Y404516D01*
G01Y402036D02*
X1646250D01*
G01X1632594Y398428D02*
X1644406D01*
G01X1649210Y412602D02*
X1643010D01*
G01D02*
Y415802D01*
G01D02*
X1649210D01*
G01X1635622Y407695D02*
X1632522D01*
Y408615D01*
X1632677Y408922D01*
X1633039Y409152D01*
X1633452Y409229D01*
X1633865Y409152D01*
X1634175Y408960D01*
X1634330Y408615D01*
Y407695D01*
G01X1632522Y410719D02*
X1634744D01*
X1635209Y410872D01*
X1635519Y411179D01*
X1635622Y411562D01*
X1635519Y411945D01*
X1635209Y412252D01*
X1634744Y412405D01*
X1632522D01*
G01X1633039Y413934D02*
X1632729Y414164D01*
X1632574Y414432D01*
X1632522Y414739D01*
X1632625Y415122D01*
X1632884Y415390D01*
X1633194Y415467D01*
X1633504Y415429D01*
X1633762Y415275D01*
X1634279Y414509D01*
X1634640Y414164D01*
X1635157Y413934D01*
X1635622Y413857D01*
Y415467D01*
G01X1632522Y417762D02*
X1632625Y417455D01*
X1632884Y417225D01*
X1633194Y417072D01*
X1633607Y416957D01*
X1634072Y416919D01*
X1634537Y416957D01*
X1634950Y417072D01*
X1635260Y417225D01*
X1635519Y417455D01*
X1635622Y417762D01*
X1635519Y418069D01*
X1635260Y418299D01*
X1634950Y418452D01*
X1634537Y418567D01*
X1634072Y418605D01*
X1633607Y418567D01*
X1633194Y418452D01*
X1632884Y418299D01*
X1632625Y418069D01*
X1632522Y417762D01*
G01X1635157Y420019D02*
X1635415Y420249D01*
X1635570Y420517D01*
X1635622Y420862D01*
X1635519Y421207D01*
X1635312Y421475D01*
X1634950Y421667D01*
X1634537Y421705D01*
X1634124Y421629D01*
X1633865Y421437D01*
X1633659Y421169D01*
X1633607Y420900D01*
X1633659Y420632D01*
X1633865Y420287D01*
X1632522Y420402D01*
Y421437D01*
G01X1644910Y426944D02*
Y433144D01*
G01D02*
X1648110D01*
G01Y426944D02*
X1644910D01*
G01X1635639Y529230D02*
Y523230D01*
G01Y536130D02*
Y530130D01*
G01Y543030D02*
Y537030D01*
G01X1642296Y551694D02*
X1644518D01*
X1644983Y551847D01*
X1645293Y552154D01*
X1645396Y552537D01*
X1645293Y552920D01*
X1644983Y553227D01*
X1644518Y553380D01*
X1642296D01*
G01X1644776Y554794D02*
X1645138Y555024D01*
X1645344Y555330D01*
X1645396Y555675D01*
X1645344Y555982D01*
X1645086Y556289D01*
X1644776Y556480D01*
X1644466Y556519D01*
X1644104Y556442D01*
X1643846Y556174D01*
X1643743Y555905D01*
Y555560D01*
G01Y555905D02*
X1643588Y556135D01*
X1643329Y556327D01*
X1643019Y556404D01*
X1642709Y556327D01*
X1642451Y556135D01*
X1642296Y555790D01*
X1642348Y555445D01*
X1642554Y555100D01*
G01X1642813Y558009D02*
X1642503Y558239D01*
X1642348Y558507D01*
X1642296Y558814D01*
X1642399Y559197D01*
X1642658Y559465D01*
X1642968Y559542D01*
X1643278Y559504D01*
X1643536Y559350D01*
X1644053Y558584D01*
X1644414Y558239D01*
X1644931Y558009D01*
X1645396Y557932D01*
Y559542D01*
G01X1644104Y561109D02*
X1643743Y561377D01*
X1643536Y561607D01*
X1643433Y561914D01*
X1643536Y562182D01*
X1643743Y562374D01*
X1644053Y562527D01*
X1644414Y562565D01*
X1644724Y562527D01*
X1645034Y562374D01*
X1645293Y562144D01*
X1645396Y561875D01*
X1645293Y561569D01*
X1644983Y561300D01*
X1644518Y561147D01*
X1644001Y561109D01*
X1643329Y561185D01*
X1642968Y561300D01*
X1642606Y561492D01*
X1642348Y561760D01*
X1642296Y562029D01*
X1642399Y562297D01*
X1642658Y562489D01*
G01X1639934Y556687D02*
X1636734D01*
G01Y562887D02*
X1639934D01*
G01X1636734Y556687D02*
Y562887D01*
G01X1639934D02*
Y556687D01*
G01X1634379Y571933D02*
X1647455D01*
G01X1647288Y625606D02*
X1641088D01*
G01D02*
Y628806D01*
G01X1634043Y625837D02*
X1640243D01*
G01D02*
Y622637D01*
G01D02*
X1634043D01*
G01D02*
Y625837D01*
G01X1647455Y615933D02*
X1634279D01*
G01X1641088Y628806D02*
X1647288D01*
G01X1648107Y631162D02*
X1644907D01*
G01D02*
Y632700D01*
G01Y637362D02*
X1648107D01*
G01X1644907Y634600D02*
Y637362D01*
G01Y641662D02*
Y647862D01*
G01X1648107Y641662D02*
X1644907D01*
G01X1641850Y634798D02*
Y632944D01*
G01D02*
X1640842D01*
G01X1644907Y647862D02*
X1648107D01*
G01X1649650Y654983D02*
X1643450D01*
G01D02*
Y658183D01*
G01X1648084Y648483D02*
X1644884D01*
G01D02*
Y654683D01*
G01D02*
X1648084D01*
G01X1641057Y656566D02*
X1641850D01*
G01D02*
Y653966D01*
G01Y647355D02*
Y645657D01*
G01X1643450Y658183D02*
X1649650D01*
G01X1647807Y659783D02*
X1642466D01*
G01X1644362Y1293000D02*
Y705000D01*
G01X1642466Y703091D02*
X1647807D01*
G01X1640204Y1312661D02*
X1643404D01*
G01X1640204Y1306461D02*
Y1312661D01*
G01X1643404Y1306461D02*
X1640204D01*
G01X1643404Y1312661D02*
Y1306461D01*
G01X1639433Y1313474D02*
Y1310274D01*
G01X1633233D02*
Y1313474D01*
G01X1639433Y1310274D02*
X1633233D01*
G01Y1305274D02*
Y1308474D01*
G01X1639433Y1305274D02*
X1633233D01*
G01X1639433Y1308474D02*
Y1305274D01*
G01X1633233Y1308474D02*
X1639433D01*
G01X1645045Y1298763D02*
X1652172D01*
G01X1645045Y1317417D02*
Y1298763D01*
G01X1633233Y1313474D02*
X1639433D01*
G01X1644362Y1325040D02*
Y1323500D01*
G01X1643825Y1327995D02*
X1644017Y1327685D01*
X1644247Y1327478D01*
X1644515Y1327375D01*
X1644822Y1327478D01*
X1645052Y1327685D01*
X1645282Y1327995D01*
X1645359Y1328408D01*
Y1330475D01*
G01X1646964Y1328667D02*
X1647232Y1329028D01*
X1647462Y1329235D01*
X1647769Y1329338D01*
X1648037Y1329235D01*
X1648229Y1329028D01*
X1648382Y1328718D01*
X1648420Y1328357D01*
X1648382Y1328047D01*
X1648229Y1327737D01*
X1647999Y1327478D01*
X1647730Y1327375D01*
X1647424Y1327478D01*
X1647155Y1327788D01*
X1647002Y1328253D01*
X1646964Y1328770D01*
X1647040Y1329442D01*
X1647155Y1329803D01*
X1647347Y1330165D01*
X1647615Y1330423D01*
X1647884Y1330475D01*
X1648152Y1330372D01*
X1648344Y1330113D01*
G01X1650140Y1327737D02*
X1650409Y1327478D01*
X1650715Y1327375D01*
X1651022Y1327478D01*
X1651290Y1327788D01*
X1651482Y1328253D01*
X1651559Y1328718D01*
Y1329287D01*
X1651482Y1329752D01*
X1651290Y1330165D01*
X1651060Y1330372D01*
X1650792Y1330475D01*
X1650485Y1330372D01*
X1650255Y1330165D01*
X1650102Y1329855D01*
X1650025Y1329442D01*
X1650102Y1329080D01*
X1650294Y1328718D01*
X1650524Y1328512D01*
X1650792Y1328460D01*
X1651099Y1328563D01*
X1651329Y1328822D01*
X1651559Y1329287D01*
G01X1648045Y1320417D02*
X1645045Y1317417D01*
G01X1648132Y1370220D02*
X1645032D01*
Y1371140D01*
X1645187Y1371447D01*
X1645549Y1371677D01*
X1645962Y1371754D01*
X1646375Y1371677D01*
X1646685Y1371485D01*
X1646840Y1371140D01*
Y1370220D01*
G01X1645032Y1373244D02*
X1647254D01*
X1647719Y1373397D01*
X1648029Y1373704D01*
X1648132Y1374087D01*
X1648029Y1374470D01*
X1647719Y1374777D01*
X1647254Y1374930D01*
X1645032D01*
G01X1645549Y1376459D02*
X1645239Y1376689D01*
X1645084Y1376957D01*
X1645032Y1377264D01*
X1645135Y1377647D01*
X1645394Y1377915D01*
X1645704Y1377992D01*
X1646014Y1377954D01*
X1646272Y1377800D01*
X1646789Y1377034D01*
X1647150Y1376689D01*
X1647667Y1376459D01*
X1648132Y1376382D01*
Y1377992D01*
G01X1645549Y1379559D02*
X1645239Y1379789D01*
X1645084Y1380057D01*
X1645032Y1380364D01*
X1645135Y1380747D01*
X1645394Y1381015D01*
X1645704Y1381092D01*
X1646014Y1381054D01*
X1646272Y1380900D01*
X1646789Y1380134D01*
X1647150Y1379789D01*
X1647667Y1379559D01*
X1648132Y1379482D01*
Y1381092D01*
G01X1646755Y1389720D02*
X1643555D01*
G01X1646755Y1395920D02*
Y1389720D01*
G01X1643555Y1395920D02*
X1646755D01*
G01X1643555Y1389720D02*
Y1395920D01*
G01X1636390Y1408798D02*
Y1411998D01*
G01X1642590Y1408798D02*
X1636390D01*
G01X1642590Y1411998D02*
Y1408798D01*
G01X1636390Y1411998D02*
X1642590D01*
G01X1632727Y1411040D02*
X1635927D01*
G01Y1404840D02*
X1632727D01*
G01X1635927Y1411040D02*
Y1404840D01*
G01X1632727D02*
Y1411040D01*
G01X1639440Y1415698D02*
Y1417604D01*
G01X1641346Y1415698D02*
X1639440D01*
G01X1634328Y1433848D02*
Y1430648D01*
G01X1634303Y1426066D02*
Y1422866D01*
G01Y1429966D02*
Y1426766D01*
G01X1634349Y1422050D02*
Y1418850D01*
G01X1634983Y1418541D02*
X1637983D01*
G01X1637933Y1426341D02*
X1636433D01*
G01X1634328Y1437748D02*
Y1434548D01*
G01X1634267Y1449616D02*
Y1446416D01*
G01Y1445616D02*
Y1442416D01*
G01Y1441616D02*
Y1438416D01*
G01X1638067Y1440628D02*
Y1443828D01*
G01X1644267Y1440628D02*
X1638067D01*
G01X1644267Y1443828D02*
Y1440628D01*
G01X1638067Y1443828D02*
X1644267D01*
G01X1645077Y1442088D02*
X1651277D01*
G01X1645077Y1438888D02*
Y1442088D01*
G01X1651277Y1438888D02*
X1645077D01*
G01X1634567Y1443578D02*
X1637767D01*
G01X1634567Y1437378D02*
Y1443578D01*
G01X1637767Y1437378D02*
X1634567D01*
G01X1637767Y1443578D02*
Y1437378D01*
G01X1641411Y1440035D02*
Y1437535D01*
X1641731Y1438035D01*
G01Y1440035D02*
X1641091D01*
G01X1639211Y1437535D02*
X1639424Y1437618D01*
X1639584Y1437827D01*
X1639691Y1438077D01*
X1639771Y1438410D01*
X1639798Y1438785D01*
X1639771Y1439160D01*
X1639691Y1439493D01*
X1639584Y1439743D01*
X1639424Y1439952D01*
X1639211Y1440035D01*
X1638998Y1439952D01*
X1638838Y1439743D01*
X1638731Y1439493D01*
X1638651Y1439160D01*
X1638624Y1438785D01*
X1638651Y1438410D01*
X1638731Y1438077D01*
X1638838Y1437827D01*
X1638998Y1437618D01*
X1639211Y1437535D01*
G01X1635250Y1436041D02*
X1637750D01*
X1637250Y1436361D01*
G01X1635250D02*
Y1435721D01*
G01Y1433841D02*
X1637750D01*
X1637250Y1434161D01*
G01X1635250D02*
Y1433521D01*
G01X1639440Y1435384D02*
X1641336D01*
G01X1639440Y1433478D02*
Y1435384D01*
G01X1642183Y1437760D02*
Y1436941D01*
G01X1640300Y1646023D02*
X1633300D01*
G01X1643307Y1736118D02*
Y1659000D01*
G01X1635834Y1686125D02*
X1632734D01*
G01Y1687581D02*
X1634646Y1686125D01*
G01X1635834Y1687811D02*
X1633767Y1686776D01*
G01X1632734Y1681476D02*
X1635834D01*
Y1683010D01*
G01Y1676522D02*
X1632734D01*
X1635317Y1677519D01*
X1632734Y1678516D01*
X1635834D01*
G01Y1671913D02*
X1632734D01*
X1635834Y1673677D01*
X1632734D01*
G01X1635214Y1690925D02*
X1635524Y1691117D01*
X1635731Y1691347D01*
X1635834Y1691615D01*
X1635731Y1691922D01*
X1635524Y1692152D01*
X1635214Y1692382D01*
X1634801Y1692459D01*
X1632734D01*
G01X1635834Y1700336D02*
X1632734D01*
G01Y1701946D02*
X1635834D01*
G01X1634284D02*
Y1700336D01*
G01X1632734Y1695957D02*
Y1696877D01*
G01Y1696417D02*
X1635834D01*
G01Y1695957D02*
Y1696877D01*
G01X1641741Y1703388D02*
X1638641D01*
Y1704308D01*
X1638796Y1704615D01*
X1639158Y1704845D01*
X1639571Y1704922D01*
X1639984Y1704845D01*
X1640294Y1704653D01*
X1640449Y1704308D01*
Y1703388D01*
G01X1641741Y1706488D02*
X1638641D01*
Y1707447D01*
X1638796Y1707753D01*
X1639003Y1707945D01*
X1639416Y1708022D01*
X1639829Y1707945D01*
X1640088Y1707715D01*
X1640243Y1707447D01*
Y1706488D01*
G01Y1707447D02*
X1641741Y1708022D01*
G01Y1711122D02*
Y1709588D01*
X1638641D01*
Y1711122D01*
G01X1640139Y1710508D02*
Y1709588D01*
G01X1641328Y1712650D02*
X1641586Y1712957D01*
X1641741Y1713302D01*
Y1713608D01*
X1641586Y1713915D01*
X1641328Y1714145D01*
X1640966Y1714260D01*
X1640604Y1714183D01*
X1640294Y1713992D01*
X1640088Y1713647D01*
X1639984Y1713187D01*
X1639778Y1712918D01*
X1639416Y1712803D01*
X1639054Y1712880D01*
X1638796Y1713072D01*
X1638641Y1713340D01*
Y1713608D01*
X1638744Y1713877D01*
X1639003Y1714107D01*
G01X1641328Y1715750D02*
X1641586Y1716057D01*
X1641741Y1716402D01*
Y1716708D01*
X1641586Y1717015D01*
X1641328Y1717245D01*
X1640966Y1717360D01*
X1640604Y1717283D01*
X1640294Y1717092D01*
X1640088Y1716747D01*
X1639984Y1716287D01*
X1639778Y1716018D01*
X1639416Y1715903D01*
X1639054Y1715980D01*
X1638796Y1716172D01*
X1638641Y1716440D01*
Y1716708D01*
X1638744Y1716977D01*
X1639003Y1717207D01*
G01X1640708Y1719157D02*
Y1720153D01*
G01X1641741Y1722027D02*
X1638641D01*
Y1723483D01*
G01X1640139Y1722947D02*
Y1722027D01*
G01X1638641Y1725395D02*
Y1726315D01*
G01Y1725855D02*
X1641741D01*
G01Y1725395D02*
Y1726315D01*
G01X1638641Y1728955D02*
X1641741D01*
G01X1638641Y1728073D02*
Y1729837D01*
G01X1635834Y1716081D02*
Y1714547D01*
X1632734D01*
Y1716081D01*
G01X1634232Y1715467D02*
Y1714547D01*
G01X1635834Y1709862D02*
X1632734D01*
Y1711318D01*
G01X1634232Y1710782D02*
Y1709862D01*
G01X1634284Y1706096D02*
Y1706863D01*
X1635214D01*
X1635524Y1706633D01*
X1635731Y1706364D01*
X1635834Y1705981D01*
X1635731Y1705598D01*
X1635524Y1705329D01*
X1635214Y1705099D01*
X1634852Y1704946D01*
X1634439Y1704869D01*
X1634077D01*
X1633767Y1704946D01*
X1633406Y1705099D01*
X1633096Y1705329D01*
X1632889Y1705559D01*
X1632734Y1705866D01*
Y1706134D01*
X1632837Y1706441D01*
X1633044Y1706671D01*
G01X1635834Y1719196D02*
X1632734D01*
Y1719962D01*
X1632889Y1720269D01*
X1633096Y1720499D01*
X1633406Y1720691D01*
X1633767Y1720844D01*
X1634284Y1720882D01*
X1634801Y1720844D01*
X1635162Y1720691D01*
X1635472Y1720499D01*
X1635679Y1720269D01*
X1635834Y1719962D01*
Y1719196D01*
G01X1634181Y1729795D02*
X1634026Y1729948D01*
X1633767Y1730063D01*
X1633406Y1730140D01*
X1633096Y1730063D01*
X1632889Y1729910D01*
X1632734Y1729641D01*
Y1728606D01*
X1635834D01*
Y1729871D01*
X1635627Y1730140D01*
X1635317Y1730293D01*
X1634956Y1730370D01*
X1634594Y1730293D01*
X1634284Y1730063D01*
X1634181Y1729795D01*
Y1728606D01*
G01X1632992Y1725606D02*
X1632837Y1725376D01*
X1632734Y1725108D01*
Y1724801D01*
X1632889Y1724456D01*
X1633147Y1724188D01*
X1633457Y1723996D01*
X1633974Y1723843D01*
X1634439Y1723805D01*
X1634904Y1723881D01*
X1635214Y1723996D01*
X1635524Y1724226D01*
X1635731Y1724495D01*
X1635834Y1724763D01*
Y1725031D01*
X1635731Y1725300D01*
X1635576Y1725530D01*
X1635369Y1725721D01*
G01X1668631Y43779D02*
X1655431D01*
G01X1671000Y51142D02*
X1653500D01*
G01X1664000Y132000D02*
X1661000Y129000D01*
G01D02*
Y135000D01*
G01D02*
X1664000Y132000D01*
G01X1653425Y143361D02*
X1659625D01*
G01D02*
Y140163D01*
G01D02*
X1653425D01*
G01D02*
Y143361D01*
G01X1659625Y153362D02*
Y150162D01*
G01D02*
X1653425D01*
G01D02*
Y153362D01*
G01Y148362D02*
X1659625D01*
G01D02*
Y145162D01*
G01D02*
X1653425D01*
G01D02*
Y148362D01*
G01Y153362D02*
X1659625D01*
G01X1653425Y163362D02*
X1659625D01*
G01D02*
Y160162D01*
G01D02*
X1653425D01*
G01D02*
Y163362D01*
G01X1663528Y223072D02*
X1660328D01*
G01D02*
Y229272D01*
G01X1663600Y216400D02*
X1660400D01*
G01Y222600D02*
X1663600D01*
G01X1660400Y216400D02*
Y222600D01*
G01X1650310Y228387D02*
Y234587D01*
G01D02*
X1653510D01*
G01D02*
Y228387D01*
G01D02*
X1650310D01*
G01X1660328Y229272D02*
X1663528D01*
G01X1655412Y373170D02*
Y376270D01*
X1656332D01*
X1656639Y376115D01*
X1656869Y375753D01*
X1656946Y375340D01*
X1656869Y374927D01*
X1656677Y374617D01*
X1656332Y374462D01*
X1655412D01*
G01X1658436Y373170D02*
Y376270D01*
X1659202D01*
X1659509Y376115D01*
X1659739Y375908D01*
X1659931Y375598D01*
X1660084Y375237D01*
X1660122Y374720D01*
X1660084Y374203D01*
X1659931Y373842D01*
X1659739Y373532D01*
X1659509Y373325D01*
X1659202Y373170D01*
X1658436D01*
G01X1662379D02*
Y376270D01*
X1661919Y375650D01*
G01Y373170D02*
X1662839D01*
G01X1665479Y376270D02*
X1665172Y376167D01*
X1664942Y375908D01*
X1664789Y375598D01*
X1664674Y375185D01*
X1664636Y374720D01*
X1664674Y374255D01*
X1664789Y373842D01*
X1664942Y373532D01*
X1665172Y373273D01*
X1665479Y373170D01*
X1665786Y373273D01*
X1666016Y373532D01*
X1666169Y373842D01*
X1666284Y374255D01*
X1666322Y374720D01*
X1666284Y375185D01*
X1666169Y375598D01*
X1666016Y375908D01*
X1665786Y376167D01*
X1665479Y376270D01*
G01X1667736Y373790D02*
X1667966Y373428D01*
X1668272Y373222D01*
X1668617Y373170D01*
X1668924Y373222D01*
X1669231Y373480D01*
X1669422Y373790D01*
X1669461Y374100D01*
X1669384Y374462D01*
X1669116Y374720D01*
X1668847Y374823D01*
X1668502D01*
G01X1668847D02*
X1669077Y374978D01*
X1669269Y375237D01*
X1669346Y375547D01*
X1669269Y375857D01*
X1669077Y376115D01*
X1668732Y376270D01*
X1668387Y376218D01*
X1668042Y376012D01*
G01X1680046Y379850D02*
X1650487D01*
G01D02*
Y391346D01*
G01X1661210Y401802D02*
Y395602D01*
G01D02*
X1658010D01*
G01D02*
Y401802D01*
G01D02*
X1661210D01*
G01X1651010Y395602D02*
Y401802D01*
G01D02*
X1654210D01*
G01D02*
Y395602D01*
G01D02*
X1651010D01*
G01X1650487Y391346D02*
X1680046D01*
G01X1649210Y415802D02*
Y412602D01*
G01X1660491Y420089D02*
Y408315D01*
G01D02*
X1650729D01*
G01D02*
Y420089D01*
G01X1648110Y433144D02*
Y426944D01*
G01X1659510Y427102D02*
Y433302D01*
G01D02*
X1662710D01*
G01Y427102D02*
X1659510D01*
G01X1655390Y433144D02*
Y426944D01*
G01D02*
X1652190D01*
G01D02*
Y433144D01*
G01D02*
X1655390D01*
G01X1655945D02*
X1659145D01*
G01X1655945Y426944D02*
Y433144D01*
G01X1659145Y426944D02*
X1655945D01*
G01X1659145Y433144D02*
Y426944D01*
G01X1651635Y433144D02*
Y426944D01*
X1648435D01*
Y433144D01*
X1651635D01*
G01X1650729Y420089D02*
X1660491D01*
G01X1647455Y571933D02*
Y615933D01*
G01X1657383Y588500D02*
Y591600D01*
X1658303D01*
X1658610Y591445D01*
X1658840Y591083D01*
X1658917Y590670D01*
X1658840Y590257D01*
X1658648Y589947D01*
X1658303Y589792D01*
X1657383D01*
G01X1662093Y591342D02*
X1661863Y591497D01*
X1661595Y591600D01*
X1661288D01*
X1660943Y591445D01*
X1660675Y591187D01*
X1660483Y590877D01*
X1660330Y590360D01*
X1660292Y589895D01*
X1660368Y589430D01*
X1660483Y589120D01*
X1660713Y588810D01*
X1660982Y588603D01*
X1661250Y588500D01*
X1661518D01*
X1661787Y588603D01*
X1662017Y588758D01*
X1662208Y588965D01*
G01X1664350Y588500D02*
Y591600D01*
X1663890Y590980D01*
G01Y588500D02*
X1664810D01*
G01X1667450D02*
X1667718Y588552D01*
X1668025Y588707D01*
X1668217Y588965D01*
X1668293Y589327D01*
X1668217Y589688D01*
X1667987Y589998D01*
X1667642Y590153D01*
X1667258D01*
X1667028Y590257D01*
X1666837Y590515D01*
X1666760Y590877D01*
X1666875Y591238D01*
X1667143Y591497D01*
X1667450Y591600D01*
X1667757Y591497D01*
X1668025Y591238D01*
X1668140Y590877D01*
X1668063Y590515D01*
X1667872Y590257D01*
X1667642Y590153D01*
X1667258D01*
X1666913Y589998D01*
X1666683Y589688D01*
X1666607Y589327D01*
X1666683Y588965D01*
X1666875Y588707D01*
X1667182Y588552D01*
X1667450Y588500D01*
G01X1671010D02*
Y591600D01*
X1669592Y589378D01*
X1671508D01*
G01X1672807Y588965D02*
X1673037Y588707D01*
X1673305Y588552D01*
X1673650Y588500D01*
X1673995Y588603D01*
X1674263Y588810D01*
X1674455Y589172D01*
X1674493Y589585D01*
X1674417Y589998D01*
X1674225Y590257D01*
X1673957Y590463D01*
X1673688Y590515D01*
X1673420Y590463D01*
X1673075Y590257D01*
X1673190Y591600D01*
X1674225D01*
G01X1653528Y596876D02*
X1656528Y593876D01*
G01X1653528Y601003D02*
Y596876D01*
G01X1656528Y593876D02*
X1675182D01*
G01X1653528Y612530D02*
Y608403D01*
G01X1656528Y615530D02*
X1653528Y612530D01*
G01X1647288Y628806D02*
Y625606D01*
G01X1651579Y623646D02*
Y617446D01*
G01D02*
X1648379D01*
G01D02*
Y623646D01*
G01D02*
X1651579D01*
G01X1655747Y623598D02*
Y617398D01*
G01D02*
X1652547D01*
G01D02*
Y623598D01*
G01D02*
X1655747D01*
G01X1675182Y615530D02*
X1656528D01*
G01X1648107Y637362D02*
Y631162D01*
G01Y647862D02*
Y641662D01*
G01X1649650Y658183D02*
Y654983D01*
G01X1648084Y654683D02*
Y648483D01*
G01X1655327Y661344D02*
X1651332D01*
G01D02*
Y686934D01*
G01X1647807Y703091D02*
Y659783D01*
G01X1651332Y686934D02*
X1655327D01*
G01X1648473Y687244D02*
Y1293000D01*
G01X1653559Y697347D02*
Y691147D01*
G01D02*
X1650359D01*
G01D02*
Y697347D01*
G01D02*
X1653559D01*
G01X1655066Y697918D02*
X1661266D01*
G01D02*
Y694718D01*
G01D02*
X1655066D01*
G01D02*
Y697918D01*
G01X1661248Y690728D02*
X1655048D01*
G01D02*
Y693928D01*
G01D02*
X1661248D01*
G01D02*
Y690728D01*
G01X1674063Y720709D02*
X1648473D01*
G01X1674063Y1291575D02*
X1648473D01*
G01X1659572Y1298763D02*
X1666699D01*
G01X1648473Y1325040D02*
X1651000D01*
G01X1661000D02*
X1674063D01*
G01X1648473Y1323500D02*
Y1325040D01*
G01X1652733Y1327881D02*
Y1367251D01*
G01X1659075Y1327881D02*
X1652733D01*
G01X1663699Y1320417D02*
X1659572D01*
G01X1652172D02*
X1648045D01*
G01X1650500Y1356383D02*
X1647400D01*
Y1357303D01*
X1647555Y1357610D01*
X1647917Y1357840D01*
X1648330Y1357917D01*
X1648743Y1357840D01*
X1649053Y1357648D01*
X1649208Y1357303D01*
Y1356383D01*
G01X1647400Y1359483D02*
X1650500D01*
Y1361017D01*
G01X1647917Y1362622D02*
X1647607Y1362852D01*
X1647452Y1363120D01*
X1647400Y1363427D01*
X1647503Y1363810D01*
X1647762Y1364078D01*
X1648072Y1364155D01*
X1648382Y1364117D01*
X1648640Y1363963D01*
X1649157Y1363197D01*
X1649518Y1362852D01*
X1650035Y1362622D01*
X1650500Y1362545D01*
Y1364155D01*
G01X1649880Y1365607D02*
X1650242Y1365837D01*
X1650448Y1366143D01*
X1650500Y1366488D01*
X1650448Y1366795D01*
X1650190Y1367102D01*
X1649880Y1367293D01*
X1649570Y1367332D01*
X1649208Y1367255D01*
X1648950Y1366987D01*
X1648847Y1366718D01*
Y1366373D01*
G01Y1366718D02*
X1648692Y1366948D01*
X1648433Y1367140D01*
X1648123Y1367217D01*
X1647813Y1367140D01*
X1647555Y1366948D01*
X1647400Y1366603D01*
X1647452Y1366258D01*
X1647658Y1365913D01*
G01X1656447Y1372114D02*
Y1368914D01*
G01X1650247Y1372114D02*
X1656447D01*
G01X1650247Y1368914D02*
Y1372114D01*
G01X1656447Y1368914D02*
X1650247D01*
G01X1655013Y1372414D02*
X1651813D01*
G01X1655013Y1378614D02*
Y1372414D01*
G01X1651813D02*
Y1378614D01*
G01X1652733Y1367251D02*
X1659075D01*
G01X1658047Y1370531D02*
Y1373131D01*
G01X1658840Y1370531D02*
X1658047D01*
G01X1651790Y1385435D02*
X1654990D01*
G01X1651790Y1379235D02*
Y1385435D01*
G01X1654990Y1379235D02*
X1651790D01*
G01X1654990Y1385435D02*
Y1379235D01*
G01X1651813Y1378614D02*
X1655013D01*
G01X1658047Y1379742D02*
Y1381440D01*
G01X1658884Y1398366D02*
X1655684D01*
G01X1658884Y1404566D02*
Y1398366D01*
G01X1655684D02*
Y1404566D01*
G01X1654990Y1389735D02*
X1651790D01*
G01X1654990Y1395935D02*
Y1394300D01*
G01X1651790Y1395935D02*
X1654990D01*
G01X1651790Y1389735D02*
Y1395935D01*
G01X1654990Y1392100D02*
Y1389735D01*
G01X1650797Y1389668D02*
X1647597D01*
G01X1650797Y1395868D02*
Y1389668D01*
G01X1647597Y1395868D02*
X1650797D01*
G01X1647597Y1389668D02*
Y1395868D01*
G01X1659654Y1401260D02*
Y1404460D01*
G01X1665854Y1401260D02*
X1659654D01*
G01X1658047Y1394153D02*
X1659055D01*
G01X1658047Y1392299D02*
Y1394153D01*
G01X1655684Y1404566D02*
X1658884D01*
G01X1647424Y1411321D02*
X1650624D01*
G01X1647424Y1405121D02*
Y1411321D01*
G01X1650624Y1405121D02*
X1647424D01*
G01X1650624Y1411321D02*
Y1405121D01*
G01X1659654Y1404460D02*
X1665854D01*
G01X1651424Y1411321D02*
X1654624D01*
G01X1651424Y1405121D02*
Y1411321D01*
G01X1654624Y1405121D02*
X1651424D01*
G01X1654624Y1411321D02*
Y1405121D01*
G01X1655224Y1411321D02*
X1658424D01*
G01X1655224Y1405121D02*
Y1411321D01*
G01X1658424Y1405121D02*
X1655224D01*
G01X1658424Y1411321D02*
Y1405121D01*
G01X1659024Y1411321D02*
X1662224D01*
G01X1659024Y1405121D02*
Y1411321D01*
G01X1662224Y1405121D02*
X1659024D01*
G01X1660770Y1413974D02*
X1660610Y1414266D01*
X1660396Y1414432D01*
X1660156Y1414474D01*
X1659943Y1414432D01*
X1659730Y1414224D01*
X1659596Y1413974D01*
X1659570Y1413724D01*
X1659623Y1413432D01*
X1659810Y1413224D01*
X1659996Y1413141D01*
X1660236D01*
G01X1659996D02*
X1659836Y1413016D01*
X1659703Y1412807D01*
X1659650Y1412557D01*
X1659703Y1412307D01*
X1659836Y1412099D01*
X1660076Y1411974D01*
X1660316Y1412016D01*
X1660556Y1412182D01*
G01X1657983Y1411974D02*
X1658196Y1412057D01*
X1658356Y1412266D01*
X1658463Y1412516D01*
X1658543Y1412849D01*
X1658570Y1413224D01*
X1658543Y1413599D01*
X1658463Y1413932D01*
X1658356Y1414182D01*
X1658196Y1414391D01*
X1657983Y1414474D01*
X1657770Y1414391D01*
X1657610Y1414182D01*
X1657503Y1413932D01*
X1657423Y1413599D01*
X1657396Y1413224D01*
X1657423Y1412849D01*
X1657503Y1412516D01*
X1657610Y1412266D01*
X1657770Y1412057D01*
X1657983Y1411974D01*
G01X1659126Y1415698D02*
X1657220D01*
G01X1659126Y1417604D02*
Y1415698D01*
G01X1656283Y1414241D02*
Y1411241D01*
G01X1648483Y1414191D02*
Y1412691D01*
G01X1661150Y1421458D02*
X1660858Y1421298D01*
X1660692Y1421084D01*
X1660650Y1420844D01*
X1660692Y1420631D01*
X1660900Y1420418D01*
X1661150Y1420284D01*
X1661400Y1420258D01*
X1661692Y1420311D01*
X1661900Y1420498D01*
X1661983Y1420684D01*
Y1420924D01*
G01Y1420684D02*
X1662108Y1420524D01*
X1662317Y1420391D01*
X1662567Y1420338D01*
X1662817Y1420391D01*
X1663025Y1420524D01*
X1663150Y1420764D01*
X1663108Y1421004D01*
X1662942Y1421244D01*
G01X1660650Y1418671D02*
X1663150D01*
X1662650Y1418991D01*
G01X1660650D02*
Y1418351D01*
G01X1660583Y1432641D02*
X1663583D01*
G01X1662033Y1424841D02*
X1660533D01*
G01X1655267Y1438641D02*
X1652067D01*
G01X1655267Y1444841D02*
Y1438641D01*
G01X1652067Y1444841D02*
X1655267D01*
G01X1652067Y1438641D02*
Y1444841D01*
G01X1659767Y1438641D02*
X1656567D01*
G01X1659767Y1444841D02*
Y1438641D01*
G01X1656567Y1444841D02*
X1659767D01*
G01X1656567Y1438641D02*
Y1444841D01*
G01X1664065Y1437074D02*
X1660865D01*
G01Y1443274D02*
X1664065D01*
G01X1660865Y1437074D02*
Y1443274D01*
G01X1651277Y1442088D02*
Y1438888D01*
G01X1651642Y1446350D02*
Y1449450D01*
X1652562D01*
X1652869Y1449295D01*
X1653099Y1448933D01*
X1653176Y1448520D01*
X1653099Y1448107D01*
X1652907Y1447797D01*
X1652562Y1447642D01*
X1651642D01*
G01X1654666Y1449450D02*
Y1447228D01*
X1654819Y1446763D01*
X1655126Y1446453D01*
X1655509Y1446350D01*
X1655892Y1446453D01*
X1656199Y1446763D01*
X1656352Y1447228D01*
Y1449450D01*
G01X1657881Y1448933D02*
X1658111Y1449243D01*
X1658379Y1449398D01*
X1658686Y1449450D01*
X1659069Y1449347D01*
X1659337Y1449088D01*
X1659414Y1448778D01*
X1659376Y1448468D01*
X1659222Y1448210D01*
X1658456Y1447693D01*
X1658111Y1447332D01*
X1657881Y1446815D01*
X1657804Y1446350D01*
X1659414D01*
G01X1661709D02*
Y1449450D01*
X1661249Y1448830D01*
G01Y1446350D02*
X1662169D01*
G01X1657220Y1435384D02*
X1659126D01*
G01D02*
Y1433478D01*
G01X1649983Y1438391D02*
Y1436891D01*
G01X1659492Y1450760D02*
X1656292D01*
G01X1659492Y1456960D02*
Y1450760D01*
G01X1656292Y1456960D02*
X1659492D01*
G01X1656292Y1450760D02*
Y1456960D01*
G01X1655214Y1450739D02*
X1652014D01*
G01X1655214Y1456939D02*
Y1450739D01*
G01X1652014Y1456939D02*
X1655214D01*
G01X1652014Y1450739D02*
Y1456939D01*
G01X1667306Y1540451D02*
X1660300D01*
G01Y1575491D02*
X1667306D01*
G01X1648516Y1656628D02*
X1648708Y1656318D01*
X1648938Y1656111D01*
X1649206Y1656008D01*
X1649513Y1656111D01*
X1649743Y1656318D01*
X1649973Y1656628D01*
X1650050Y1657041D01*
Y1659108D01*
G01X1652383Y1656008D02*
Y1659108D01*
X1651923Y1658488D01*
G01Y1656008D02*
X1652843D01*
G01X1655483Y1659108D02*
X1655176Y1659005D01*
X1654946Y1658746D01*
X1654793Y1658436D01*
X1654678Y1658023D01*
X1654640Y1657558D01*
X1654678Y1657093D01*
X1654793Y1656680D01*
X1654946Y1656370D01*
X1655176Y1656111D01*
X1655483Y1656008D01*
X1655790Y1656111D01*
X1656020Y1656370D01*
X1656173Y1656680D01*
X1656288Y1657093D01*
X1656326Y1657558D01*
X1656288Y1658023D01*
X1656173Y1658436D01*
X1656020Y1658746D01*
X1655790Y1659005D01*
X1655483Y1659108D01*
G01X1657740Y1656473D02*
X1657970Y1656215D01*
X1658238Y1656060D01*
X1658583Y1656008D01*
X1658928Y1656111D01*
X1659196Y1656318D01*
X1659388Y1656680D01*
X1659426Y1657093D01*
X1659350Y1657506D01*
X1659158Y1657765D01*
X1658890Y1657971D01*
X1658621Y1658023D01*
X1658353Y1657971D01*
X1658008Y1657765D01*
X1658123Y1659108D01*
X1659158D01*
G01X1648758Y1678963D02*
X1668444D01*
G01X1648758Y1693363D02*
Y1678963D01*
G01X1668444Y1693363D02*
X1648758D01*
G01X1656113Y1713284D02*
Y1707084D01*
G01D02*
X1652913D01*
G01D02*
Y1713284D01*
G01D02*
X1656113D01*
G01X1656913Y1710234D02*
Y1716434D01*
G01X1660113Y1710234D02*
X1656913D01*
G01X1660113Y1716434D02*
Y1710234D01*
G01X1652913Y1714084D02*
Y1720284D01*
G01X1656113Y1714084D02*
X1652913D01*
G01X1656113Y1720284D02*
Y1714084D01*
G01X1652113Y1707084D02*
X1648913D01*
G01X1652113Y1713284D02*
Y1707084D01*
G01X1648913Y1713284D02*
X1652113D01*
G01X1648913Y1707084D02*
Y1713284D01*
G01X1652113Y1714084D02*
X1648913D01*
G01X1652113Y1720284D02*
Y1714084D01*
G01X1648913D02*
Y1720284D01*
G01X1661513Y1709987D02*
Y1718649D01*
G01X1672007Y1709987D02*
X1661513D01*
G01X1656113Y1728434D02*
Y1722234D01*
G01D02*
X1652913D01*
G01D02*
Y1728434D01*
G01D02*
X1656113D01*
G01X1656913Y1716434D02*
X1660113D01*
G01X1656113Y1735434D02*
Y1729234D01*
G01D02*
X1652913D01*
G01D02*
Y1735434D01*
G01X1648913Y1722234D02*
Y1728434D01*
G01D02*
X1652113D01*
G01D02*
Y1722234D01*
G01D02*
X1648913D01*
G01Y1729234D02*
Y1735434D01*
G01X1652113D02*
Y1729234D01*
G01D02*
X1648913D01*
G01X1652913Y1720284D02*
X1656113D01*
G01X1648913D02*
X1652113D01*
G01X1672007Y1725137D02*
X1661513D01*
G01D02*
Y1733799D01*
G01X1662310Y1719885D02*
X1662003Y1719937D01*
X1661735Y1720143D01*
X1661505Y1720453D01*
X1661352Y1720815D01*
X1661275Y1721228D01*
Y1721642D01*
X1661352Y1722055D01*
X1661505Y1722417D01*
X1661735Y1722727D01*
X1662003Y1722933D01*
X1662310Y1722985D01*
X1662617Y1722933D01*
X1662885Y1722727D01*
X1663115Y1722417D01*
X1663268Y1722055D01*
X1663345Y1721642D01*
Y1721228D01*
X1663268Y1720815D01*
X1663115Y1720453D01*
X1662885Y1720143D01*
X1662617Y1719937D01*
X1662310Y1719885D01*
G01X1662617Y1720712D02*
X1663077Y1719885D01*
G01X1665410D02*
Y1722985D01*
X1664950Y1722365D01*
G01Y1719885D02*
X1665870D01*
G01X1667667Y1720505D02*
X1667897Y1720143D01*
X1668203Y1719937D01*
X1668548Y1719885D01*
X1668855Y1719937D01*
X1669162Y1720195D01*
X1669353Y1720505D01*
X1669392Y1720815D01*
X1669315Y1721177D01*
X1669047Y1721435D01*
X1668778Y1721538D01*
X1668433D01*
G01X1668778D02*
X1669008Y1721693D01*
X1669200Y1721952D01*
X1669277Y1722262D01*
X1669200Y1722572D01*
X1669008Y1722830D01*
X1668663Y1722985D01*
X1668318Y1722933D01*
X1667973Y1722727D01*
G01X1670767Y1720350D02*
X1670997Y1720092D01*
X1671265Y1719937D01*
X1671610Y1719885D01*
X1671955Y1719988D01*
X1672223Y1720195D01*
X1672415Y1720557D01*
X1672453Y1720970D01*
X1672377Y1721383D01*
X1672185Y1721642D01*
X1671917Y1721848D01*
X1671648Y1721900D01*
X1671380Y1721848D01*
X1671035Y1721642D01*
X1671150Y1722985D01*
X1672185D01*
G01X1661513Y1718649D02*
X1664860D01*
G01X1652913Y1735434D02*
X1656113D01*
G01X1648913D02*
X1652113D01*
G01X1663031Y1735442D02*
X1662724Y1735494D01*
X1662456Y1735700D01*
X1662226Y1736010D01*
X1662073Y1736372D01*
X1661996Y1736785D01*
Y1737199D01*
X1662073Y1737612D01*
X1662226Y1737974D01*
X1662456Y1738284D01*
X1662724Y1738490D01*
X1663031Y1738542D01*
X1663338Y1738490D01*
X1663606Y1738284D01*
X1663836Y1737974D01*
X1663989Y1737612D01*
X1664066Y1737199D01*
Y1736785D01*
X1663989Y1736372D01*
X1663836Y1736010D01*
X1663606Y1735700D01*
X1663338Y1735494D01*
X1663031Y1735442D01*
G01X1663338Y1736269D02*
X1663798Y1735442D01*
G01X1665403Y1736734D02*
X1665671Y1737095D01*
X1665901Y1737302D01*
X1666208Y1737405D01*
X1666476Y1737302D01*
X1666668Y1737095D01*
X1666821Y1736785D01*
X1666859Y1736424D01*
X1666821Y1736114D01*
X1666668Y1735804D01*
X1666438Y1735545D01*
X1666169Y1735442D01*
X1665863Y1735545D01*
X1665594Y1735855D01*
X1665441Y1736320D01*
X1665403Y1736837D01*
X1665479Y1737509D01*
X1665594Y1737870D01*
X1665786Y1738232D01*
X1666054Y1738490D01*
X1666323Y1738542D01*
X1666591Y1738439D01*
X1666783Y1738180D01*
G01X1668579Y1735804D02*
X1668848Y1735545D01*
X1669154Y1735442D01*
X1669461Y1735545D01*
X1669729Y1735855D01*
X1669921Y1736320D01*
X1669998Y1736785D01*
Y1737354D01*
X1669921Y1737819D01*
X1669729Y1738232D01*
X1669499Y1738439D01*
X1669231Y1738542D01*
X1668924Y1738439D01*
X1668694Y1738232D01*
X1668541Y1737922D01*
X1668464Y1737509D01*
X1668541Y1737147D01*
X1668733Y1736785D01*
X1668963Y1736579D01*
X1669231Y1736527D01*
X1669538Y1736630D01*
X1669768Y1736889D01*
X1669998Y1737354D01*
G01X1661513Y1733799D02*
X1664860D01*
G01X1678000Y51142D02*
X1675000D01*
G01X1676700Y122162D02*
Y120162D01*
X1691700D01*
Y122162D01*
X1676700D01*
G01X1684100Y168262D02*
X1679679Y171683D01*
X1675143D01*
Y116841D01*
X1693057D01*
Y171683D01*
X1688521D01*
X1684100Y168262D01*
G01X1676700Y127162D02*
Y125162D01*
X1691700D01*
Y127162D01*
X1676700D01*
G01Y132162D02*
Y130162D01*
X1691700D01*
Y132162D01*
X1676700D01*
G01Y137162D02*
Y135162D01*
X1691700D01*
Y137162D01*
X1676700D01*
G01Y142162D02*
Y140162D01*
X1691700D01*
Y142162D01*
X1676700D01*
G01Y147162D02*
Y145162D01*
X1691700D01*
Y147162D01*
X1676700D01*
G01Y152162D02*
Y150162D01*
X1691700D01*
Y152162D01*
X1676700D01*
G01Y157162D02*
Y155162D01*
X1691700D01*
Y157162D01*
X1676700D01*
G01Y162162D02*
Y160162D01*
X1691700D01*
Y162162D01*
X1676700D01*
G01Y167162D02*
Y165162D01*
X1691700D01*
Y167162D01*
X1676700D01*
G01X1675495Y172942D02*
X1675802Y172684D01*
X1676147Y172529D01*
X1676453D01*
X1676760Y172684D01*
X1676990Y172942D01*
X1677105Y173304D01*
X1677028Y173666D01*
X1676837Y173976D01*
X1676492Y174182D01*
X1676032Y174286D01*
X1675763Y174492D01*
X1675648Y174854D01*
X1675725Y175216D01*
X1675917Y175474D01*
X1676185Y175629D01*
X1676453D01*
X1676722Y175526D01*
X1676952Y175267D01*
G01X1678250Y175629D02*
X1678787Y172529D01*
X1679400Y175629D01*
X1680013Y172529D01*
X1680550Y175629D01*
G01X1682500Y172529D02*
Y175629D01*
X1682040Y175009D01*
G01Y172529D02*
X1682960D01*
G01X1665335Y204285D02*
X1677809D01*
G01X1665335Y216097D02*
Y204285D01*
G01X1663528Y229272D02*
Y223072D01*
G01X1663600Y222600D02*
Y216400D01*
G01X1681535Y218097D02*
X1665335D01*
G01D02*
Y231097D01*
G01X1677809Y216097D02*
X1665335D01*
G01X1665742Y235664D02*
Y233442D01*
X1665895Y232977D01*
X1666202Y232667D01*
X1666585Y232564D01*
X1666968Y232667D01*
X1667275Y232977D01*
X1667428Y233442D01*
Y235664D01*
G01X1669685Y232564D02*
Y235664D01*
X1669225Y235044D01*
G01Y232564D02*
X1670145D01*
G01X1672057Y235147D02*
X1672287Y235457D01*
X1672555Y235612D01*
X1672862Y235664D01*
X1673245Y235561D01*
X1673513Y235302D01*
X1673590Y234992D01*
X1673552Y234682D01*
X1673398Y234424D01*
X1672632Y233907D01*
X1672287Y233546D01*
X1672057Y233029D01*
X1671980Y232564D01*
X1673590D01*
G01X1676345D02*
Y235664D01*
X1674927Y233442D01*
X1676843D01*
G01X1665335Y231097D02*
X1671935D01*
G01D02*
X1673435Y228597D01*
G01D02*
X1674935Y231097D01*
G01D02*
X1681535D01*
G01X1680056Y377418D02*
X1677630D01*
G01X1665210Y401802D02*
Y395602D01*
G01D02*
X1662010D01*
G01D02*
Y401802D01*
G01D02*
X1665210D01*
G01X1670570Y423832D02*
Y411832D01*
G01D02*
X1664570D01*
G01D02*
Y423832D01*
G01X1662710Y433302D02*
Y427102D01*
G01X1672272Y426545D02*
Y432745D01*
G01D02*
X1675472D01*
G01D02*
Y426545D01*
G01D02*
X1672272D01*
G01X1664570Y423832D02*
X1670570D01*
G01X1682850Y425672D02*
X1676850D01*
G01D02*
Y437672D01*
G01D02*
X1682850D01*
G01X1675182Y593876D02*
Y601003D01*
G01Y608403D02*
Y615530D01*
G01X1673835Y626172D02*
Y629272D01*
G01X1675445D02*
Y626172D01*
G01Y627722D02*
X1673835D01*
G01X1676897Y626637D02*
X1677127Y626379D01*
X1677395Y626224D01*
X1677740Y626172D01*
X1678085Y626275D01*
X1678353Y626482D01*
X1678545Y626844D01*
X1678583Y627257D01*
X1678507Y627670D01*
X1678315Y627929D01*
X1678047Y628135D01*
X1677778Y628187D01*
X1677510Y628135D01*
X1677165Y627929D01*
X1677280Y629272D01*
X1678315D01*
G01X1679997Y626792D02*
X1680227Y626430D01*
X1680533Y626224D01*
X1680878Y626172D01*
X1681185Y626224D01*
X1681492Y626482D01*
X1681683Y626792D01*
X1681722Y627102D01*
X1681645Y627464D01*
X1681377Y627722D01*
X1681108Y627825D01*
X1680763D01*
G01X1681108D02*
X1681338Y627980D01*
X1681530Y628239D01*
X1681607Y628549D01*
X1681530Y628859D01*
X1681338Y629117D01*
X1680993Y629272D01*
X1680648Y629220D01*
X1680303Y629014D01*
G01X1676922Y661344D02*
X1672927D01*
G01X1675000Y686934D02*
X1676922D01*
G01X1674063Y1293000D02*
Y689000D01*
G01X1666699Y1298763D02*
Y1317417D01*
G01X1669045Y1298763D02*
X1676172D01*
G01X1669045Y1317417D02*
Y1298763D01*
G01X1683047Y1327881D02*
X1676705D01*
G01X1666699Y1317417D02*
X1663699Y1320417D01*
G01X1672045D02*
X1669045Y1317417D01*
G01X1676172Y1320417D02*
X1672045D01*
G01X1676705Y1367251D02*
X1683047D01*
G01X1673321Y1397366D02*
Y1403566D01*
G01X1676521Y1397366D02*
X1673321D01*
G01X1676521Y1403566D02*
Y1397366D01*
G01X1672479D02*
X1669279D01*
G01X1672479Y1403566D02*
Y1397366D01*
G01X1669279D02*
Y1403566D01*
G01X1665854Y1404460D02*
Y1401260D01*
G01X1673321Y1403566D02*
X1676521D01*
G01X1669279D02*
X1672479D01*
G01X1666824Y1411321D02*
X1670024D01*
G01X1666824Y1405121D02*
Y1411321D01*
G01X1670024Y1405121D02*
X1666824D01*
G01X1670024Y1411321D02*
Y1405121D01*
G01X1670910Y1418278D02*
Y1415078D01*
G01X1664710D02*
Y1418278D01*
G01X1670910Y1415078D02*
X1664710D01*
G01X1662224Y1411321D02*
Y1405121D01*
G01X1662824Y1411321D02*
X1666024D01*
G01X1662824Y1405121D02*
Y1411321D01*
G01X1666024Y1405121D02*
X1662824D01*
G01X1666024Y1411321D02*
Y1405121D01*
G01X1682758Y1408694D02*
X1670758D01*
G01Y1414694D02*
X1682758D01*
G01X1670758Y1408694D02*
Y1414694D01*
G01X1664656Y1430615D02*
Y1433815D01*
G01X1670856Y1430615D02*
X1664656D01*
G01X1670856Y1433815D02*
Y1430615D01*
G01X1664690Y1426745D02*
Y1429945D01*
G01X1670890Y1426745D02*
X1664690D01*
G01X1670890Y1429945D02*
Y1426745D01*
G01X1664690Y1429945D02*
X1670890D01*
G01X1664724Y1422883D02*
Y1426083D01*
G01X1670924Y1422883D02*
X1664724D01*
G01X1670924Y1426083D02*
Y1422883D01*
G01X1664724Y1426083D02*
X1670924D01*
G01X1664742Y1418967D02*
Y1422167D01*
G01X1670942Y1418967D02*
X1664742D01*
G01X1670942Y1422167D02*
Y1418967D01*
G01X1664742Y1422167D02*
X1670942D01*
G01X1664710Y1418278D02*
X1670910D01*
G01X1671850Y1435021D02*
X1674350D01*
X1672558Y1436008D01*
Y1434674D01*
G01X1674350Y1433141D02*
X1674267Y1433354D01*
X1674058Y1433514D01*
X1673808Y1433621D01*
X1673475Y1433701D01*
X1673100Y1433728D01*
X1672725Y1433701D01*
X1672392Y1433621D01*
X1672142Y1433514D01*
X1671933Y1433354D01*
X1671850Y1433141D01*
X1671933Y1432928D01*
X1672142Y1432768D01*
X1672392Y1432661D01*
X1672725Y1432581D01*
X1673100Y1432554D01*
X1673475Y1432581D01*
X1673808Y1432661D01*
X1674058Y1432768D01*
X1674267Y1432928D01*
X1674350Y1433141D01*
G01X1664065Y1443274D02*
Y1437074D01*
G01X1664656Y1433815D02*
X1670856D01*
G01X1667890Y1437107D02*
X1664690D01*
G01X1667890Y1443307D02*
Y1437107D01*
G01X1664690Y1443307D02*
X1667890D01*
G01X1664690Y1437107D02*
Y1443307D01*
G01X1671747Y1437049D02*
X1668547D01*
G01X1671747Y1443249D02*
Y1437049D01*
G01X1668547Y1443249D02*
X1671747D01*
G01X1668547Y1437049D02*
Y1443249D01*
G01X1672074Y1551200D02*
Y1557200D01*
G01X1684074Y1551200D02*
X1672074D01*
G01X1672034Y1544000D02*
Y1550400D01*
G01D02*
X1684914D01*
G01Y1544000D02*
X1672034D01*
G01X1667306Y1575491D02*
Y1540451D01*
G01X1672007Y1566745D02*
Y1572745D01*
G01X1684007Y1566745D02*
X1672007D01*
G01X1672074Y1557200D02*
X1684074D01*
G01X1672106Y1558900D02*
Y1565100D01*
X1675306D01*
Y1558900D01*
X1672106D01*
G01X1682114Y1558026D02*
X1675914D01*
Y1561226D01*
X1682114D01*
Y1558026D01*
G01Y1561926D02*
X1675914D01*
Y1565126D01*
X1682114D01*
Y1561926D01*
G01X1672007Y1579599D02*
X1684007D01*
G01X1672007Y1573599D02*
Y1579599D01*
G01X1684007Y1573599D02*
X1672007D01*
G01Y1572745D02*
X1684007D01*
G01X1669006Y1680435D02*
X1671228D01*
X1671693Y1680588D01*
X1672003Y1680895D01*
X1672106Y1681278D01*
X1672003Y1681661D01*
X1671693Y1681968D01*
X1671228Y1682121D01*
X1669006D01*
G01X1672106Y1684378D02*
X1669006D01*
X1669626Y1683918D01*
G01X1672106D02*
Y1684838D01*
G01X1670814Y1686750D02*
X1670453Y1687018D01*
X1670246Y1687248D01*
X1670143Y1687555D01*
X1670246Y1687823D01*
X1670453Y1688015D01*
X1670763Y1688168D01*
X1671124Y1688206D01*
X1671434Y1688168D01*
X1671744Y1688015D01*
X1672003Y1687785D01*
X1672106Y1687516D01*
X1672003Y1687210D01*
X1671693Y1686941D01*
X1671228Y1686788D01*
X1670711Y1686750D01*
X1670039Y1686826D01*
X1669678Y1686941D01*
X1669316Y1687133D01*
X1669058Y1687401D01*
X1669006Y1687670D01*
X1669109Y1687938D01*
X1669368Y1688130D01*
G01X1668444Y1681920D02*
X1664201Y1686163D01*
G01X1668444Y1678963D02*
Y1681920D01*
G01X1664201Y1686163D02*
X1668444Y1690406D01*
G01D02*
Y1693363D01*
G01X1676960Y1707402D02*
X1673760D01*
G01Y1713602D02*
X1676960D01*
G01X1673760Y1707402D02*
Y1713602D01*
G01X1672007Y1718649D02*
Y1709987D01*
G01X1673760Y1722152D02*
Y1728352D01*
G01D02*
X1676960D01*
G01Y1722152D02*
X1673760D01*
G01X1672007Y1733799D02*
Y1725137D01*
G01X1668660Y1718649D02*
X1672007D01*
G01X1666760Y1716449D02*
X1668660Y1718649D01*
G01X1664860D02*
X1666760Y1716449D01*
G01X1664860Y1733799D02*
X1666760Y1731599D01*
G01D02*
X1668660Y1733799D01*
G01D02*
X1672007D01*
G01X1693500Y51142D02*
X1691500D01*
G01X1686000D02*
X1683500D01*
G01X1684200Y122162D02*
Y120162D01*
G01Y127162D02*
Y125162D01*
G01Y132162D02*
Y130162D01*
G01Y137162D02*
Y135162D01*
G01Y142162D02*
Y140162D01*
G01Y147162D02*
Y145162D01*
G01Y152162D02*
Y150162D01*
G01Y157162D02*
Y155162D01*
G01Y162162D02*
Y160162D01*
G01Y167162D02*
Y165162D01*
G01X1714670Y203533D02*
G02I-13385J0D01*
G01X1714671D02*
X1687899D01*
G01X1677465Y199106D02*
Y202206D01*
X1678231D01*
X1678538Y202051D01*
X1678768Y201844D01*
X1678960Y201534D01*
X1679113Y201173D01*
X1679151Y200656D01*
X1679113Y200139D01*
X1678960Y199778D01*
X1678768Y199468D01*
X1678538Y199261D01*
X1678231Y199106D01*
X1677465D01*
G01X1681408D02*
Y202206D01*
X1680948Y201586D01*
G01Y199106D02*
X1681868D01*
G01X1677809Y204285D02*
Y216097D01*
G01X1681535Y231097D02*
Y218097D01*
G01X1683342Y226812D02*
Y233012D01*
G01D02*
X1686542D01*
G01D02*
Y226812D01*
G01D02*
X1683342D01*
G01X1691400Y233100D02*
X1694600D01*
G01X1691400Y226900D02*
Y233100D01*
G01X1694600Y226900D02*
X1691400D01*
G01X1687400Y233100D02*
X1690600D01*
G01X1687400Y226900D02*
Y233100D01*
G01X1690600Y226900D02*
X1687400D01*
G01X1690600Y233100D02*
Y226900D01*
G01X1680046Y391346D02*
Y379850D01*
G01X1680669Y379116D02*
X1711673D01*
Y393916D01*
X1680669D01*
Y379116D01*
G01X1690104Y406160D02*
Y399960D01*
G01D02*
X1686904D01*
G01D02*
Y406160D01*
G01X1697104Y399885D02*
X1690904D01*
G01D02*
Y403085D01*
G01D02*
X1697104D01*
G01X1687883Y395500D02*
Y398600D01*
X1688842D01*
X1689148Y398445D01*
X1689340Y398238D01*
X1689417Y397825D01*
X1689340Y397412D01*
X1689110Y397153D01*
X1688842Y396998D01*
X1687883D01*
G01X1688842D02*
X1689417Y395500D01*
G01X1690907Y396120D02*
X1691137Y395758D01*
X1691443Y395552D01*
X1691788Y395500D01*
X1692095Y395552D01*
X1692402Y395810D01*
X1692593Y396120D01*
X1692632Y396430D01*
X1692555Y396792D01*
X1692287Y397050D01*
X1692018Y397153D01*
X1691673D01*
G01X1692018D02*
X1692248Y397308D01*
X1692440Y397567D01*
X1692517Y397877D01*
X1692440Y398187D01*
X1692248Y398445D01*
X1691903Y398600D01*
X1691558Y398548D01*
X1691213Y398342D01*
G01X1694122Y396792D02*
X1694390Y397153D01*
X1694620Y397360D01*
X1694927Y397463D01*
X1695195Y397360D01*
X1695387Y397153D01*
X1695540Y396843D01*
X1695578Y396482D01*
X1695540Y396172D01*
X1695387Y395862D01*
X1695157Y395603D01*
X1694888Y395500D01*
X1694582Y395603D01*
X1694313Y395913D01*
X1694160Y396378D01*
X1694122Y396895D01*
X1694198Y397567D01*
X1694313Y397928D01*
X1694505Y398290D01*
X1694773Y398548D01*
X1695042Y398600D01*
X1695310Y398497D01*
X1695502Y398238D01*
G01X1698410Y395500D02*
Y398600D01*
X1696992Y396378D01*
X1698908D01*
G01X1700207Y395965D02*
X1700437Y395707D01*
X1700705Y395552D01*
X1701050Y395500D01*
X1701395Y395603D01*
X1701663Y395810D01*
X1701855Y396172D01*
X1701893Y396585D01*
X1701817Y396998D01*
X1701625Y397257D01*
X1701357Y397463D01*
X1701088Y397515D01*
X1700820Y397463D01*
X1700475Y397257D01*
X1700590Y398600D01*
X1701625D01*
G01X1686904Y406160D02*
X1690104D01*
G01X1686870Y407558D02*
X1683770D01*
Y408478D01*
X1683925Y408785D01*
X1684287Y409015D01*
X1684700Y409092D01*
X1685113Y409015D01*
X1685423Y408823D01*
X1685578Y408478D01*
Y407558D01*
G01X1683770Y410582D02*
X1685992D01*
X1686457Y410735D01*
X1686767Y411042D01*
X1686870Y411425D01*
X1686767Y411808D01*
X1686457Y412115D01*
X1685992Y412268D01*
X1683770D01*
G01X1684287Y413797D02*
X1683977Y414027D01*
X1683822Y414295D01*
X1683770Y414602D01*
X1683873Y414985D01*
X1684132Y415253D01*
X1684442Y415330D01*
X1684752Y415292D01*
X1685010Y415138D01*
X1685527Y414372D01*
X1685888Y414027D01*
X1686405Y413797D01*
X1686870Y413720D01*
Y415330D01*
G01X1683770Y417625D02*
X1683873Y417318D01*
X1684132Y417088D01*
X1684442Y416935D01*
X1684855Y416820D01*
X1685320Y416782D01*
X1685785Y416820D01*
X1686198Y416935D01*
X1686508Y417088D01*
X1686767Y417318D01*
X1686870Y417625D01*
X1686767Y417932D01*
X1686508Y418162D01*
X1686198Y418315D01*
X1685785Y418430D01*
X1685320Y418468D01*
X1684855Y418430D01*
X1684442Y418315D01*
X1684132Y418162D01*
X1683873Y417932D01*
X1683770Y417625D01*
G01X1684287Y419997D02*
X1683977Y420227D01*
X1683822Y420495D01*
X1683770Y420802D01*
X1683873Y421185D01*
X1684132Y421453D01*
X1684442Y421530D01*
X1684752Y421492D01*
X1685010Y421338D01*
X1685527Y420572D01*
X1685888Y420227D01*
X1686405Y419997D01*
X1686870Y419920D01*
Y421530D01*
G01X1691754Y433285D02*
Y427085D01*
G01D02*
X1688554D01*
G01D02*
Y433285D01*
G01D02*
X1691754D01*
G01X1691733Y423094D02*
X1685533D01*
G01D02*
Y426294D01*
G01D02*
X1691733D01*
G01D02*
Y423094D01*
G01X1684554Y427085D02*
Y433285D01*
G01D02*
X1687754D01*
G01D02*
Y427085D01*
G01D02*
X1684554D01*
G01X1682850Y437672D02*
Y425672D01*
G01X1681760Y662312D02*
X1678660D01*
Y663232D01*
X1678815Y663539D01*
X1679177Y663769D01*
X1679590Y663846D01*
X1680003Y663769D01*
X1680313Y663577D01*
X1680468Y663232D01*
Y662312D01*
G01X1678660Y665412D02*
X1681760D01*
Y666946D01*
G01X1680468Y668551D02*
X1680107Y668819D01*
X1679900Y669049D01*
X1679797Y669356D01*
X1679900Y669624D01*
X1680107Y669816D01*
X1680417Y669969D01*
X1680778Y670007D01*
X1681088Y669969D01*
X1681398Y669816D01*
X1681657Y669586D01*
X1681760Y669317D01*
X1681657Y669011D01*
X1681347Y668742D01*
X1680882Y668589D01*
X1680365Y668551D01*
X1679693Y668627D01*
X1679332Y668742D01*
X1678970Y668934D01*
X1678712Y669202D01*
X1678660Y669471D01*
X1678763Y669739D01*
X1679022Y669931D01*
G01X1679177Y671651D02*
X1678867Y671881D01*
X1678712Y672149D01*
X1678660Y672456D01*
X1678763Y672839D01*
X1679022Y673107D01*
X1679332Y673184D01*
X1679642Y673146D01*
X1679900Y672992D01*
X1680417Y672226D01*
X1680778Y671881D01*
X1681295Y671651D01*
X1681760Y671574D01*
Y673184D01*
G01X1676922Y686934D02*
Y661344D01*
G01X1685194Y683505D02*
X1685386Y683195D01*
X1685616Y682988D01*
X1685884Y682885D01*
X1686191Y682988D01*
X1686421Y683195D01*
X1686651Y683505D01*
X1686728Y683918D01*
Y685985D01*
G01X1689061Y682885D02*
Y685985D01*
X1688601Y685365D01*
G01Y682885D02*
X1689521D01*
G01X1692161D02*
X1692429Y682937D01*
X1692736Y683092D01*
X1692928Y683350D01*
X1693004Y683712D01*
X1692928Y684073D01*
X1692698Y684383D01*
X1692353Y684538D01*
X1691969D01*
X1691739Y684642D01*
X1691548Y684900D01*
X1691471Y685262D01*
X1691586Y685623D01*
X1691854Y685882D01*
X1692161Y685985D01*
X1692468Y685882D01*
X1692736Y685623D01*
X1692851Y685262D01*
X1692774Y684900D01*
X1692583Y684642D01*
X1692353Y684538D01*
X1691969D01*
X1691624Y684383D01*
X1691394Y684073D01*
X1691318Y683712D01*
X1691394Y683350D01*
X1691586Y683092D01*
X1691893Y682937D01*
X1692161Y682885D01*
G01X1678174Y687244D02*
Y1293000D01*
G01X1703764Y687244D02*
X1678174D01*
G01X1703764Y720709D02*
X1678174D01*
G01X1703764Y1291575D02*
X1678174D01*
G01X1690699Y1298763D02*
Y1317417D01*
G01X1683572Y1298763D02*
X1690699D01*
G01X1685500Y1325040D02*
X1698500D01*
G01X1685515Y1327981D02*
Y1367351D01*
G01X1691857Y1327981D02*
X1685515D01*
G01X1683047Y1367251D02*
Y1327881D01*
G01X1687699Y1320417D02*
X1683572D01*
G01X1690699Y1317417D02*
X1687699Y1320417D01*
G01X1689229Y1372214D02*
Y1369014D01*
G01X1683029Y1372214D02*
X1689229D01*
G01X1683029Y1369014D02*
Y1372214D01*
G01X1689229Y1369014D02*
X1683029D01*
G01X1687795Y1372514D02*
X1684595D01*
G01X1687795Y1378714D02*
Y1372514D01*
G01X1684595D02*
Y1378714D01*
G01X1685515Y1367351D02*
X1691857D01*
G01X1690829Y1370631D02*
Y1373231D01*
G01X1691622Y1370631D02*
X1690829D01*
G01X1677733Y1370531D02*
X1676940D01*
G01X1677733Y1373131D02*
Y1370531D01*
G01X1680690Y1385790D02*
X1683890D01*
G01X1680690Y1379590D02*
Y1385790D01*
G01X1683890Y1379590D02*
X1680690D01*
G01X1683890Y1385790D02*
Y1379590D01*
G01X1684572Y1385535D02*
X1687772D01*
G01X1684572Y1379335D02*
Y1385535D01*
G01X1687772Y1379335D02*
X1684572D01*
G01X1687772Y1385535D02*
Y1379335D01*
G01X1684595Y1378714D02*
X1687795D01*
G01X1690829Y1379842D02*
Y1381540D01*
G01X1691666Y1398466D02*
X1688466D01*
G01X1691666Y1404666D02*
Y1398466D01*
G01X1688466D02*
Y1404666D01*
G01X1681288Y1398103D02*
Y1401303D01*
G01X1687488Y1398103D02*
X1681288D01*
G01X1687488Y1401303D02*
Y1398103D01*
G01X1681288Y1401303D02*
X1687488D01*
G01X1687772Y1389835D02*
X1684572D01*
G01X1687772Y1396035D02*
Y1394700D01*
G01X1684572Y1396035D02*
X1687772D01*
G01X1684572Y1389835D02*
Y1396035D01*
G01X1687772Y1392000D02*
Y1389835D01*
G01X1690829Y1394253D02*
X1691837D01*
G01X1690829Y1392399D02*
Y1394253D01*
G01X1677733Y1394153D02*
Y1391962D01*
G01X1677000Y1394153D02*
X1677733D01*
G01X1688466Y1404666D02*
X1691666D01*
G01X1682758Y1414694D02*
Y1408694D01*
G01X1682600Y1438100D02*
Y1431900D01*
G01X1679400D02*
Y1438100D01*
G01X1682600Y1431900D02*
X1679400D01*
G01X1714226Y1429440D02*
X1687454D01*
G01X1714226D02*
G02I-13386J0D01*
G01X1679400Y1444600D02*
X1682600D01*
G01X1679400Y1438400D02*
Y1444600D01*
G01X1682600Y1438400D02*
X1679400D01*
G01X1682600Y1444600D02*
Y1438400D01*
G01X1679400Y1438100D02*
X1682600D01*
G01X1687074Y1544800D02*
Y1556800D01*
G01X1693074Y1544800D02*
X1687074D01*
G01X1684074Y1557200D02*
Y1551200D01*
G01X1684914Y1544000D02*
Y1550400D01*
G01X1686551Y1557926D02*
Y1561126D01*
G01X1692751Y1557926D02*
X1686551D01*
G01Y1561126D02*
X1692751D01*
G01X1686551Y1561926D02*
Y1565126D01*
G01X1692751Y1561926D02*
X1686551D01*
G01Y1565126D02*
X1692751D01*
G01X1687074Y1556800D02*
X1693074D01*
G01X1684007Y1572745D02*
Y1566745D01*
G01X1679164Y1565026D02*
X1685164D01*
Y1562026D01*
X1679164D01*
Y1565026D01*
G01X1685264Y1558026D02*
X1679064D01*
Y1561226D01*
X1685264D01*
Y1558026D01*
G01X1684007Y1579599D02*
Y1573599D01*
G01X1682412Y1670841D02*
X1685612D01*
G01X1682412Y1664641D02*
Y1670841D01*
G01X1685612Y1664641D02*
X1682412D01*
G01X1685612Y1670841D02*
Y1664641D01*
G01X1686643Y1670902D02*
X1689843D01*
G01Y1664702D02*
X1686643D01*
G01X1689843Y1670902D02*
Y1664702D01*
G01X1686643D02*
Y1670902D01*
G01X1690815Y1670840D02*
X1694015D01*
G01Y1664640D02*
X1690815D01*
G01D02*
Y1670840D01*
G01X1678216Y1670903D02*
X1681416D01*
G01Y1664703D02*
X1678216D01*
G01X1681416Y1670903D02*
Y1664703D01*
G01X1678216D02*
Y1670903D01*
G01X1685120Y1680339D02*
X1683167D01*
G01D02*
Y1682292D01*
G01X1683208Y1698027D02*
X1689408D01*
G01X1683208Y1694827D02*
Y1698027D01*
G01X1689408D02*
Y1694827D01*
G01D02*
X1683208D01*
G01X1690427Y1698022D02*
X1696627D01*
G01X1690427Y1694822D02*
Y1698022D01*
G01X1696627Y1694822D02*
X1690427D01*
G01X1683167Y1692151D02*
X1685120D01*
G01X1683167Y1690198D02*
Y1692151D01*
G01X1691113Y1707084D02*
X1687913D01*
G01D02*
Y1713284D01*
G01D02*
X1691113D01*
G01D02*
Y1707084D01*
G01X1676960Y1713602D02*
Y1707402D01*
G01X1691113Y1714084D02*
X1687913D01*
G01D02*
Y1720284D01*
G01X1691113D02*
Y1714084D01*
G01X1683913D02*
Y1720284D01*
G01X1687113D02*
Y1714084D01*
G01D02*
X1683913D01*
G01Y1707084D02*
Y1713284D01*
G01D02*
X1687113D01*
G01D02*
Y1707084D01*
G01D02*
X1683913D01*
G01X1676960Y1728352D02*
Y1722152D01*
G01X1687913Y1720284D02*
X1691113D01*
G01X1683913D02*
X1687113D01*
G01X1753000Y51142D02*
X1706000D01*
G01X1701856Y171233D02*
X1698756D01*
Y172153D01*
X1698911Y172460D01*
X1699273Y172690D01*
X1699686Y172767D01*
X1700099Y172690D01*
X1700409Y172498D01*
X1700564Y172153D01*
Y171233D01*
G01X1698756Y174333D02*
X1701856D01*
Y175867D01*
G01Y178200D02*
X1701804Y178468D01*
X1701649Y178775D01*
X1701391Y178967D01*
X1701029Y179043D01*
X1700668Y178967D01*
X1700358Y178737D01*
X1700203Y178392D01*
Y178008D01*
X1700099Y177778D01*
X1699841Y177587D01*
X1699479Y177510D01*
X1699118Y177625D01*
X1698859Y177893D01*
X1698756Y178200D01*
X1698859Y178507D01*
X1699118Y178775D01*
X1699479Y178890D01*
X1699841Y178813D01*
X1700099Y178622D01*
X1700203Y178392D01*
Y178008D01*
X1700358Y177663D01*
X1700668Y177433D01*
X1701029Y177357D01*
X1701391Y177433D01*
X1701649Y177625D01*
X1701804Y177932D01*
X1701856Y178200D01*
G01X1698756Y181300D02*
X1698859Y180993D01*
X1699118Y180763D01*
X1699428Y180610D01*
X1699841Y180495D01*
X1700306Y180457D01*
X1700771Y180495D01*
X1701184Y180610D01*
X1701494Y180763D01*
X1701753Y180993D01*
X1701856Y181300D01*
X1701753Y181607D01*
X1701494Y181837D01*
X1701184Y181990D01*
X1700771Y182105D01*
X1700306Y182143D01*
X1699841Y182105D01*
X1699428Y181990D01*
X1699118Y181837D01*
X1698859Y181607D01*
X1698756Y181300D01*
G01X1701856Y184860D02*
X1698756D01*
X1700978Y183442D01*
Y185358D01*
G01X1701391Y186657D02*
X1701649Y186887D01*
X1701804Y187155D01*
X1701856Y187500D01*
X1701753Y187845D01*
X1701546Y188113D01*
X1701184Y188305D01*
X1700771Y188343D01*
X1700358Y188267D01*
X1700099Y188075D01*
X1699893Y187807D01*
X1699841Y187538D01*
X1699893Y187270D01*
X1700099Y186925D01*
X1698756Y187040D01*
Y188075D01*
G01X1694600Y233100D02*
Y226900D01*
G01X1706394Y375373D02*
Y372173D01*
G01X1700194D02*
Y375373D01*
G01X1706394Y372173D02*
X1700194D01*
G01X1706394Y371373D02*
Y368173D01*
G01X1700194D02*
Y371373D01*
G01X1706394Y368173D02*
X1700194D01*
G01Y371373D02*
X1706394D01*
G01X1700194Y375373D02*
X1706394D01*
G01X1697104Y403085D02*
Y399885D01*
G01X1698284Y403085D02*
X1704484D01*
G01D02*
Y399885D01*
G01D02*
X1698284D01*
G01D02*
Y403085D01*
G01X1704208Y407687D02*
Y421663D01*
G01X1696020D02*
Y407687D01*
G01D02*
X1704208D01*
G01X1695914Y433255D02*
Y427055D01*
G01D02*
X1692714D01*
G01D02*
Y433255D01*
G01D02*
X1695914D01*
G01X1703024Y426575D02*
Y432775D01*
G01D02*
X1706224D01*
G01D02*
Y426575D01*
G01D02*
X1703024D01*
G01X1699524D02*
Y432775D01*
G01D02*
X1702724D01*
G01D02*
Y426575D01*
G01D02*
X1699524D01*
G01X1704208Y421663D02*
X1696020D01*
G01X1703764Y1293000D02*
Y687244D01*
G01X1693045Y1298763D02*
X1700172D01*
G01X1693045Y1317417D02*
Y1298763D01*
G01X1696045Y1320417D02*
X1693045Y1317417D01*
G01X1700172Y1320417D02*
X1696045D01*
G01X1706103Y1397466D02*
Y1403666D01*
G01X1709303Y1397466D02*
X1706103D01*
G01X1705261D02*
X1702061D01*
G01X1705261Y1403666D02*
Y1397466D01*
G01X1702061D02*
Y1403666D01*
G01X1698636Y1404560D02*
Y1401360D01*
G01X1692436D02*
Y1404560D01*
G01X1698636Y1401360D02*
X1692436D01*
G01X1706103Y1403666D02*
X1709303D01*
G01X1702061D02*
X1705261D01*
G01X1692436Y1404560D02*
X1698636D01*
G01X1693843Y1411448D02*
Y1414548D01*
X1694763D01*
X1695070Y1414393D01*
X1695300Y1414031D01*
X1695377Y1413618D01*
X1695300Y1413205D01*
X1695108Y1412895D01*
X1694763Y1412740D01*
X1693843D01*
G01X1698553Y1414290D02*
X1698323Y1414445D01*
X1698055Y1414548D01*
X1697748D01*
X1697403Y1414393D01*
X1697135Y1414135D01*
X1696943Y1413825D01*
X1696790Y1413308D01*
X1696752Y1412843D01*
X1696828Y1412378D01*
X1696943Y1412068D01*
X1697173Y1411758D01*
X1697442Y1411551D01*
X1697710Y1411448D01*
X1697978D01*
X1698247Y1411551D01*
X1698477Y1411706D01*
X1698668Y1411913D01*
G01X1700082Y1414031D02*
X1700312Y1414341D01*
X1700580Y1414496D01*
X1700887Y1414548D01*
X1701270Y1414445D01*
X1701538Y1414186D01*
X1701615Y1413876D01*
X1701577Y1413566D01*
X1701423Y1413308D01*
X1700657Y1412791D01*
X1700312Y1412430D01*
X1700082Y1411913D01*
X1700005Y1411448D01*
X1701615D01*
G01X1703182Y1414031D02*
X1703412Y1414341D01*
X1703680Y1414496D01*
X1703987Y1414548D01*
X1704370Y1414445D01*
X1704638Y1414186D01*
X1704715Y1413876D01*
X1704677Y1413566D01*
X1704523Y1413308D01*
X1703757Y1412791D01*
X1703412Y1412430D01*
X1703182Y1411913D01*
X1703105Y1411448D01*
X1704715D01*
G01X1707010Y1414548D02*
X1706703Y1414445D01*
X1706473Y1414186D01*
X1706320Y1413876D01*
X1706205Y1413463D01*
X1706167Y1412998D01*
X1706205Y1412533D01*
X1706320Y1412120D01*
X1706473Y1411810D01*
X1706703Y1411551D01*
X1707010Y1411448D01*
X1707317Y1411551D01*
X1707547Y1411810D01*
X1707700Y1412120D01*
X1707815Y1412533D01*
X1707853Y1412998D01*
X1707815Y1413463D01*
X1707700Y1413876D01*
X1707547Y1414186D01*
X1707317Y1414445D01*
X1707010Y1414548D01*
G01X1693074Y1556800D02*
Y1544800D01*
G01X1697129Y1549868D02*
Y1543668D01*
X1693929D01*
Y1549868D01*
X1697129D01*
G01X1692751Y1561126D02*
Y1557926D01*
G01Y1565126D02*
Y1561926D01*
G01X1699653Y1584875D02*
Y1587975D01*
G01X1701263D02*
Y1584875D01*
G01Y1586425D02*
X1699653D01*
G01X1703558Y1584875D02*
Y1587975D01*
X1703098Y1587355D01*
G01Y1584875D02*
X1704018D01*
G01X1706658Y1587975D02*
X1706351Y1587872D01*
X1706121Y1587613D01*
X1705968Y1587303D01*
X1705853Y1586890D01*
X1705815Y1586425D01*
X1705853Y1585960D01*
X1705968Y1585547D01*
X1706121Y1585237D01*
X1706351Y1584978D01*
X1706658Y1584875D01*
X1706965Y1584978D01*
X1707195Y1585237D01*
X1707348Y1585547D01*
X1707463Y1585960D01*
X1707501Y1586425D01*
X1707463Y1586890D01*
X1707348Y1587303D01*
X1707195Y1587613D01*
X1706965Y1587872D01*
X1706658Y1587975D01*
G01X1694015Y1670840D02*
Y1664640D01*
G01X1694979Y1680339D02*
X1693026D01*
G01X1694979Y1682292D02*
Y1680339D01*
G01X1696627Y1698022D02*
Y1694822D01*
G01X1694979Y1692151D02*
Y1690198D01*
G01X1693026Y1692151D02*
X1694979D01*
G01X1707007Y1709987D02*
X1696513D01*
G01D02*
Y1718649D01*
G01X1697310Y1719885D02*
X1697003Y1719937D01*
X1696735Y1720143D01*
X1696505Y1720453D01*
X1696352Y1720815D01*
X1696275Y1721228D01*
Y1721642D01*
X1696352Y1722055D01*
X1696505Y1722417D01*
X1696735Y1722727D01*
X1697003Y1722933D01*
X1697310Y1722985D01*
X1697617Y1722933D01*
X1697885Y1722727D01*
X1698115Y1722417D01*
X1698268Y1722055D01*
X1698345Y1721642D01*
Y1721228D01*
X1698268Y1720815D01*
X1698115Y1720453D01*
X1697885Y1720143D01*
X1697617Y1719937D01*
X1697310Y1719885D01*
G01X1697617Y1720712D02*
X1698077Y1719885D01*
G01X1700333D02*
X1700410Y1720557D01*
X1700525Y1721125D01*
X1700678Y1721642D01*
X1700870Y1722210D01*
X1701177Y1722985D01*
X1699643D01*
G01X1703510D02*
X1703203Y1722882D01*
X1702973Y1722623D01*
X1702820Y1722313D01*
X1702705Y1721900D01*
X1702667Y1721435D01*
X1702705Y1720970D01*
X1702820Y1720557D01*
X1702973Y1720247D01*
X1703203Y1719988D01*
X1703510Y1719885D01*
X1703817Y1719988D01*
X1704047Y1720247D01*
X1704200Y1720557D01*
X1704315Y1720970D01*
X1704353Y1721435D01*
X1704315Y1721900D01*
X1704200Y1722313D01*
X1704047Y1722623D01*
X1703817Y1722882D01*
X1703510Y1722985D01*
G01X1696513Y1718649D02*
X1699860D01*
G01D02*
X1701760Y1716449D01*
G01D02*
X1703660Y1718649D01*
G01D02*
X1707007D01*
G01X1710198Y60679D02*
Y66879D01*
G01X1713398Y60679D02*
X1710198D01*
G01X1713398Y66879D02*
Y60679D01*
G01X1714958D02*
Y66879D01*
G01X1718158Y60679D02*
X1714958D01*
G01X1718158Y66879D02*
Y60679D01*
G01X1719744Y60856D02*
Y67056D01*
G01X1722944Y60856D02*
X1719744D01*
G01X1718531Y80355D02*
Y74155D01*
G01D02*
X1715331D01*
G01D02*
Y80355D01*
G01X1713398Y80367D02*
Y74167D01*
G01D02*
X1710198D01*
G01D02*
Y80367D01*
G01Y66879D02*
X1713398D01*
G01X1714958D02*
X1718158D01*
G01X1719744Y67056D02*
X1722944D01*
G01X1715331Y80355D02*
X1718531D01*
G01X1710198Y80367D02*
X1713398D01*
G01X1721008Y104284D02*
Y110484D01*
G01X1724208Y104284D02*
X1721008D01*
G01X1717008Y99484D02*
Y105684D01*
G01D02*
X1720208D01*
G01D02*
Y99484D01*
G01D02*
X1717008D01*
G01X1711765Y108087D02*
X1714265D01*
X1713765Y108407D01*
G01X1711765D02*
Y107767D01*
G01Y105887D02*
X1714265D01*
X1713765Y106207D01*
G01X1711765D02*
Y105567D01*
G01X1722778Y98060D02*
Y95560D01*
X1723098Y96060D01*
G01Y98060D02*
X1722458D01*
G01X1721085Y95977D02*
X1720925Y95727D01*
X1720738Y95602D01*
X1720525Y95560D01*
X1720258Y95643D01*
X1720071Y95852D01*
X1720018Y96102D01*
X1720045Y96352D01*
X1720151Y96560D01*
X1720685Y96977D01*
X1720925Y97268D01*
X1721085Y97685D01*
X1721138Y98060D01*
X1720018D01*
G01X1721008Y110484D02*
X1724208D01*
G01X1727018Y115267D02*
X1720818D01*
G01D02*
Y118467D01*
G01D02*
X1727018D01*
G01X1720818Y114467D02*
X1727018D01*
G01Y111267D02*
X1720818D01*
G01D02*
Y114467D01*
G01X1719818Y123567D02*
Y129767D01*
G01D02*
X1723018D01*
G01Y123567D02*
X1719818D01*
G01X1715818D02*
Y129767D01*
G01D02*
X1719018D01*
G01D02*
Y123567D01*
G01D02*
X1715818D01*
G01X1715018Y129767D02*
Y123567D01*
G01D02*
X1711818D01*
G01D02*
Y129767D01*
G01D02*
X1715018D01*
G01X1711712Y136622D02*
Y142822D01*
G01D02*
X1714912D01*
G01D02*
Y136622D01*
G01D02*
X1711712D01*
G01X1706922Y168406D02*
Y186122D01*
G01X1710330Y168406D02*
X1706922D01*
G01X1724638D02*
X1721230D01*
G01X1711868Y190155D02*
Y193255D01*
X1712788D01*
X1713095Y193100D01*
X1713325Y192738D01*
X1713402Y192325D01*
X1713325Y191912D01*
X1713133Y191602D01*
X1712788Y191447D01*
X1711868D01*
G01X1716578Y192997D02*
X1716348Y193152D01*
X1716080Y193255D01*
X1715773D01*
X1715428Y193100D01*
X1715160Y192842D01*
X1714968Y192532D01*
X1714815Y192015D01*
X1714777Y191550D01*
X1714853Y191085D01*
X1714968Y190775D01*
X1715198Y190465D01*
X1715467Y190258D01*
X1715735Y190155D01*
X1716003D01*
X1716272Y190258D01*
X1716502Y190413D01*
X1716693Y190620D01*
G01X1717992Y190775D02*
X1718222Y190413D01*
X1718528Y190207D01*
X1718873Y190155D01*
X1719180Y190207D01*
X1719487Y190465D01*
X1719678Y190775D01*
X1719717Y191085D01*
X1719640Y191447D01*
X1719372Y191705D01*
X1719103Y191808D01*
X1718758D01*
G01X1719103D02*
X1719333Y191963D01*
X1719525Y192222D01*
X1719602Y192532D01*
X1719525Y192842D01*
X1719333Y193100D01*
X1718988Y193255D01*
X1718643Y193203D01*
X1718298Y192997D01*
G01X1745045Y203533D02*
G02I-13385J0D01*
G01X1706922Y186122D02*
X1710330D01*
G01X1721230D02*
X1724638D01*
G01X1745046Y203533D02*
X1718274D01*
G01X1713090Y366562D02*
X1719290D01*
G01D02*
Y363362D01*
G01D02*
X1713090D01*
G01D02*
Y366562D01*
G01X1724100Y367262D02*
X1720900D01*
G01Y373462D02*
X1724100D01*
G01X1720900Y367262D02*
Y373462D01*
G01X1713444Y405445D02*
Y411645D01*
G01D02*
X1716644D01*
G01D02*
Y405445D01*
G01D02*
X1713444D01*
G01X1712026Y412263D02*
Y406063D01*
G01D02*
X1708826D01*
G01D02*
Y412263D01*
G01D02*
X1712026D01*
G01X1708808Y418845D02*
Y425045D01*
G01X1712008D02*
Y418845D01*
G01D02*
X1708808D01*
G01X1717331Y405437D02*
Y411637D01*
G01D02*
X1720531D01*
G01D02*
Y405437D01*
G01D02*
X1717331D01*
G01X1719627Y418740D02*
X1713427D01*
G01D02*
Y421940D01*
G01X1719627D02*
Y418740D01*
G01X1708808Y425045D02*
X1712008D01*
G01X1719627Y422740D02*
X1713427D01*
G01D02*
Y425940D01*
G01D02*
X1719627D01*
G01D02*
Y422740D01*
G01X1713427Y421940D02*
X1719627D01*
G01X1762645Y605411D02*
G02I-22900J0D01*
G01X1711400Y650250D02*
Y656450D01*
X1714600D01*
Y650250D01*
X1711400D01*
G01Y653400D02*
Y659600D01*
X1714600D01*
Y653400D01*
X1711400D01*
G01X1708234Y667838D02*
X1714434D01*
G01D02*
Y664638D01*
G01D02*
X1708234D01*
G01D02*
Y667838D01*
G01Y663838D02*
X1714434D01*
G01D02*
Y660638D01*
G01D02*
X1708234D01*
G01D02*
Y663838D01*
G01X1714600Y678250D02*
Y672050D01*
X1711400D01*
Y678250D01*
X1714600D01*
G01Y675100D02*
Y668900D01*
X1711400D01*
Y675100D01*
X1714600D01*
G01X1711593Y683145D02*
X1711785Y682835D01*
X1712015Y682628D01*
X1712283Y682525D01*
X1712590Y682628D01*
X1712820Y682835D01*
X1713050Y683145D01*
X1713127Y683558D01*
Y685625D01*
G01X1714732Y683817D02*
X1715000Y684178D01*
X1715230Y684385D01*
X1715537Y684488D01*
X1715805Y684385D01*
X1715997Y684178D01*
X1716150Y683868D01*
X1716188Y683507D01*
X1716150Y683197D01*
X1715997Y682887D01*
X1715767Y682628D01*
X1715498Y682525D01*
X1715192Y682628D01*
X1714923Y682938D01*
X1714770Y683403D01*
X1714732Y683920D01*
X1714808Y684592D01*
X1714923Y684953D01*
X1715115Y685315D01*
X1715383Y685573D01*
X1715652Y685625D01*
X1715920Y685522D01*
X1716112Y685263D01*
G01X1718560Y682525D02*
X1718828Y682577D01*
X1719135Y682732D01*
X1719327Y682990D01*
X1719403Y683352D01*
X1719327Y683713D01*
X1719097Y684023D01*
X1718752Y684178D01*
X1718368D01*
X1718138Y684282D01*
X1717947Y684540D01*
X1717870Y684902D01*
X1717985Y685263D01*
X1718253Y685522D01*
X1718560Y685625D01*
X1718867Y685522D01*
X1719135Y685263D01*
X1719250Y684902D01*
X1719173Y684540D01*
X1718982Y684282D01*
X1718752Y684178D01*
X1718368D01*
X1718023Y684023D01*
X1717793Y683713D01*
X1717717Y683352D01*
X1717793Y682990D01*
X1717985Y682732D01*
X1718292Y682577D01*
X1718560Y682525D01*
G01X1707875Y687244D02*
Y1293000D01*
G01X1733465Y687244D02*
X1707875D01*
G01X1733465Y720709D02*
X1707875D01*
G01X1733465Y1291575D02*
X1707875D01*
G01X1716840Y1298763D02*
X1723967D01*
G01X1716840Y1317417D02*
Y1298763D01*
G01X1714699D02*
Y1317417D01*
G01X1707572Y1298763D02*
X1714699D01*
G01X1713000Y1325040D02*
X1733465D01*
G01X1715829Y1327981D02*
X1709487D01*
G01X1715829Y1367351D02*
Y1327981D01*
G01X1719840Y1320417D02*
X1716840Y1317417D01*
G01X1723967Y1320417D02*
X1719840D01*
G01X1711699D02*
X1707572D01*
G01X1714699Y1317417D02*
X1711699Y1320417D01*
G01X1721000Y1356383D02*
X1717900D01*
Y1357303D01*
X1718055Y1357610D01*
X1718417Y1357840D01*
X1718830Y1357917D01*
X1719243Y1357840D01*
X1719553Y1357648D01*
X1719708Y1357303D01*
Y1356383D01*
G01X1717900Y1359483D02*
X1721000D01*
Y1361017D01*
G01X1718417Y1362622D02*
X1718107Y1362852D01*
X1717952Y1363120D01*
X1717900Y1363427D01*
X1718003Y1363810D01*
X1718262Y1364078D01*
X1718572Y1364155D01*
X1718882Y1364117D01*
X1719140Y1363963D01*
X1719657Y1363197D01*
X1720018Y1362852D01*
X1720535Y1362622D01*
X1721000Y1362545D01*
Y1364155D01*
G01X1718417Y1365722D02*
X1718107Y1365952D01*
X1717952Y1366220D01*
X1717900Y1366527D01*
X1718003Y1366910D01*
X1718262Y1367178D01*
X1718572Y1367255D01*
X1718882Y1367217D01*
X1719140Y1367063D01*
X1719657Y1366297D01*
X1720018Y1365952D01*
X1720535Y1365722D01*
X1721000Y1365645D01*
Y1367255D01*
G01X1709487Y1367351D02*
X1715829D01*
G01X1710515Y1370631D02*
X1709722D01*
G01X1710515Y1373231D02*
Y1370631D01*
G01X1713472Y1385890D02*
X1716672D01*
G01X1713472Y1379690D02*
Y1385890D01*
G01X1716672Y1379690D02*
X1713472D01*
G01X1716672Y1385890D02*
Y1379690D01*
G01X1717349Y1385890D02*
X1720549D01*
G01X1717349Y1379690D02*
Y1385890D01*
G01X1720549Y1379690D02*
X1717349D01*
G01X1720549Y1385890D02*
Y1379690D01*
G01X1722564Y1387125D02*
X1719464D01*
Y1388045D01*
X1719619Y1388352D01*
X1719981Y1388582D01*
X1720394Y1388659D01*
X1720807Y1388582D01*
X1721117Y1388390D01*
X1721272Y1388045D01*
Y1387125D01*
G01X1719464Y1390149D02*
X1721686D01*
X1722151Y1390302D01*
X1722461Y1390609D01*
X1722564Y1390992D01*
X1722461Y1391375D01*
X1722151Y1391682D01*
X1721686Y1391835D01*
X1719464D01*
G01X1719981Y1393364D02*
X1719671Y1393594D01*
X1719516Y1393862D01*
X1719464Y1394169D01*
X1719567Y1394552D01*
X1719826Y1394820D01*
X1720136Y1394897D01*
X1720446Y1394859D01*
X1720704Y1394705D01*
X1721221Y1393939D01*
X1721582Y1393594D01*
X1722099Y1393364D01*
X1722564Y1393287D01*
Y1394897D01*
G01X1721944Y1396349D02*
X1722306Y1396579D01*
X1722512Y1396885D01*
X1722564Y1397230D01*
X1722512Y1397537D01*
X1722254Y1397844D01*
X1721944Y1398035D01*
X1721634Y1398074D01*
X1721272Y1397997D01*
X1721014Y1397729D01*
X1720911Y1397460D01*
Y1397115D01*
G01Y1397460D02*
X1720756Y1397690D01*
X1720497Y1397882D01*
X1720187Y1397959D01*
X1719877Y1397882D01*
X1719619Y1397690D01*
X1719464Y1397345D01*
X1719516Y1397000D01*
X1719722Y1396655D01*
G01X1709303Y1403666D02*
Y1397466D01*
G01X1710515Y1394253D02*
Y1392062D01*
G01X1709782Y1394253D02*
X1710515D01*
G01X1719473Y1410854D02*
Y1414262D01*
G01X1737189Y1410854D02*
X1719473D01*
G01X1719314Y1430009D02*
Y1433109D01*
X1720234D01*
X1720541Y1432954D01*
X1720771Y1432592D01*
X1720848Y1432179D01*
X1720771Y1431766D01*
X1720579Y1431456D01*
X1720234Y1431301D01*
X1719314D01*
G01X1722414Y1433109D02*
Y1430009D01*
X1723948D01*
G01X1725553Y1432592D02*
X1725783Y1432902D01*
X1726051Y1433057D01*
X1726358Y1433109D01*
X1726741Y1433006D01*
X1727009Y1432747D01*
X1727086Y1432437D01*
X1727048Y1432127D01*
X1726894Y1431869D01*
X1726128Y1431352D01*
X1725783Y1430991D01*
X1725553Y1430474D01*
X1725476Y1430009D01*
X1727086D01*
G01X1729841D02*
Y1433109D01*
X1728423Y1430887D01*
X1730339D01*
G01X1719473Y1428570D02*
X1737189D01*
G01X1719473Y1425162D02*
Y1428570D01*
G01X1722445Y1672234D02*
X1719245D01*
G01Y1678434D02*
X1722445D01*
G01X1719245Y1672234D02*
Y1678434D01*
G01X1709095Y1679100D02*
X1711317D01*
X1711782Y1679253D01*
X1712092Y1679560D01*
X1712195Y1679943D01*
X1712092Y1680326D01*
X1711782Y1680633D01*
X1711317Y1680786D01*
X1709095D01*
G01X1710903Y1682315D02*
X1710542Y1682583D01*
X1710335Y1682813D01*
X1710232Y1683120D01*
X1710335Y1683388D01*
X1710542Y1683580D01*
X1710852Y1683733D01*
X1711213Y1683771D01*
X1711523Y1683733D01*
X1711833Y1683580D01*
X1712092Y1683350D01*
X1712195Y1683081D01*
X1712092Y1682775D01*
X1711782Y1682506D01*
X1711317Y1682353D01*
X1710800Y1682315D01*
X1710128Y1682391D01*
X1709767Y1682506D01*
X1709405Y1682698D01*
X1709147Y1682966D01*
X1709095Y1683235D01*
X1709198Y1683503D01*
X1709457Y1683695D01*
G01X1709095Y1686143D02*
X1709198Y1685836D01*
X1709457Y1685606D01*
X1709767Y1685453D01*
X1710180Y1685338D01*
X1710645Y1685300D01*
X1711110Y1685338D01*
X1711523Y1685453D01*
X1711833Y1685606D01*
X1712092Y1685836D01*
X1712195Y1686143D01*
X1712092Y1686450D01*
X1711833Y1686680D01*
X1711523Y1686833D01*
X1711110Y1686948D01*
X1710645Y1686986D01*
X1710180Y1686948D01*
X1709767Y1686833D01*
X1709457Y1686680D01*
X1709198Y1686450D01*
X1709095Y1686143D01*
G01Y1689243D02*
X1709198Y1688936D01*
X1709457Y1688706D01*
X1709767Y1688553D01*
X1710180Y1688438D01*
X1710645Y1688400D01*
X1711110Y1688438D01*
X1711523Y1688553D01*
X1711833Y1688706D01*
X1712092Y1688936D01*
X1712195Y1689243D01*
X1712092Y1689550D01*
X1711833Y1689780D01*
X1711523Y1689933D01*
X1711110Y1690048D01*
X1710645Y1690086D01*
X1710180Y1690048D01*
X1709767Y1689933D01*
X1709457Y1689780D01*
X1709198Y1689550D01*
X1709095Y1689243D01*
G01X1711730Y1691500D02*
X1711988Y1691730D01*
X1712143Y1691998D01*
X1712195Y1692343D01*
X1712092Y1692688D01*
X1711885Y1692956D01*
X1711523Y1693148D01*
X1711110Y1693186D01*
X1710697Y1693110D01*
X1710438Y1692918D01*
X1710232Y1692650D01*
X1710180Y1692381D01*
X1710232Y1692113D01*
X1710438Y1691768D01*
X1709095Y1691883D01*
Y1692918D01*
G01X1708760Y1707402D02*
Y1713602D01*
G01D02*
X1711960D01*
G01D02*
Y1707402D01*
G01D02*
X1708760D01*
G01X1707007Y1718649D02*
Y1709987D01*
G01X1730575Y-32352D02*
Y-16072D01*
X1740175D01*
Y-32352D01*
X1730575D01*
G01X1749781Y43779D02*
X1734981D01*
G01X1730765Y52051D02*
Y55251D01*
G01X1736965Y52051D02*
X1730765D01*
G01Y55251D02*
X1736965D01*
G01X1730765Y59251D02*
X1736965D01*
G01X1730765Y56051D02*
Y59251D01*
G01X1736965Y56051D02*
X1730765D01*
G01X1722944Y67056D02*
Y60856D01*
G01X1739596Y60051D02*
X1727596D01*
G01D02*
Y66051D01*
G01D02*
X1739596D01*
G01X1724117Y67639D02*
X1755121D01*
G01X1724117Y82439D02*
Y67639D01*
G01X1735209Y83739D02*
Y86939D01*
G01X1741409Y83739D02*
X1735209D01*
G01Y86939D02*
X1741409D01*
G01X1731518Y88227D02*
Y91427D01*
G01X1737718Y88227D02*
X1731518D01*
G01X1755121Y82439D02*
X1724117D01*
G01X1724208Y110484D02*
Y104284D01*
G01X1728208Y110484D02*
Y104284D01*
G01D02*
X1725008D01*
G01D02*
Y110484D01*
G01X1731518Y91427D02*
X1737718D01*
G01X1724408Y92227D02*
Y96827D01*
G01X1734608Y92227D02*
X1724408D01*
G01X1734608Y96827D02*
Y92227D01*
G01X1724408Y96827D02*
X1734608D01*
G01Y102027D02*
Y97427D01*
G01X1724408Y102027D02*
X1734608D01*
G01X1724408Y97427D02*
Y102027D01*
G01X1734608Y97427D02*
X1724408D01*
G01X1731509Y107959D02*
Y104825D01*
G01D02*
X1732674D01*
G01X1727018Y118467D02*
Y115267D01*
G01X1725008Y110484D02*
X1728208D01*
G01X1727018Y114467D02*
Y111267D01*
G01X1731801Y120968D02*
X1731615Y121177D01*
X1731401Y121260D01*
X1731188Y121177D01*
X1731001Y120927D01*
X1730868Y120552D01*
X1730815Y120177D01*
Y119718D01*
X1730868Y119343D01*
X1731001Y119010D01*
X1731161Y118843D01*
X1731348Y118760D01*
X1731561Y118843D01*
X1731721Y119010D01*
X1731828Y119260D01*
X1731881Y119593D01*
X1731828Y119885D01*
X1731695Y120177D01*
X1731535Y120343D01*
X1731348Y120385D01*
X1731135Y120302D01*
X1730975Y120093D01*
X1730815Y119718D01*
G01X1723825Y121907D02*
X1726325D01*
X1725825Y122227D01*
G01X1723825D02*
Y121587D01*
G01X1726325Y119707D02*
X1726242Y119920D01*
X1726033Y120080D01*
X1725783Y120187D01*
X1725450Y120267D01*
X1725075Y120294D01*
X1724700Y120267D01*
X1724367Y120187D01*
X1724117Y120080D01*
X1723908Y119920D01*
X1723825Y119707D01*
X1723908Y119494D01*
X1724117Y119334D01*
X1724367Y119227D01*
X1724700Y119147D01*
X1725075Y119120D01*
X1725450Y119147D01*
X1725783Y119227D01*
X1726033Y119334D01*
X1726242Y119494D01*
X1726325Y119707D01*
G01X1732674Y117029D02*
X1731509D01*
G01D02*
Y113895D01*
G01Y111895D02*
Y109959D01*
G01X1734818Y123567D02*
Y129767D01*
G01D02*
X1738018D01*
G01Y123567D02*
X1734818D01*
G01X1727818D02*
Y129767D01*
G01D02*
X1731018D01*
G01D02*
Y123567D01*
G01D02*
X1727818D01*
G01X1723018Y129767D02*
Y123567D01*
G01X1723818D02*
Y129767D01*
G01D02*
X1727018D01*
G01D02*
Y123567D01*
G01D02*
X1723818D01*
G01X1728764Y169851D02*
Y176051D01*
G01D02*
X1731964D01*
G01D02*
Y169851D01*
G01D02*
X1728764D01*
G01X1724638Y186122D02*
Y168406D01*
G01X1730223Y184625D02*
Y187725D01*
X1731143D01*
X1731450Y187570D01*
X1731680Y187208D01*
X1731757Y186795D01*
X1731680Y186382D01*
X1731488Y186072D01*
X1731143Y185917D01*
X1730223D01*
G01X1734933Y187467D02*
X1734703Y187622D01*
X1734435Y187725D01*
X1734128D01*
X1733783Y187570D01*
X1733515Y187312D01*
X1733323Y187002D01*
X1733170Y186485D01*
X1733132Y186020D01*
X1733208Y185555D01*
X1733323Y185245D01*
X1733553Y184935D01*
X1733822Y184728D01*
X1734090Y184625D01*
X1734358D01*
X1734627Y184728D01*
X1734857Y184883D01*
X1735048Y185090D01*
G01X1736347D02*
X1736577Y184832D01*
X1736845Y184677D01*
X1737190Y184625D01*
X1737535Y184728D01*
X1737803Y184935D01*
X1737995Y185297D01*
X1738033Y185710D01*
X1737957Y186123D01*
X1737765Y186382D01*
X1737497Y186588D01*
X1737228Y186640D01*
X1736960Y186588D01*
X1736615Y186382D01*
X1736730Y187725D01*
X1737765D01*
G01X1739562Y185917D02*
X1739830Y186278D01*
X1740060Y186485D01*
X1740367Y186588D01*
X1740635Y186485D01*
X1740827Y186278D01*
X1740980Y185968D01*
X1741018Y185607D01*
X1740980Y185297D01*
X1740827Y184987D01*
X1740597Y184728D01*
X1740328Y184625D01*
X1740022Y184728D01*
X1739753Y185038D01*
X1739600Y185503D01*
X1739562Y186020D01*
X1739638Y186692D01*
X1739753Y187053D01*
X1739945Y187415D01*
X1740213Y187673D01*
X1740482Y187725D01*
X1740750Y187622D01*
X1740942Y187363D01*
G01X1742662Y185917D02*
X1742930Y186278D01*
X1743160Y186485D01*
X1743467Y186588D01*
X1743735Y186485D01*
X1743927Y186278D01*
X1744080Y185968D01*
X1744118Y185607D01*
X1744080Y185297D01*
X1743927Y184987D01*
X1743697Y184728D01*
X1743428Y184625D01*
X1743122Y184728D01*
X1742853Y185038D01*
X1742700Y185503D01*
X1742662Y186020D01*
X1742738Y186692D01*
X1742853Y187053D01*
X1743045Y187415D01*
X1743313Y187673D01*
X1743582Y187725D01*
X1743850Y187622D01*
X1744042Y187363D01*
G01X1728271Y265792D02*
X1727638D01*
G01D02*
Y284296D01*
G01X1725322Y277644D02*
X1725270Y277337D01*
X1725064Y277069D01*
X1724754Y276839D01*
X1724392Y276686D01*
X1723979Y276609D01*
X1723565D01*
X1723152Y276686D01*
X1722790Y276839D01*
X1722480Y277069D01*
X1722274Y277337D01*
X1722222Y277644D01*
X1722274Y277951D01*
X1722480Y278219D01*
X1722790Y278449D01*
X1723152Y278602D01*
X1723565Y278679D01*
X1723979D01*
X1724392Y278602D01*
X1724754Y278449D01*
X1725064Y278219D01*
X1725270Y277951D01*
X1725322Y277644D01*
G01X1724495Y277951D02*
X1725322Y278411D01*
G01X1724857Y279901D02*
X1725115Y280131D01*
X1725270Y280399D01*
X1725322Y280744D01*
X1725219Y281089D01*
X1725012Y281357D01*
X1724650Y281549D01*
X1724237Y281587D01*
X1723824Y281511D01*
X1723565Y281319D01*
X1723359Y281051D01*
X1723307Y280782D01*
X1723359Y280514D01*
X1723565Y280169D01*
X1722222Y280284D01*
Y281319D01*
G01X1724030Y283116D02*
X1723669Y283384D01*
X1723462Y283614D01*
X1723359Y283921D01*
X1723462Y284189D01*
X1723669Y284381D01*
X1723979Y284534D01*
X1724340Y284572D01*
X1724650Y284534D01*
X1724960Y284381D01*
X1725219Y284151D01*
X1725322Y283882D01*
X1725219Y283576D01*
X1724909Y283307D01*
X1724444Y283154D01*
X1723927Y283116D01*
X1723255Y283192D01*
X1722894Y283307D01*
X1722532Y283499D01*
X1722274Y283767D01*
X1722222Y284036D01*
X1722325Y284304D01*
X1722584Y284496D01*
G01X1727638Y284296D02*
X1728571D01*
G01X1724100Y373462D02*
Y367262D01*
G01X1729086Y364478D02*
Y366431D01*
G01X1731039Y364478D02*
X1729086D01*
G01X1723900Y382462D02*
X1727100D01*
G01Y376262D02*
X1723900D01*
G01X1727100Y382462D02*
Y376262D01*
G01X1723900D02*
Y382462D01*
G01X1728625Y383557D02*
Y381335D01*
X1728778Y380870D01*
X1729085Y380560D01*
X1729468Y380457D01*
X1729851Y380560D01*
X1730158Y380870D01*
X1730311Y381335D01*
Y383557D01*
G01X1731840Y383040D02*
X1732070Y383350D01*
X1732338Y383505D01*
X1732645Y383557D01*
X1733028Y383454D01*
X1733296Y383195D01*
X1733373Y382885D01*
X1733335Y382575D01*
X1733181Y382317D01*
X1732415Y381800D01*
X1732070Y381439D01*
X1731840Y380922D01*
X1731763Y380457D01*
X1733373D01*
G01X1734940Y381749D02*
X1735208Y382110D01*
X1735438Y382317D01*
X1735745Y382420D01*
X1736013Y382317D01*
X1736205Y382110D01*
X1736358Y381800D01*
X1736396Y381439D01*
X1736358Y381129D01*
X1736205Y380819D01*
X1735975Y380560D01*
X1735706Y380457D01*
X1735400Y380560D01*
X1735131Y380870D01*
X1734978Y381335D01*
X1734940Y381852D01*
X1735016Y382524D01*
X1735131Y382885D01*
X1735323Y383247D01*
X1735591Y383505D01*
X1735860Y383557D01*
X1736128Y383454D01*
X1736320Y383195D01*
G01X1738040Y381749D02*
X1738308Y382110D01*
X1738538Y382317D01*
X1738845Y382420D01*
X1739113Y382317D01*
X1739305Y382110D01*
X1739458Y381800D01*
X1739496Y381439D01*
X1739458Y381129D01*
X1739305Y380819D01*
X1739075Y380560D01*
X1738806Y380457D01*
X1738500Y380560D01*
X1738231Y380870D01*
X1738078Y381335D01*
X1738040Y381852D01*
X1738116Y382524D01*
X1738231Y382885D01*
X1738423Y383247D01*
X1738691Y383505D01*
X1738960Y383557D01*
X1739228Y383454D01*
X1739420Y383195D01*
G01X1729086Y376290D02*
X1731039D01*
G01X1729086Y374337D02*
Y376290D01*
G01X1727266Y635244D02*
Y638344D01*
G01X1728876D02*
Y635244D01*
G01Y636794D02*
X1727266D01*
G01X1731171Y635244D02*
Y638344D01*
X1730711Y637724D01*
G01Y635244D02*
X1731631D01*
G01X1733543Y637827D02*
X1733773Y638137D01*
X1734041Y638292D01*
X1734348Y638344D01*
X1734731Y638241D01*
X1734999Y637982D01*
X1735076Y637672D01*
X1735038Y637362D01*
X1734884Y637104D01*
X1734118Y636587D01*
X1733773Y636226D01*
X1733543Y635709D01*
X1733466Y635244D01*
X1735076D01*
G01X1737831D02*
Y638344D01*
X1736413Y636122D01*
X1738329D01*
G01X1727934Y654638D02*
X1721734D01*
G01D02*
Y657838D01*
G01X1727934D02*
Y654638D01*
G01X1724023Y674312D02*
Y672090D01*
X1724176Y671625D01*
X1724483Y671315D01*
X1724866Y671212D01*
X1725249Y671315D01*
X1725556Y671625D01*
X1725709Y672090D01*
Y674312D01*
G01X1727966Y671212D02*
Y674312D01*
X1727506Y673692D01*
G01Y671212D02*
X1728426D01*
G01X1731066Y674312D02*
X1730759Y674209D01*
X1730529Y673950D01*
X1730376Y673640D01*
X1730261Y673227D01*
X1730223Y672762D01*
X1730261Y672297D01*
X1730376Y671884D01*
X1730529Y671574D01*
X1730759Y671315D01*
X1731066Y671212D01*
X1731373Y671315D01*
X1731603Y671574D01*
X1731756Y671884D01*
X1731871Y672297D01*
X1731909Y672762D01*
X1731871Y673227D01*
X1731756Y673640D01*
X1731603Y673950D01*
X1731373Y674209D01*
X1731066Y674312D01*
G01X1733438Y672504D02*
X1733706Y672865D01*
X1733936Y673072D01*
X1734243Y673175D01*
X1734511Y673072D01*
X1734703Y672865D01*
X1734856Y672555D01*
X1734894Y672194D01*
X1734856Y671884D01*
X1734703Y671574D01*
X1734473Y671315D01*
X1734204Y671212D01*
X1733898Y671315D01*
X1733629Y671625D01*
X1733476Y672090D01*
X1733438Y672607D01*
X1733514Y673279D01*
X1733629Y673640D01*
X1733821Y674002D01*
X1734089Y674260D01*
X1734358Y674312D01*
X1734626Y674209D01*
X1734818Y673950D01*
G01X1730404Y659181D02*
X1722264D01*
G01D02*
Y669295D01*
G01D02*
X1730404D01*
G01D02*
Y659181D01*
G01X1721734Y657838D02*
X1727934D01*
G01X1733465Y1293000D02*
Y687244D01*
G01X1731367Y1298763D02*
X1738494D01*
G01X1733465Y1325040D02*
Y1323500D01*
G01X1735494Y1320417D02*
X1731367D01*
G01X1738494Y1317417D02*
X1735494Y1320417D01*
G01X1736151Y1329553D02*
X1733051D01*
Y1330473D01*
X1733206Y1330780D01*
X1733568Y1331010D01*
X1733981Y1331087D01*
X1734394Y1331010D01*
X1734704Y1330818D01*
X1734859Y1330473D01*
Y1329553D01*
G01X1733309Y1334263D02*
X1733154Y1334033D01*
X1733051Y1333765D01*
Y1333458D01*
X1733206Y1333113D01*
X1733464Y1332845D01*
X1733774Y1332653D01*
X1734291Y1332500D01*
X1734756Y1332462D01*
X1735221Y1332538D01*
X1735531Y1332653D01*
X1735841Y1332883D01*
X1736048Y1333152D01*
X1736151Y1333420D01*
Y1333688D01*
X1736048Y1333957D01*
X1735893Y1334187D01*
X1735686Y1334378D01*
G01X1733568Y1335792D02*
X1733258Y1336022D01*
X1733103Y1336290D01*
X1733051Y1336597D01*
X1733154Y1336980D01*
X1733413Y1337248D01*
X1733723Y1337325D01*
X1734033Y1337287D01*
X1734291Y1337133D01*
X1734808Y1336367D01*
X1735169Y1336022D01*
X1735686Y1335792D01*
X1736151Y1335715D01*
Y1337325D01*
G01X1733568Y1338892D02*
X1733258Y1339122D01*
X1733103Y1339390D01*
X1733051Y1339697D01*
X1733154Y1340080D01*
X1733413Y1340348D01*
X1733723Y1340425D01*
X1734033Y1340387D01*
X1734291Y1340233D01*
X1734808Y1339467D01*
X1735169Y1339122D01*
X1735686Y1338892D01*
X1736151Y1338815D01*
Y1340425D01*
G01X1735789Y1342068D02*
X1736048Y1342337D01*
X1736151Y1342643D01*
X1736048Y1342950D01*
X1735738Y1343218D01*
X1735273Y1343410D01*
X1734808Y1343487D01*
X1734239D01*
X1733774Y1343410D01*
X1733361Y1343218D01*
X1733154Y1342988D01*
X1733051Y1342720D01*
X1733154Y1342413D01*
X1733361Y1342183D01*
X1733671Y1342030D01*
X1734084Y1341953D01*
X1734446Y1342030D01*
X1734808Y1342222D01*
X1735014Y1342452D01*
X1735066Y1342720D01*
X1734963Y1343027D01*
X1734704Y1343257D01*
X1734239Y1343487D01*
G01X1726791Y1329553D02*
X1723691D01*
Y1330473D01*
X1723846Y1330780D01*
X1724208Y1331010D01*
X1724621Y1331087D01*
X1725034Y1331010D01*
X1725344Y1330818D01*
X1725499Y1330473D01*
Y1329553D01*
G01X1723949Y1334263D02*
X1723794Y1334033D01*
X1723691Y1333765D01*
Y1333458D01*
X1723846Y1333113D01*
X1724104Y1332845D01*
X1724414Y1332653D01*
X1724931Y1332500D01*
X1725396Y1332462D01*
X1725861Y1332538D01*
X1726171Y1332653D01*
X1726481Y1332883D01*
X1726688Y1333152D01*
X1726791Y1333420D01*
Y1333688D01*
X1726688Y1333957D01*
X1726533Y1334187D01*
X1726326Y1334378D01*
G01X1724208Y1335792D02*
X1723898Y1336022D01*
X1723743Y1336290D01*
X1723691Y1336597D01*
X1723794Y1336980D01*
X1724053Y1337248D01*
X1724363Y1337325D01*
X1724673Y1337287D01*
X1724931Y1337133D01*
X1725448Y1336367D01*
X1725809Y1336022D01*
X1726326Y1335792D01*
X1726791Y1335715D01*
Y1337325D01*
G01X1724208Y1338892D02*
X1723898Y1339122D01*
X1723743Y1339390D01*
X1723691Y1339697D01*
X1723794Y1340080D01*
X1724053Y1340348D01*
X1724363Y1340425D01*
X1724673Y1340387D01*
X1724931Y1340233D01*
X1725448Y1339467D01*
X1725809Y1339122D01*
X1726326Y1338892D01*
X1726791Y1338815D01*
Y1340425D01*
G01Y1342720D02*
X1726739Y1342988D01*
X1726584Y1343295D01*
X1726326Y1343487D01*
X1725964Y1343563D01*
X1725603Y1343487D01*
X1725293Y1343257D01*
X1725138Y1342912D01*
Y1342528D01*
X1725034Y1342298D01*
X1724776Y1342107D01*
X1724414Y1342030D01*
X1724053Y1342145D01*
X1723794Y1342413D01*
X1723691Y1342720D01*
X1723794Y1343027D01*
X1724053Y1343295D01*
X1724414Y1343410D01*
X1724776Y1343333D01*
X1725034Y1343142D01*
X1725138Y1342912D01*
Y1342528D01*
X1725293Y1342183D01*
X1725603Y1341953D01*
X1725964Y1341877D01*
X1726326Y1341953D01*
X1726584Y1342145D01*
X1726739Y1342452D01*
X1726791Y1342720D01*
G01X1731461Y1329543D02*
X1728361D01*
Y1330463D01*
X1728516Y1330770D01*
X1728878Y1331000D01*
X1729291Y1331077D01*
X1729704Y1331000D01*
X1730014Y1330808D01*
X1730169Y1330463D01*
Y1329543D01*
G01X1728619Y1334253D02*
X1728464Y1334023D01*
X1728361Y1333755D01*
Y1333448D01*
X1728516Y1333103D01*
X1728774Y1332835D01*
X1729084Y1332643D01*
X1729601Y1332490D01*
X1730066Y1332452D01*
X1730531Y1332528D01*
X1730841Y1332643D01*
X1731151Y1332873D01*
X1731358Y1333142D01*
X1731461Y1333410D01*
Y1333678D01*
X1731358Y1333947D01*
X1731203Y1334177D01*
X1730996Y1334368D01*
G01X1728878Y1335782D02*
X1728568Y1336012D01*
X1728413Y1336280D01*
X1728361Y1336587D01*
X1728464Y1336970D01*
X1728723Y1337238D01*
X1729033Y1337315D01*
X1729343Y1337277D01*
X1729601Y1337123D01*
X1730118Y1336357D01*
X1730479Y1336012D01*
X1730996Y1335782D01*
X1731461Y1335705D01*
Y1337315D01*
G01X1730841Y1338767D02*
X1731203Y1338997D01*
X1731409Y1339303D01*
X1731461Y1339648D01*
X1731409Y1339955D01*
X1731151Y1340262D01*
X1730841Y1340453D01*
X1730531Y1340492D01*
X1730169Y1340415D01*
X1729911Y1340147D01*
X1729808Y1339878D01*
Y1339533D01*
G01Y1339878D02*
X1729653Y1340108D01*
X1729394Y1340300D01*
X1729084Y1340377D01*
X1728774Y1340300D01*
X1728516Y1340108D01*
X1728361Y1339763D01*
X1728413Y1339418D01*
X1728619Y1339073D01*
G01X1728361Y1342710D02*
X1728464Y1342403D01*
X1728723Y1342173D01*
X1729033Y1342020D01*
X1729446Y1341905D01*
X1729911Y1341867D01*
X1730376Y1341905D01*
X1730789Y1342020D01*
X1731099Y1342173D01*
X1731358Y1342403D01*
X1731461Y1342710D01*
X1731358Y1343017D01*
X1731099Y1343247D01*
X1730789Y1343400D01*
X1730376Y1343515D01*
X1729911Y1343553D01*
X1729446Y1343515D01*
X1729033Y1343400D01*
X1728723Y1343247D01*
X1728464Y1343017D01*
X1728361Y1342710D01*
G01X1733513Y1398580D02*
Y1401680D01*
G01X1735123D02*
Y1398580D01*
G01Y1400130D02*
X1733513D01*
G01X1736575Y1399200D02*
X1736805Y1398838D01*
X1737111Y1398632D01*
X1737456Y1398580D01*
X1737763Y1398632D01*
X1738070Y1398890D01*
X1738261Y1399200D01*
X1738300Y1399510D01*
X1738223Y1399872D01*
X1737955Y1400130D01*
X1737686Y1400233D01*
X1737341D01*
G01X1737686D02*
X1737916Y1400388D01*
X1738108Y1400647D01*
X1738185Y1400957D01*
X1738108Y1401267D01*
X1737916Y1401525D01*
X1737571Y1401680D01*
X1737226Y1401628D01*
X1736881Y1401422D01*
G01X1740978Y1398580D02*
Y1401680D01*
X1739560Y1399458D01*
X1741476D01*
G01X1728479Y1529350D02*
Y1532550D01*
G01X1734679Y1529350D02*
X1728479D01*
G01X1734679Y1532550D02*
Y1529350D01*
G01X1728479Y1532550D02*
X1734679D01*
G01X1728479Y1533650D02*
Y1536850D01*
G01X1734679Y1533650D02*
X1728479D01*
G01X1734679Y1536850D02*
Y1533650D01*
G01X1728479Y1536850D02*
X1734679D01*
G01X1734345Y1550771D02*
Y1553971D01*
G01X1740545Y1550771D02*
X1734345D01*
G01Y1553971D02*
X1740545D01*
G01X1736314Y1561607D02*
Y1567807D01*
G01X1739514Y1561607D02*
X1736314D01*
G01X1737545Y1554771D02*
X1734345D01*
G01Y1560971D02*
X1737545D01*
G01X1734345Y1554771D02*
Y1560971D01*
G01X1736314Y1567807D02*
X1739514D01*
G01Y1568607D02*
X1736314D01*
G01Y1574807D02*
X1737500D01*
G01X1736314Y1568607D02*
Y1574807D01*
G01X1736379Y1575805D02*
Y1582005D01*
G01X1737500Y1575805D02*
X1736379D01*
G01X1728602Y1594493D02*
Y1600693D01*
G01X1731802Y1594493D02*
X1728602D01*
G01X1731802Y1600693D02*
Y1594493D01*
G01X1724602D02*
Y1600693D01*
G01X1727802Y1594493D02*
X1724602D01*
G01X1727802Y1600693D02*
Y1594493D01*
G01X1736379Y1582005D02*
X1739579D01*
G01X1728602Y1600693D02*
X1731802D01*
G01X1724602D02*
X1727802D01*
G01X1733829Y1647856D02*
Y1651056D01*
G01X1740029Y1647856D02*
X1733829D01*
G01Y1651056D02*
X1740029D01*
G01X1725363Y1670865D02*
Y1674065D01*
G01X1731563Y1670865D02*
X1725363D01*
G01X1731563Y1674065D02*
Y1670865D01*
G01X1725363Y1661865D02*
Y1665065D01*
G01X1731563Y1661865D02*
X1725363D01*
G01X1731563Y1665065D02*
Y1661865D01*
G01X1725363Y1665065D02*
X1731563D01*
G01X1725363Y1666365D02*
Y1669565D01*
G01X1731563Y1666365D02*
X1725363D01*
G01X1731563Y1669565D02*
Y1666365D01*
G01X1725363Y1669565D02*
X1731563D01*
G01X1725363Y1657365D02*
Y1660565D01*
G01X1731563Y1657365D02*
X1725363D01*
G01X1731563Y1660565D02*
Y1657365D01*
G01X1725363Y1660565D02*
X1731563D01*
G01X1734500Y1661417D02*
X1734750Y1661257D01*
X1734875Y1661070D01*
X1734917Y1660857D01*
X1734834Y1660590D01*
X1734625Y1660403D01*
X1734375Y1660350D01*
X1734125Y1660377D01*
X1733917Y1660483D01*
X1733500Y1661017D01*
X1733209Y1661257D01*
X1732792Y1661417D01*
X1732417Y1661470D01*
Y1660350D01*
G01X1734917Y1658710D02*
X1734834Y1658923D01*
X1734625Y1659083D01*
X1734375Y1659190D01*
X1734042Y1659270D01*
X1733667Y1659297D01*
X1733292Y1659270D01*
X1732959Y1659190D01*
X1732709Y1659083D01*
X1732500Y1658923D01*
X1732417Y1658710D01*
X1732500Y1658497D01*
X1732709Y1658337D01*
X1732959Y1658230D01*
X1733292Y1658150D01*
X1733667Y1658123D01*
X1734042Y1658150D01*
X1734375Y1658230D01*
X1734625Y1658337D01*
X1734834Y1658497D01*
X1734917Y1658710D01*
G01X1735029Y1661956D02*
X1738029D01*
G01X1737979Y1669756D02*
X1736479D01*
G01X1731563Y1683065D02*
Y1679865D01*
G01X1725363Y1683065D02*
X1731563D01*
G01X1725363Y1679865D02*
Y1683065D01*
G01X1731563Y1679865D02*
X1725363D01*
G01X1723823Y1685556D02*
Y1691756D01*
G01X1727023Y1685556D02*
X1723823D01*
G01X1727023Y1691756D02*
Y1685556D01*
G01X1731563Y1678565D02*
Y1675365D01*
G01X1725363Y1678565D02*
X1731563D01*
G01X1725363Y1675365D02*
Y1678565D01*
G01X1731563Y1675365D02*
X1725363D01*
G01X1727836Y1685565D02*
Y1691765D01*
G01X1731036Y1685565D02*
X1727836D01*
G01X1731036Y1691765D02*
Y1685565D01*
G01X1722445Y1678434D02*
Y1672234D01*
G01X1725363Y1674065D02*
X1731563D01*
G01X1733440Y1681274D02*
X1735940D01*
X1735440Y1681594D01*
G01X1733440D02*
Y1680954D01*
G01Y1679074D02*
X1735940D01*
X1735440Y1679394D01*
G01X1733440D02*
Y1678754D01*
G01X1723823Y1691756D02*
X1727023D01*
G01X1733863Y1693565D02*
X1737063D01*
G01X1733863Y1687365D02*
Y1693565D01*
G01X1737063Y1687365D02*
X1733863D01*
G01X1727836Y1691765D02*
X1731036D01*
G01X1727033Y1703590D02*
Y1709790D01*
G01X1730233Y1703590D02*
X1727033D01*
G01Y1709790D02*
X1730233D01*
G01D02*
Y1703590D01*
G01X1723033Y1710590D02*
Y1716790D01*
G01X1726233D02*
Y1710590D01*
G01D02*
X1723033D01*
G01X1730233Y1716790D02*
Y1710590D01*
G01D02*
X1727033D01*
G01D02*
Y1716790D01*
G01X1726233Y1703590D02*
X1723033D01*
G01X1726233Y1709790D02*
Y1703590D01*
G01X1723033Y1709790D02*
X1726233D01*
G01X1723033Y1703590D02*
Y1709790D01*
G01X1746127Y1706493D02*
X1735633D01*
G01D02*
Y1715155D01*
G01D02*
X1738980D01*
G01X1730233Y1724940D02*
Y1718740D01*
G01D02*
X1727033D01*
G01D02*
Y1724940D01*
G01D02*
X1730233D01*
G01X1734233Y1728090D02*
Y1721890D01*
G01D02*
X1731033D01*
G01D02*
Y1728090D01*
G01D02*
X1734233D01*
G01X1730233Y1731940D02*
Y1725740D01*
G01D02*
X1727033D01*
G01D02*
Y1731940D01*
G01X1723033Y1718740D02*
Y1724940D01*
G01D02*
X1726233D01*
G01Y1718740D02*
X1723033D01*
G01X1726233Y1724940D02*
Y1718740D01*
G01X1723033Y1725740D02*
Y1731940D01*
G01X1726233Y1725740D02*
X1723033D01*
G01X1726233Y1731940D02*
Y1725740D01*
G01X1723033Y1716790D02*
X1726233D01*
G01X1727033D02*
X1730233D01*
G01X1736430Y1731541D02*
X1736123Y1731593D01*
X1735855Y1731799D01*
X1735625Y1732109D01*
X1735472Y1732471D01*
X1735395Y1732884D01*
Y1733298D01*
X1735472Y1733711D01*
X1735625Y1734073D01*
X1735855Y1734383D01*
X1736123Y1734589D01*
X1736430Y1734641D01*
X1736737Y1734589D01*
X1737005Y1734383D01*
X1737235Y1734073D01*
X1737388Y1733711D01*
X1737465Y1733298D01*
Y1732884D01*
X1737388Y1732471D01*
X1737235Y1732109D01*
X1737005Y1731799D01*
X1736737Y1731593D01*
X1736430Y1731541D01*
G01X1736737Y1732368D02*
X1737197Y1731541D01*
G01X1739530D02*
Y1734641D01*
X1739070Y1734021D01*
G01Y1731541D02*
X1739990D01*
G01X1741787Y1732161D02*
X1742017Y1731799D01*
X1742323Y1731593D01*
X1742668Y1731541D01*
X1742975Y1731593D01*
X1743282Y1731851D01*
X1743473Y1732161D01*
X1743512Y1732471D01*
X1743435Y1732833D01*
X1743167Y1733091D01*
X1742898Y1733194D01*
X1742553D01*
G01X1742898D02*
X1743128Y1733349D01*
X1743320Y1733608D01*
X1743397Y1733918D01*
X1743320Y1734228D01*
X1743128Y1734486D01*
X1742783Y1734641D01*
X1742438Y1734589D01*
X1742093Y1734383D01*
G01X1745002Y1732833D02*
X1745270Y1733194D01*
X1745500Y1733401D01*
X1745807Y1733504D01*
X1746075Y1733401D01*
X1746267Y1733194D01*
X1746420Y1732884D01*
X1746458Y1732523D01*
X1746420Y1732213D01*
X1746267Y1731903D01*
X1746037Y1731644D01*
X1745768Y1731541D01*
X1745462Y1731644D01*
X1745193Y1731954D01*
X1745040Y1732419D01*
X1745002Y1732936D01*
X1745078Y1733608D01*
X1745193Y1733969D01*
X1745385Y1734331D01*
X1745653Y1734589D01*
X1745922Y1734641D01*
X1746190Y1734538D01*
X1746382Y1734279D01*
G01X1746127Y1721643D02*
X1735633D01*
G01D02*
Y1730305D01*
G01D02*
X1738980D01*
G01X1736126Y1717758D02*
X1735819Y1717810D01*
X1735551Y1718016D01*
X1735321Y1718326D01*
X1735168Y1718688D01*
X1735091Y1719101D01*
Y1719515D01*
X1735168Y1719928D01*
X1735321Y1720290D01*
X1735551Y1720600D01*
X1735819Y1720806D01*
X1736126Y1720858D01*
X1736433Y1720806D01*
X1736701Y1720600D01*
X1736931Y1720290D01*
X1737084Y1719928D01*
X1737161Y1719515D01*
Y1719101D01*
X1737084Y1718688D01*
X1736931Y1718326D01*
X1736701Y1718016D01*
X1736433Y1717810D01*
X1736126Y1717758D01*
G01X1736433Y1718585D02*
X1736893Y1717758D01*
G01X1739226D02*
Y1720858D01*
X1738766Y1720238D01*
G01Y1717758D02*
X1739686D01*
G01X1742326Y1720858D02*
X1742019Y1720755D01*
X1741789Y1720496D01*
X1741636Y1720186D01*
X1741521Y1719773D01*
X1741483Y1719308D01*
X1741521Y1718843D01*
X1741636Y1718430D01*
X1741789Y1718120D01*
X1742019Y1717861D01*
X1742326Y1717758D01*
X1742633Y1717861D01*
X1742863Y1718120D01*
X1743016Y1718430D01*
X1743131Y1718843D01*
X1743169Y1719308D01*
X1743131Y1719773D01*
X1743016Y1720186D01*
X1742863Y1720496D01*
X1742633Y1720755D01*
X1742326Y1720858D01*
G01X1744698Y1719050D02*
X1744966Y1719411D01*
X1745196Y1719618D01*
X1745503Y1719721D01*
X1745771Y1719618D01*
X1745963Y1719411D01*
X1746116Y1719101D01*
X1746154Y1718740D01*
X1746116Y1718430D01*
X1745963Y1718120D01*
X1745733Y1717861D01*
X1745464Y1717758D01*
X1745158Y1717861D01*
X1744889Y1718171D01*
X1744736Y1718636D01*
X1744698Y1719153D01*
X1744774Y1719825D01*
X1744889Y1720186D01*
X1745081Y1720548D01*
X1745349Y1720806D01*
X1745618Y1720858D01*
X1745886Y1720755D01*
X1746078Y1720496D01*
G01X1727033Y1731940D02*
X1730233D01*
G01X1723033D02*
X1726233D01*
G01X1736965Y55251D02*
Y52051D01*
G01Y59251D02*
Y56051D01*
G01X1739596Y66051D02*
Y60051D01*
G01X1742124Y53058D02*
X1742316Y52748D01*
X1742546Y52541D01*
X1742814Y52438D01*
X1743121Y52541D01*
X1743351Y52748D01*
X1743581Y53058D01*
X1743658Y53471D01*
Y55538D01*
G01X1745148Y53058D02*
X1745378Y52696D01*
X1745684Y52490D01*
X1746029Y52438D01*
X1746336Y52490D01*
X1746643Y52748D01*
X1746834Y53058D01*
X1746873Y53368D01*
X1746796Y53730D01*
X1746528Y53988D01*
X1746259Y54091D01*
X1745914D01*
G01X1746259D02*
X1746489Y54246D01*
X1746681Y54505D01*
X1746758Y54815D01*
X1746681Y55125D01*
X1746489Y55383D01*
X1746144Y55538D01*
X1745799Y55486D01*
X1745454Y55280D01*
G01X1749091Y52438D02*
X1749359Y52490D01*
X1749666Y52645D01*
X1749858Y52903D01*
X1749934Y53265D01*
X1749858Y53626D01*
X1749628Y53936D01*
X1749283Y54091D01*
X1748899D01*
X1748669Y54195D01*
X1748478Y54453D01*
X1748401Y54815D01*
X1748516Y55176D01*
X1748784Y55435D01*
X1749091Y55538D01*
X1749398Y55435D01*
X1749666Y55176D01*
X1749781Y54815D01*
X1749704Y54453D01*
X1749513Y54195D01*
X1749283Y54091D01*
X1748899D01*
X1748554Y53936D01*
X1748324Y53626D01*
X1748248Y53265D01*
X1748324Y52903D01*
X1748516Y52645D01*
X1748823Y52490D01*
X1749091Y52438D01*
G01X1741383Y63000D02*
Y66100D01*
X1742342D01*
X1742648Y65945D01*
X1742840Y65738D01*
X1742917Y65325D01*
X1742840Y64912D01*
X1742610Y64653D01*
X1742342Y64498D01*
X1741383D01*
G01X1742342D02*
X1742917Y63000D01*
G01X1745250D02*
Y66100D01*
X1744790Y65480D01*
G01Y63000D02*
X1745710D01*
G01X1747507Y63620D02*
X1747737Y63258D01*
X1748043Y63052D01*
X1748388Y63000D01*
X1748695Y63052D01*
X1749002Y63310D01*
X1749193Y63620D01*
X1749232Y63930D01*
X1749155Y64292D01*
X1748887Y64550D01*
X1748618Y64653D01*
X1748273D01*
G01X1748618D02*
X1748848Y64808D01*
X1749040Y65067D01*
X1749117Y65377D01*
X1749040Y65687D01*
X1748848Y65945D01*
X1748503Y66100D01*
X1748158Y66048D01*
X1747813Y65842D01*
G01X1750722Y65583D02*
X1750952Y65893D01*
X1751220Y66048D01*
X1751527Y66100D01*
X1751910Y65997D01*
X1752178Y65738D01*
X1752255Y65428D01*
X1752217Y65118D01*
X1752063Y64860D01*
X1751297Y64343D01*
X1750952Y63982D01*
X1750722Y63465D01*
X1750645Y63000D01*
X1752255D01*
G01X1755010D02*
Y66100D01*
X1753592Y63878D01*
X1755508D01*
G01X1744909Y90864D02*
Y87664D01*
G01X1738709Y90864D02*
X1744909D01*
G01X1738709Y87664D02*
Y90864D01*
G01X1744909Y87664D02*
X1738709D01*
G01X1748409Y86939D02*
Y83739D01*
G01X1742209Y86939D02*
X1748409D01*
G01X1742209Y83739D02*
Y86939D01*
G01X1748409Y83739D02*
X1742209D01*
G01X1741409Y86939D02*
Y83739D01*
G01X1737718Y91427D02*
Y88227D01*
G01X1760142Y90075D02*
X1748142D01*
G01D02*
Y96075D01*
G01X1747288Y98707D02*
Y101907D01*
G01X1753488Y98707D02*
X1747288D01*
G01Y101907D02*
X1753488D01*
G01X1748142Y96075D02*
X1760142D01*
G01X1750422Y104825D02*
X1751587D01*
G01Y117029D02*
X1750414D01*
G01X1745318Y123567D02*
Y129767D01*
G01D02*
X1748518D01*
G01D02*
Y123567D01*
G01D02*
X1745318D01*
G01X1738018Y129767D02*
Y123567D01*
G01X1752518D02*
X1749318D01*
G01D02*
Y129767D01*
G01D02*
X1752518D01*
G01X1741818Y127067D02*
Y133267D01*
G01D02*
X1745018D01*
G01D02*
Y127067D01*
G01D02*
X1741818D01*
G01X1739147Y134719D02*
Y137819D01*
X1740067D01*
X1740374Y137664D01*
X1740604Y137302D01*
X1740681Y136889D01*
X1740604Y136476D01*
X1740412Y136166D01*
X1740067Y136011D01*
X1739147D01*
G01X1742171Y137819D02*
Y135597D01*
X1742324Y135132D01*
X1742631Y134822D01*
X1743014Y134719D01*
X1743397Y134822D01*
X1743704Y135132D01*
X1743857Y135597D01*
Y137819D01*
G01X1745386Y137302D02*
X1745616Y137612D01*
X1745884Y137767D01*
X1746191Y137819D01*
X1746574Y137716D01*
X1746842Y137457D01*
X1746919Y137147D01*
X1746881Y136837D01*
X1746727Y136579D01*
X1745961Y136062D01*
X1745616Y135701D01*
X1745386Y135184D01*
X1745309Y134719D01*
X1746919D01*
G01X1749214Y137819D02*
X1748907Y137716D01*
X1748677Y137457D01*
X1748524Y137147D01*
X1748409Y136734D01*
X1748371Y136269D01*
X1748409Y135804D01*
X1748524Y135391D01*
X1748677Y135081D01*
X1748907Y134822D01*
X1749214Y134719D01*
X1749521Y134822D01*
X1749751Y135081D01*
X1749904Y135391D01*
X1750019Y135804D01*
X1750057Y136269D01*
X1750019Y136734D01*
X1749904Y137147D01*
X1749751Y137457D01*
X1749521Y137716D01*
X1749214Y137819D01*
G01X1752774Y134719D02*
Y137819D01*
X1751356Y135597D01*
X1753272D01*
G01X1753788Y181096D02*
X1747788D01*
G01D02*
Y193096D01*
G01D02*
X1753788D01*
G01X1752833Y203402D02*
X1746833D01*
G01D02*
Y215402D01*
G01D02*
X1752833D01*
G01X1750383Y262737D02*
X1753583D01*
G01X1750383Y256537D02*
Y262737D01*
G01X1753583Y256537D02*
X1750383D01*
G01X1748504Y265792D02*
X1747871D01*
G01X1748504Y284296D02*
Y265792D01*
G01X1751761Y271836D02*
Y274936D01*
X1752681D01*
X1752988Y274781D01*
X1753218Y274419D01*
X1753295Y274006D01*
X1753218Y273593D01*
X1753026Y273283D01*
X1752681Y273128D01*
X1751761D01*
G01X1756471Y274678D02*
X1756241Y274833D01*
X1755973Y274936D01*
X1755666D01*
X1755321Y274781D01*
X1755053Y274523D01*
X1754861Y274213D01*
X1754708Y273696D01*
X1754670Y273231D01*
X1754746Y272766D01*
X1754861Y272456D01*
X1755091Y272146D01*
X1755360Y271939D01*
X1755628Y271836D01*
X1755896D01*
X1756165Y271939D01*
X1756395Y272094D01*
X1756586Y272301D01*
G01X1758728Y271836D02*
Y274936D01*
X1758268Y274316D01*
G01Y271836D02*
X1759188D01*
G01X1761828D02*
X1762096Y271888D01*
X1762403Y272043D01*
X1762595Y272301D01*
X1762671Y272663D01*
X1762595Y273024D01*
X1762365Y273334D01*
X1762020Y273489D01*
X1761636D01*
X1761406Y273593D01*
X1761215Y273851D01*
X1761138Y274213D01*
X1761253Y274574D01*
X1761521Y274833D01*
X1761828Y274936D01*
X1762135Y274833D01*
X1762403Y274574D01*
X1762518Y274213D01*
X1762441Y273851D01*
X1762250Y273593D01*
X1762020Y273489D01*
X1761636D01*
X1761291Y273334D01*
X1761061Y273024D01*
X1760985Y272663D01*
X1761061Y272301D01*
X1761253Y272043D01*
X1761560Y271888D01*
X1761828Y271836D01*
G01X1764200Y273128D02*
X1764468Y273489D01*
X1764698Y273696D01*
X1765005Y273799D01*
X1765273Y273696D01*
X1765465Y273489D01*
X1765618Y273179D01*
X1765656Y272818D01*
X1765618Y272508D01*
X1765465Y272198D01*
X1765235Y271939D01*
X1764966Y271836D01*
X1764660Y271939D01*
X1764391Y272249D01*
X1764238Y272714D01*
X1764200Y273231D01*
X1764276Y273903D01*
X1764391Y274264D01*
X1764583Y274626D01*
X1764851Y274884D01*
X1765120Y274936D01*
X1765388Y274833D01*
X1765580Y274574D01*
G01X1767951Y271836D02*
X1768028Y272508D01*
X1768143Y273076D01*
X1768296Y273593D01*
X1768488Y274161D01*
X1768795Y274936D01*
X1767261D01*
G01X1747671Y284296D02*
X1748504D01*
G01X1742567Y296637D02*
Y302637D01*
G01X1754567Y296637D02*
X1742567D01*
G01X1744510Y306706D02*
X1750710D01*
G01D02*
Y303506D01*
G01D02*
X1744510D01*
G01D02*
Y306706D01*
G01X1742567Y302637D02*
X1754567D01*
G01X1749487Y365648D02*
X1755687D01*
G01X1749487Y362448D02*
Y365648D01*
G01X1755687Y362448D02*
X1749487D01*
G01Y369648D02*
X1755687D01*
G01X1749487Y366448D02*
Y369648D01*
G01X1755687Y366448D02*
X1749487D01*
G01X1749620Y370852D02*
Y374052D01*
G01X1755820Y370852D02*
X1749620D01*
G01Y374052D02*
X1755820D01*
G01X1740898Y364478D02*
X1738945D01*
G01X1740898Y366431D02*
Y364478D01*
G01X1749620Y379052D02*
X1755820D01*
G01X1749620Y375852D02*
Y379052D01*
G01X1755820Y375852D02*
X1749620D01*
G01Y384552D02*
X1755820D01*
G01X1749620Y381352D02*
Y384552D01*
G01X1755820Y381352D02*
X1749620D01*
G01X1740898Y376290D02*
Y374337D01*
G01X1738945Y376290D02*
X1740898D01*
G01X1744177Y666616D02*
X1737977D01*
G01D02*
Y669816D01*
G01D02*
X1744177D01*
G01D02*
Y666616D01*
G01Y662616D02*
X1737977D01*
G01D02*
Y665816D01*
G01D02*
X1744177D01*
G01D02*
Y662616D01*
G01X1740082Y683335D02*
X1740274Y683025D01*
X1740504Y682818D01*
X1740772Y682715D01*
X1741079Y682818D01*
X1741309Y683025D01*
X1741539Y683335D01*
X1741616Y683748D01*
Y685815D01*
G01X1743221Y685298D02*
X1743451Y685608D01*
X1743719Y685763D01*
X1744026Y685815D01*
X1744409Y685712D01*
X1744677Y685453D01*
X1744754Y685143D01*
X1744716Y684833D01*
X1744562Y684575D01*
X1743796Y684058D01*
X1743451Y683697D01*
X1743221Y683180D01*
X1743144Y682715D01*
X1744754D01*
G01X1747049Y685815D02*
X1746742Y685712D01*
X1746512Y685453D01*
X1746359Y685143D01*
X1746244Y684730D01*
X1746206Y684265D01*
X1746244Y683800D01*
X1746359Y683387D01*
X1746512Y683077D01*
X1746742Y682818D01*
X1747049Y682715D01*
X1747356Y682818D01*
X1747586Y683077D01*
X1747739Y683387D01*
X1747854Y683800D01*
X1747892Y684265D01*
X1747854Y684730D01*
X1747739Y685143D01*
X1747586Y685453D01*
X1747356Y685712D01*
X1747049Y685815D01*
G01X1737576Y687244D02*
Y1293000D01*
G01X1763166Y687244D02*
X1737576D01*
G01X1763166Y720709D02*
X1737576D01*
G01X1763166Y1291575D02*
X1737576D01*
G01X1738494Y1298763D02*
Y1317417D01*
G01X1737576Y1323500D02*
Y1325040D01*
G01D02*
X1763166D01*
G01X1740836Y1329583D02*
X1737736D01*
Y1330503D01*
X1737891Y1330810D01*
X1738253Y1331040D01*
X1738666Y1331117D01*
X1739079Y1331040D01*
X1739389Y1330848D01*
X1739544Y1330503D01*
Y1329583D01*
G01X1737994Y1334293D02*
X1737839Y1334063D01*
X1737736Y1333795D01*
Y1333488D01*
X1737891Y1333143D01*
X1738149Y1332875D01*
X1738459Y1332683D01*
X1738976Y1332530D01*
X1739441Y1332492D01*
X1739906Y1332568D01*
X1740216Y1332683D01*
X1740526Y1332913D01*
X1740733Y1333182D01*
X1740836Y1333450D01*
Y1333718D01*
X1740733Y1333987D01*
X1740578Y1334217D01*
X1740371Y1334408D01*
G01X1740836Y1336550D02*
X1740784Y1336818D01*
X1740629Y1337125D01*
X1740371Y1337317D01*
X1740009Y1337393D01*
X1739648Y1337317D01*
X1739338Y1337087D01*
X1739183Y1336742D01*
Y1336358D01*
X1739079Y1336128D01*
X1738821Y1335937D01*
X1738459Y1335860D01*
X1738098Y1335975D01*
X1737839Y1336243D01*
X1737736Y1336550D01*
X1737839Y1336857D01*
X1738098Y1337125D01*
X1738459Y1337240D01*
X1738821Y1337163D01*
X1739079Y1336972D01*
X1739183Y1336742D01*
Y1336358D01*
X1739338Y1336013D01*
X1739648Y1335783D01*
X1740009Y1335707D01*
X1740371Y1335783D01*
X1740629Y1335975D01*
X1740784Y1336282D01*
X1740836Y1336550D01*
G01X1737736Y1339650D02*
X1737839Y1339343D01*
X1738098Y1339113D01*
X1738408Y1338960D01*
X1738821Y1338845D01*
X1739286Y1338807D01*
X1739751Y1338845D01*
X1740164Y1338960D01*
X1740474Y1339113D01*
X1740733Y1339343D01*
X1740836Y1339650D01*
X1740733Y1339957D01*
X1740474Y1340187D01*
X1740164Y1340340D01*
X1739751Y1340455D01*
X1739286Y1340493D01*
X1738821Y1340455D01*
X1738408Y1340340D01*
X1738098Y1340187D01*
X1737839Y1339957D01*
X1737736Y1339650D01*
G01X1740836Y1342750D02*
X1737736D01*
X1738356Y1342290D01*
G01X1740836D02*
Y1343210D01*
G01X1748200Y1404261D02*
X1757861Y1394600D01*
Y1395215D01*
X1748739Y1404337D01*
Y1404393D01*
X1749265D01*
X1757918Y1395740D01*
Y1395665D01*
X1757936Y1395683D01*
Y1396342D01*
X1749922Y1404356D01*
X1750476D01*
X1757947Y1396885D01*
X1758012D01*
Y1397486D01*
X1751293Y1404205D01*
X1751217D01*
X1751292Y1404130D01*
X1751911D01*
X1757880Y1398161D01*
Y1397843D01*
X1757974Y1397937D01*
Y1398800D01*
X1752680Y1404094D01*
X1752349D01*
X1752367Y1404112D01*
X1753268D01*
X1758073Y1399307D01*
Y1399157D01*
X1758055Y1399175D01*
Y1399983D01*
X1753850Y1404188D01*
X1753437D01*
X1753512Y1404263D01*
X1754319D01*
X1757942Y1400640D01*
Y1400452D01*
X1757961Y1400471D01*
Y1401353D01*
X1755145Y1404169D01*
X1754807D01*
X1754919Y1404281D01*
X1755577D01*
X1757923Y1401935D01*
Y1402686D01*
X1756365Y1404244D01*
X1755971D01*
X1756084Y1404131D01*
X1756928D01*
X1757904Y1403155D01*
Y1403136D01*
X1757829Y1403211D01*
Y1403831D01*
X1757491Y1404169D01*
X1757323D01*
X1757379Y1404225D01*
X1757810D01*
X1757998Y1404037D01*
G01X1747073Y1404158D02*
X1747251D01*
X1757939Y1393470D01*
Y1394014D01*
X1747692Y1404261D01*
X1748200D01*
X1757861Y1394600D01*
Y1394502D01*
G01X1746338Y1404449D02*
X1758149Y1392638D01*
G01Y1404449D02*
X1746338D01*
G01X1737189Y1414262D02*
Y1410854D01*
G01Y1428570D02*
Y1425162D01*
G01X1738397Y1433405D02*
Y1436605D01*
G01X1744597Y1433405D02*
X1738397D01*
G01X1744597Y1436605D02*
Y1433405D01*
G01X1738397Y1436605D02*
X1744597D01*
G01X1739383Y1476500D02*
Y1479600D01*
X1740303D01*
X1740610Y1479445D01*
X1740840Y1479083D01*
X1740917Y1478670D01*
X1740840Y1478257D01*
X1740648Y1477947D01*
X1740303Y1477792D01*
X1739383D01*
G01X1744093Y1479342D02*
X1743863Y1479497D01*
X1743595Y1479600D01*
X1743288D01*
X1742943Y1479445D01*
X1742675Y1479187D01*
X1742483Y1478877D01*
X1742330Y1478360D01*
X1742292Y1477895D01*
X1742368Y1477430D01*
X1742483Y1477120D01*
X1742713Y1476810D01*
X1742982Y1476603D01*
X1743250Y1476500D01*
X1743518D01*
X1743787Y1476603D01*
X1744017Y1476758D01*
X1744208Y1476965D01*
G01X1745622Y1477792D02*
X1745890Y1478153D01*
X1746120Y1478360D01*
X1746427Y1478463D01*
X1746695Y1478360D01*
X1746887Y1478153D01*
X1747040Y1477843D01*
X1747078Y1477482D01*
X1747040Y1477172D01*
X1746887Y1476862D01*
X1746657Y1476603D01*
X1746388Y1476500D01*
X1746082Y1476603D01*
X1745813Y1476913D01*
X1745660Y1477378D01*
X1745622Y1477895D01*
X1745698Y1478567D01*
X1745813Y1478928D01*
X1746005Y1479290D01*
X1746273Y1479548D01*
X1746542Y1479600D01*
X1746810Y1479497D01*
X1747002Y1479238D01*
G01X1748607Y1476965D02*
X1748837Y1476707D01*
X1749105Y1476552D01*
X1749450Y1476500D01*
X1749795Y1476603D01*
X1750063Y1476810D01*
X1750255Y1477172D01*
X1750293Y1477585D01*
X1750217Y1477998D01*
X1750025Y1478257D01*
X1749757Y1478463D01*
X1749488Y1478515D01*
X1749220Y1478463D01*
X1748875Y1478257D01*
X1748990Y1479600D01*
X1750025D01*
G01X1752473Y1476500D02*
X1752550Y1477172D01*
X1752665Y1477740D01*
X1752818Y1478257D01*
X1753010Y1478825D01*
X1753317Y1479600D01*
X1751783D01*
G01X1755650Y1476500D02*
Y1479600D01*
X1755190Y1478980D01*
G01Y1476500D02*
X1756110D01*
G01X1751179Y1485778D02*
X1758306D01*
G01X1736652D02*
X1743779D01*
G01X1736652Y1504432D02*
Y1485778D01*
G01X1739652Y1507432D02*
X1736652Y1504432D01*
G01X1755306Y1507432D02*
X1751179D01*
G01X1743779D02*
X1739652D01*
G01X1742288Y1529504D02*
X1739088D01*
G01X1742288Y1535704D02*
Y1529504D01*
G01X1739088Y1535704D02*
X1742288D01*
G01X1739088Y1529504D02*
Y1535704D01*
G01X1745609Y1522941D02*
Y1548531D01*
G01X1749604Y1522941D02*
X1745609D01*
G01X1740545Y1553971D02*
Y1550771D01*
G01X1745609Y1548531D02*
X1749604D01*
G01X1739514Y1567807D02*
Y1561607D01*
G01X1737545Y1560971D02*
Y1554771D01*
G01X1742645Y1561358D02*
Y1563056D01*
G01Y1552147D02*
Y1554747D01*
G01X1743438Y1552147D02*
X1742645D01*
G01X1739514Y1574000D02*
Y1568607D01*
G01X1739579Y1582005D02*
Y1577800D01*
G01X1742645Y1575769D02*
X1743653D01*
G01X1742645Y1573915D02*
Y1575769D01*
G01X1740879Y1582878D02*
X1737679D01*
G01X1740879Y1589078D02*
Y1582878D01*
G01X1737679Y1589078D02*
X1740879D01*
G01X1737679Y1582878D02*
Y1589078D01*
G01X1747379Y1584305D02*
Y1587505D01*
G01X1753579Y1584305D02*
X1747379D01*
G01Y1587505D02*
X1753579D01*
G01X1737146Y1591427D02*
Y1594527D01*
X1738066D01*
X1738373Y1594372D01*
X1738603Y1594010D01*
X1738680Y1593597D01*
X1738603Y1593184D01*
X1738411Y1592874D01*
X1738066Y1592719D01*
X1737146D01*
G01X1740170Y1594527D02*
Y1592305D01*
X1740323Y1591840D01*
X1740630Y1591530D01*
X1741013Y1591427D01*
X1741396Y1591530D01*
X1741703Y1591840D01*
X1741856Y1592305D01*
Y1594527D01*
G01X1743385Y1592719D02*
X1743653Y1593080D01*
X1743883Y1593287D01*
X1744190Y1593390D01*
X1744458Y1593287D01*
X1744650Y1593080D01*
X1744803Y1592770D01*
X1744841Y1592409D01*
X1744803Y1592099D01*
X1744650Y1591789D01*
X1744420Y1591530D01*
X1744151Y1591427D01*
X1743845Y1591530D01*
X1743576Y1591840D01*
X1743423Y1592305D01*
X1743385Y1592822D01*
X1743461Y1593494D01*
X1743576Y1593855D01*
X1743768Y1594217D01*
X1744036Y1594475D01*
X1744305Y1594527D01*
X1744573Y1594424D01*
X1744765Y1594165D01*
G01X1746370Y1591892D02*
X1746600Y1591634D01*
X1746868Y1591479D01*
X1747213Y1591427D01*
X1747558Y1591530D01*
X1747826Y1591737D01*
X1748018Y1592099D01*
X1748056Y1592512D01*
X1747980Y1592925D01*
X1747788Y1593184D01*
X1747520Y1593390D01*
X1747251Y1593442D01*
X1746983Y1593390D01*
X1746638Y1593184D01*
X1746753Y1594527D01*
X1747788D01*
G01X1750313D02*
X1750006Y1594424D01*
X1749776Y1594165D01*
X1749623Y1593855D01*
X1749508Y1593442D01*
X1749470Y1592977D01*
X1749508Y1592512D01*
X1749623Y1592099D01*
X1749776Y1591789D01*
X1750006Y1591530D01*
X1750313Y1591427D01*
X1750620Y1591530D01*
X1750850Y1591789D01*
X1751003Y1592099D01*
X1751118Y1592512D01*
X1751156Y1592977D01*
X1751118Y1593442D01*
X1751003Y1593855D01*
X1750850Y1594165D01*
X1750620Y1594424D01*
X1750313Y1594527D01*
G01X1752570Y1592047D02*
X1752800Y1591685D01*
X1753106Y1591479D01*
X1753451Y1591427D01*
X1753758Y1591479D01*
X1754065Y1591737D01*
X1754256Y1592047D01*
X1754295Y1592357D01*
X1754218Y1592719D01*
X1753950Y1592977D01*
X1753681Y1593080D01*
X1753336D01*
G01X1753681D02*
X1753911Y1593235D01*
X1754103Y1593494D01*
X1754180Y1593804D01*
X1754103Y1594114D01*
X1753911Y1594372D01*
X1753566Y1594527D01*
X1753221Y1594475D01*
X1752876Y1594269D01*
G01X1742984Y1617950D02*
Y1610823D01*
X1761638D01*
X1764638Y1613823D01*
Y1617950D01*
G01X1761638Y1632477D02*
X1742984D01*
Y1625350D01*
G01X1743383Y1634000D02*
Y1637100D01*
X1744303D01*
X1744610Y1636945D01*
X1744840Y1636583D01*
X1744917Y1636170D01*
X1744840Y1635757D01*
X1744648Y1635447D01*
X1744303Y1635292D01*
X1743383D01*
G01X1748093Y1636842D02*
X1747863Y1636997D01*
X1747595Y1637100D01*
X1747288D01*
X1746943Y1636945D01*
X1746675Y1636687D01*
X1746483Y1636377D01*
X1746330Y1635860D01*
X1746292Y1635395D01*
X1746368Y1634930D01*
X1746483Y1634620D01*
X1746713Y1634310D01*
X1746982Y1634103D01*
X1747250Y1634000D01*
X1747518D01*
X1747787Y1634103D01*
X1748017Y1634258D01*
X1748208Y1634465D01*
G01X1749622Y1635292D02*
X1749890Y1635653D01*
X1750120Y1635860D01*
X1750427Y1635963D01*
X1750695Y1635860D01*
X1750887Y1635653D01*
X1751040Y1635343D01*
X1751078Y1634982D01*
X1751040Y1634672D01*
X1750887Y1634362D01*
X1750657Y1634103D01*
X1750388Y1634000D01*
X1750082Y1634103D01*
X1749813Y1634413D01*
X1749660Y1634878D01*
X1749622Y1635395D01*
X1749698Y1636067D01*
X1749813Y1636428D01*
X1750005Y1636790D01*
X1750273Y1637048D01*
X1750542Y1637100D01*
X1750810Y1636997D01*
X1751002Y1636738D01*
G01X1752607Y1634465D02*
X1752837Y1634207D01*
X1753105Y1634052D01*
X1753450Y1634000D01*
X1753795Y1634103D01*
X1754063Y1634310D01*
X1754255Y1634672D01*
X1754293Y1635085D01*
X1754217Y1635498D01*
X1754025Y1635757D01*
X1753757Y1635963D01*
X1753488Y1636015D01*
X1753220Y1635963D01*
X1752875Y1635757D01*
X1752990Y1637100D01*
X1754025D01*
G01X1755822Y1635292D02*
X1756090Y1635653D01*
X1756320Y1635860D01*
X1756627Y1635963D01*
X1756895Y1635860D01*
X1757087Y1635653D01*
X1757240Y1635343D01*
X1757278Y1634982D01*
X1757240Y1634672D01*
X1757087Y1634362D01*
X1756857Y1634103D01*
X1756588Y1634000D01*
X1756282Y1634103D01*
X1756013Y1634413D01*
X1755860Y1634878D01*
X1755822Y1635395D01*
X1755898Y1636067D01*
X1756013Y1636428D01*
X1756205Y1636790D01*
X1756473Y1637048D01*
X1756742Y1637100D01*
X1757010Y1636997D01*
X1757202Y1636738D01*
G01X1759650Y1634000D02*
Y1637100D01*
X1759190Y1636480D01*
G01Y1634000D02*
X1760110D01*
G01X1737363Y1652365D02*
Y1655565D01*
G01X1743563Y1652365D02*
X1737363D01*
G01X1743563Y1655565D02*
Y1652365D01*
G01X1737363Y1655565D02*
X1743563D01*
G01X1740029Y1651056D02*
Y1647856D01*
G01X1746363Y1649465D02*
X1749563D01*
G01X1746363Y1643265D02*
Y1649465D01*
G01X1749563Y1643265D02*
X1746363D01*
G01X1749563Y1649465D02*
Y1643265D01*
G01X1751363Y1649465D02*
X1754563D01*
G01X1751363Y1643265D02*
Y1649465D01*
G01X1754563Y1643265D02*
X1751363D01*
G01X1740982Y1656303D02*
X1740822Y1656053D01*
X1740635Y1655928D01*
X1740422Y1655886D01*
X1740155Y1655969D01*
X1739968Y1656178D01*
X1739915Y1656428D01*
X1739942Y1656678D01*
X1740048Y1656886D01*
X1740582Y1657303D01*
X1740822Y1657594D01*
X1740982Y1658011D01*
X1741035Y1658386D01*
X1739915D01*
G01X1738275D02*
Y1655886D01*
X1738595Y1656386D01*
G01Y1658386D02*
X1737955D01*
G01X1748529Y1657606D02*
Y1656106D01*
G01X1739486Y1659113D02*
Y1661019D01*
G01X1741392Y1659113D02*
X1739486D01*
G01X1739959Y1681854D02*
Y1679354D01*
X1740279Y1679854D01*
G01Y1681854D02*
X1739639D01*
G01X1737759Y1679354D02*
X1737972Y1679437D01*
X1738132Y1679646D01*
X1738239Y1679896D01*
X1738319Y1680229D01*
X1738346Y1680604D01*
X1738319Y1680979D01*
X1738239Y1681312D01*
X1738132Y1681562D01*
X1737972Y1681771D01*
X1737759Y1681854D01*
X1737546Y1681771D01*
X1737386Y1681562D01*
X1737279Y1681312D01*
X1737199Y1680979D01*
X1737172Y1680604D01*
X1737199Y1680229D01*
X1737279Y1679896D01*
X1737386Y1679646D01*
X1737546Y1679437D01*
X1737759Y1679354D01*
G01X1739486Y1678799D02*
X1741382D01*
G01X1739486Y1676893D02*
Y1678799D01*
G01X1742229Y1683356D02*
Y1680356D01*
G01X1750029Y1681806D02*
Y1680306D01*
G01X1738863Y1693565D02*
X1742063D01*
G01X1738863Y1687365D02*
Y1693565D01*
G01X1742063Y1687365D02*
X1738863D01*
G01X1742063Y1693565D02*
Y1687365D01*
G01X1743863Y1693565D02*
X1747063D01*
G01X1743863Y1687365D02*
Y1693565D01*
G01X1747063Y1687365D02*
X1743863D01*
G01X1747063Y1693565D02*
Y1687365D01*
G01X1737063Y1693565D02*
Y1687365D01*
G01X1750168Y1693675D02*
Y1696775D01*
X1751088D01*
X1751395Y1696620D01*
X1751625Y1696258D01*
X1751702Y1695845D01*
X1751625Y1695432D01*
X1751433Y1695122D01*
X1751088Y1694967D01*
X1750168D01*
G01X1753192Y1696775D02*
Y1694553D01*
X1753345Y1694088D01*
X1753652Y1693778D01*
X1754035Y1693675D01*
X1754418Y1693778D01*
X1754725Y1694088D01*
X1754878Y1694553D01*
Y1696775D01*
G01X1756407Y1694967D02*
X1756675Y1695328D01*
X1756905Y1695535D01*
X1757212Y1695638D01*
X1757480Y1695535D01*
X1757672Y1695328D01*
X1757825Y1695018D01*
X1757863Y1694657D01*
X1757825Y1694347D01*
X1757672Y1694037D01*
X1757442Y1693778D01*
X1757173Y1693675D01*
X1756867Y1693778D01*
X1756598Y1694088D01*
X1756445Y1694553D01*
X1756407Y1695070D01*
X1756483Y1695742D01*
X1756598Y1696103D01*
X1756790Y1696465D01*
X1757058Y1696723D01*
X1757327Y1696775D01*
X1757595Y1696672D01*
X1757787Y1696413D01*
G01X1759392Y1694140D02*
X1759622Y1693882D01*
X1759890Y1693727D01*
X1760235Y1693675D01*
X1760580Y1693778D01*
X1760848Y1693985D01*
X1761040Y1694347D01*
X1761078Y1694760D01*
X1761002Y1695173D01*
X1760810Y1695432D01*
X1760542Y1695638D01*
X1760273Y1695690D01*
X1760005Y1695638D01*
X1759660Y1695432D01*
X1759775Y1696775D01*
X1760810D01*
G01X1763335D02*
X1763028Y1696672D01*
X1762798Y1696413D01*
X1762645Y1696103D01*
X1762530Y1695690D01*
X1762492Y1695225D01*
X1762530Y1694760D01*
X1762645Y1694347D01*
X1762798Y1694037D01*
X1763028Y1693778D01*
X1763335Y1693675D01*
X1763642Y1693778D01*
X1763872Y1694037D01*
X1764025Y1694347D01*
X1764140Y1694760D01*
X1764178Y1695225D01*
X1764140Y1695690D01*
X1764025Y1696103D01*
X1763872Y1696413D01*
X1763642Y1696672D01*
X1763335Y1696775D01*
G01X1765707Y1696258D02*
X1765937Y1696568D01*
X1766205Y1696723D01*
X1766512Y1696775D01*
X1766895Y1696672D01*
X1767163Y1696413D01*
X1767240Y1696103D01*
X1767202Y1695793D01*
X1767048Y1695535D01*
X1766282Y1695018D01*
X1765937Y1694657D01*
X1765707Y1694140D01*
X1765630Y1693675D01*
X1767240D01*
G01X1751980Y1708708D02*
X1748780D01*
G01Y1714908D02*
X1751980D01*
G01X1748780Y1708708D02*
Y1714908D01*
G01X1746127Y1715155D02*
Y1706493D01*
G01X1738980Y1715155D02*
X1740880Y1712955D01*
G01D02*
X1742780Y1715155D01*
G01D02*
X1746127D01*
G01X1747880Y1719058D02*
Y1725258D01*
G01D02*
X1751080D01*
G01D02*
Y1719058D01*
G01D02*
X1747880D01*
G01X1738980Y1730305D02*
X1740880Y1728105D01*
G01D02*
X1742780Y1730305D01*
G01X1746127D02*
Y1721643D01*
G01X1742780Y1730305D02*
X1746127D01*
G01X1754029Y-28643D02*
X1754339Y-28451D01*
X1754546Y-28221D01*
X1754649Y-27953D01*
X1754546Y-27646D01*
X1754339Y-27416D01*
X1754029Y-27186D01*
X1753616Y-27109D01*
X1751549D01*
G01X1753357Y-25504D02*
X1752996Y-25236D01*
X1752789Y-25006D01*
X1752686Y-24699D01*
X1752789Y-24431D01*
X1752996Y-24239D01*
X1753306Y-24086D01*
X1753667Y-24048D01*
X1753977Y-24086D01*
X1754287Y-24239D01*
X1754546Y-24469D01*
X1754649Y-24738D01*
X1754546Y-25044D01*
X1754236Y-25313D01*
X1753771Y-25466D01*
X1753254Y-25504D01*
X1752582Y-25428D01*
X1752221Y-25313D01*
X1751859Y-25121D01*
X1751601Y-24853D01*
X1751549Y-24584D01*
X1751652Y-24316D01*
X1751911Y-24124D01*
G01X1753357Y-22404D02*
X1752996Y-22136D01*
X1752789Y-21906D01*
X1752686Y-21599D01*
X1752789Y-21331D01*
X1752996Y-21139D01*
X1753306Y-20986D01*
X1753667Y-20948D01*
X1753977Y-20986D01*
X1754287Y-21139D01*
X1754546Y-21369D01*
X1754649Y-21638D01*
X1754546Y-21944D01*
X1754236Y-22213D01*
X1753771Y-22366D01*
X1753254Y-22404D01*
X1752582Y-22328D01*
X1752221Y-22213D01*
X1751859Y-22021D01*
X1751601Y-21753D01*
X1751549Y-21484D01*
X1751652Y-21216D01*
X1751911Y-21024D01*
G01X1796307Y51142D02*
X1760500D01*
G01X1765168Y78397D02*
Y75197D01*
G01D02*
X1758968D01*
G01D02*
Y78397D01*
G01X1769238Y68016D02*
X1766038D01*
G01D02*
Y74216D01*
G01D02*
X1769238D01*
G01X1758938Y74237D02*
X1765138D01*
G01D02*
Y71037D01*
G01D02*
X1758938D01*
G01D02*
Y74237D01*
G01X1765138Y67037D02*
X1758938D01*
G01D02*
Y70237D01*
G01D02*
X1765138D01*
G01D02*
Y67037D01*
G01X1755121Y67639D02*
Y82439D01*
G01X1758968Y78397D02*
X1765168D01*
G01X1758036Y83807D02*
X1751836D01*
G01X1758036Y87007D02*
Y83807D01*
G01X1751836Y87007D02*
X1758036D01*
G01X1751836Y83807D02*
Y87007D01*
G01X1765648Y85507D02*
X1759448D01*
G01D02*
Y88707D01*
G01D02*
X1765648D01*
G01D02*
Y85507D01*
G01Y82007D02*
X1759448D01*
G01D02*
Y85207D01*
G01D02*
X1765648D01*
G01D02*
Y82007D01*
G01X1760142Y96075D02*
Y90075D01*
G01X1769491Y95720D02*
X1766291D01*
G01D02*
Y101920D01*
G01D02*
X1769491D01*
G01X1753488Y101907D02*
Y98707D01*
G01X1756995Y102467D02*
X1756835Y102217D01*
X1756648Y102092D01*
X1756435Y102050D01*
X1756168Y102133D01*
X1755981Y102342D01*
X1755928Y102592D01*
X1755955Y102842D01*
X1756061Y103050D01*
X1756595Y103467D01*
X1756835Y103758D01*
X1756995Y104175D01*
X1757048Y104550D01*
X1755928D01*
G01X1754288Y102050D02*
X1754501Y102133D01*
X1754661Y102342D01*
X1754768Y102592D01*
X1754848Y102925D01*
X1754875Y103300D01*
X1754848Y103675D01*
X1754768Y104008D01*
X1754661Y104258D01*
X1754501Y104467D01*
X1754288Y104550D01*
X1754075Y104467D01*
X1753915Y104258D01*
X1753808Y104008D01*
X1753728Y103675D01*
X1753701Y103300D01*
X1753728Y102925D01*
X1753808Y102592D01*
X1753915Y102342D01*
X1754075Y102133D01*
X1754288Y102050D01*
G01X1751587Y104825D02*
Y107966D01*
G01X1762878Y115527D02*
Y121727D01*
G01X1766078D02*
Y115527D01*
G01D02*
X1762878D01*
G01X1755898Y116134D02*
X1756148Y115974D01*
X1756273Y115787D01*
X1756315Y115574D01*
X1756232Y115307D01*
X1756023Y115120D01*
X1755773Y115067D01*
X1755523Y115094D01*
X1755315Y115200D01*
X1754898Y115734D01*
X1754607Y115974D01*
X1754190Y116134D01*
X1753815Y116187D01*
Y115067D01*
G01Y113427D02*
X1756315D01*
X1755815Y113747D01*
G01X1753815D02*
Y113107D01*
G01X1752982Y112027D02*
Y110427D01*
G01X1755898Y109534D02*
X1756148Y109374D01*
X1756273Y109187D01*
X1756315Y108974D01*
X1756232Y108707D01*
X1756023Y108520D01*
X1755773Y108467D01*
X1755523Y108494D01*
X1755315Y108600D01*
X1754898Y109134D01*
X1754607Y109374D01*
X1754190Y109534D01*
X1753815Y109587D01*
Y108467D01*
G01X1755898Y107334D02*
X1756148Y107174D01*
X1756273Y106987D01*
X1756315Y106774D01*
X1756232Y106507D01*
X1756023Y106320D01*
X1755773Y106267D01*
X1755523Y106294D01*
X1755315Y106400D01*
X1754898Y106934D01*
X1754607Y107174D01*
X1754190Y107334D01*
X1753815Y107387D01*
Y106267D01*
G01X1751587Y113888D02*
Y117029D01*
G01Y109977D02*
Y111877D01*
G01X1762878Y121727D02*
X1766078D01*
G01X1752518Y129767D02*
Y123567D01*
G01X1755722Y129771D02*
X1758922D01*
G01X1755722Y123571D02*
Y129771D01*
G01X1758922Y123571D02*
X1755722D01*
G01X1758922Y129771D02*
Y123571D01*
G01X1752020Y171834D02*
Y174934D01*
G01X1753630D02*
Y171834D01*
G01Y173384D02*
X1752020D01*
G01X1755197Y173126D02*
X1755465Y173487D01*
X1755695Y173694D01*
X1756002Y173797D01*
X1756270Y173694D01*
X1756462Y173487D01*
X1756615Y173177D01*
X1756653Y172816D01*
X1756615Y172506D01*
X1756462Y172196D01*
X1756232Y171937D01*
X1755963Y171834D01*
X1755657Y171937D01*
X1755388Y172247D01*
X1755235Y172712D01*
X1755197Y173229D01*
X1755273Y173901D01*
X1755388Y174262D01*
X1755580Y174624D01*
X1755848Y174882D01*
X1756117Y174934D01*
X1756385Y174831D01*
X1756577Y174572D01*
G01X1759025Y174934D02*
X1758718Y174831D01*
X1758488Y174572D01*
X1758335Y174262D01*
X1758220Y173849D01*
X1758182Y173384D01*
X1758220Y172919D01*
X1758335Y172506D01*
X1758488Y172196D01*
X1758718Y171937D01*
X1759025Y171834D01*
X1759332Y171937D01*
X1759562Y172196D01*
X1759715Y172506D01*
X1759830Y172919D01*
X1759868Y173384D01*
X1759830Y173849D01*
X1759715Y174262D01*
X1759562Y174572D01*
X1759332Y174831D01*
X1759025Y174934D01*
G01X1762125D02*
X1761818Y174831D01*
X1761588Y174572D01*
X1761435Y174262D01*
X1761320Y173849D01*
X1761282Y173384D01*
X1761320Y172919D01*
X1761435Y172506D01*
X1761588Y172196D01*
X1761818Y171937D01*
X1762125Y171834D01*
X1762432Y171937D01*
X1762662Y172196D01*
X1762815Y172506D01*
X1762930Y172919D01*
X1762968Y173384D01*
X1762930Y173849D01*
X1762815Y174262D01*
X1762662Y174572D01*
X1762432Y174831D01*
X1762125Y174934D01*
G01X1765225D02*
X1764918Y174831D01*
X1764688Y174572D01*
X1764535Y174262D01*
X1764420Y173849D01*
X1764382Y173384D01*
X1764420Y172919D01*
X1764535Y172506D01*
X1764688Y172196D01*
X1764918Y171937D01*
X1765225Y171834D01*
X1765532Y171937D01*
X1765762Y172196D01*
X1765915Y172506D01*
X1766030Y172919D01*
X1766068Y173384D01*
X1766030Y173849D01*
X1765915Y174262D01*
X1765762Y174572D01*
X1765532Y174831D01*
X1765225Y174934D01*
G01X1767848Y181033D02*
X1761848D01*
G01D02*
Y193033D01*
G01D02*
X1767848D01*
G01X1760848Y181033D02*
X1754848D01*
G01D02*
Y193033D01*
G01D02*
X1760848D01*
G01D02*
Y181033D01*
G01X1753788Y193096D02*
Y181096D01*
G01X1766983Y203465D02*
X1760983D01*
G01D02*
Y215465D01*
G01X1759923Y215402D02*
Y203402D01*
G01D02*
X1753923D01*
G01D02*
Y215402D01*
G01X1752833D02*
Y203402D01*
G01X1760983Y215465D02*
X1766983D01*
G01X1753923Y215402D02*
X1759923D01*
G01X1768619Y225210D02*
X1765519D01*
Y226130D01*
X1765674Y226437D01*
X1766036Y226667D01*
X1766449Y226744D01*
X1766862Y226667D01*
X1767172Y226475D01*
X1767327Y226130D01*
Y225210D01*
G01X1765519Y228310D02*
X1768619D01*
Y229844D01*
G01Y232177D02*
X1768567Y232445D01*
X1768412Y232752D01*
X1768154Y232944D01*
X1767792Y233020D01*
X1767431Y232944D01*
X1767121Y232714D01*
X1766966Y232369D01*
Y231985D01*
X1766862Y231755D01*
X1766604Y231564D01*
X1766242Y231487D01*
X1765881Y231602D01*
X1765622Y231870D01*
X1765519Y232177D01*
X1765622Y232484D01*
X1765881Y232752D01*
X1766242Y232867D01*
X1766604Y232790D01*
X1766862Y232599D01*
X1766966Y232369D01*
Y231985D01*
X1767121Y231640D01*
X1767431Y231410D01*
X1767792Y231334D01*
X1768154Y231410D01*
X1768412Y231602D01*
X1768567Y231909D01*
X1768619Y232177D01*
G01X1765519Y235277D02*
X1765622Y234970D01*
X1765881Y234740D01*
X1766191Y234587D01*
X1766604Y234472D01*
X1767069Y234434D01*
X1767534Y234472D01*
X1767947Y234587D01*
X1768257Y234740D01*
X1768516Y234970D01*
X1768619Y235277D01*
X1768516Y235584D01*
X1768257Y235814D01*
X1767947Y235967D01*
X1767534Y236082D01*
X1767069Y236120D01*
X1766604Y236082D01*
X1766191Y235967D01*
X1765881Y235814D01*
X1765622Y235584D01*
X1765519Y235277D01*
G01X1767327Y237649D02*
X1766966Y237917D01*
X1766759Y238147D01*
X1766656Y238454D01*
X1766759Y238722D01*
X1766966Y238914D01*
X1767276Y239067D01*
X1767637Y239105D01*
X1767947Y239067D01*
X1768257Y238914D01*
X1768516Y238684D01*
X1768619Y238415D01*
X1768516Y238109D01*
X1768206Y237840D01*
X1767741Y237687D01*
X1767224Y237649D01*
X1766552Y237725D01*
X1766191Y237840D01*
X1765829Y238032D01*
X1765571Y238300D01*
X1765519Y238569D01*
X1765622Y238837D01*
X1765881Y239029D01*
G01X1767327Y240749D02*
X1766966Y241017D01*
X1766759Y241247D01*
X1766656Y241554D01*
X1766759Y241822D01*
X1766966Y242014D01*
X1767276Y242167D01*
X1767637Y242205D01*
X1767947Y242167D01*
X1768257Y242014D01*
X1768516Y241784D01*
X1768619Y241515D01*
X1768516Y241209D01*
X1768206Y240940D01*
X1767741Y240787D01*
X1767224Y240749D01*
X1766552Y240825D01*
X1766191Y240940D01*
X1765829Y241132D01*
X1765571Y241400D01*
X1765519Y241669D01*
X1765622Y241937D01*
X1765881Y242129D01*
G01X1762070Y253027D02*
Y265027D01*
G01X1768070Y253027D02*
X1762070D01*
G01X1760970Y252927D02*
X1754970D01*
G01D02*
Y264927D01*
G01X1760970D02*
Y252927D01*
G01X1753583Y262737D02*
Y256537D01*
G01X1762070Y265027D02*
X1768070D01*
G01X1754970Y264927D02*
X1760970D01*
G01X1783828Y289855D02*
G02I-13386J0D01*
G01X1754567Y302637D02*
Y296637D01*
G01X1783828Y289855D02*
X1757056D01*
G01X1755687Y365648D02*
Y362448D01*
G01X1763327Y369748D02*
X1769527D01*
G01X1763327Y366548D02*
Y369748D01*
G01X1769527Y366548D02*
X1763327D01*
G01X1763120Y374052D02*
X1769320D01*
G01X1763120Y370852D02*
Y374052D01*
G01X1769320Y370852D02*
X1763120D01*
G01X1755687Y369648D02*
Y366448D01*
G01X1763327Y365748D02*
X1769527D01*
G01X1763327Y362548D02*
Y365748D01*
G01X1769527Y362548D02*
X1763327D01*
G01X1755820Y374052D02*
Y370852D01*
G01Y379052D02*
Y375852D01*
G01Y384552D02*
Y381352D01*
G01X1763166Y698320D02*
Y687244D01*
G01X1790929Y702179D02*
X1759129D01*
G01D02*
Y715979D01*
G01D02*
X1790929D01*
G01X1763166Y1325040D02*
Y718620D01*
G01X1758149Y1392638D02*
Y1404449D01*
G01X1763383Y1476500D02*
Y1479600D01*
X1764303D01*
X1764610Y1479445D01*
X1764840Y1479083D01*
X1764917Y1478670D01*
X1764840Y1478257D01*
X1764648Y1477947D01*
X1764303Y1477792D01*
X1763383D01*
G01X1768093Y1479342D02*
X1767863Y1479497D01*
X1767595Y1479600D01*
X1767288D01*
X1766943Y1479445D01*
X1766675Y1479187D01*
X1766483Y1478877D01*
X1766330Y1478360D01*
X1766292Y1477895D01*
X1766368Y1477430D01*
X1766483Y1477120D01*
X1766713Y1476810D01*
X1766982Y1476603D01*
X1767250Y1476500D01*
X1767518D01*
X1767787Y1476603D01*
X1768017Y1476758D01*
X1768208Y1476965D01*
G01X1769622Y1477792D02*
X1769890Y1478153D01*
X1770120Y1478360D01*
X1770427Y1478463D01*
X1770695Y1478360D01*
X1770887Y1478153D01*
X1771040Y1477843D01*
X1771078Y1477482D01*
X1771040Y1477172D01*
X1770887Y1476862D01*
X1770657Y1476603D01*
X1770388Y1476500D01*
X1770082Y1476603D01*
X1769813Y1476913D01*
X1769660Y1477378D01*
X1769622Y1477895D01*
X1769698Y1478567D01*
X1769813Y1478928D01*
X1770005Y1479290D01*
X1770273Y1479548D01*
X1770542Y1479600D01*
X1770810Y1479497D01*
X1771002Y1479238D01*
G01X1772607Y1476965D02*
X1772837Y1476707D01*
X1773105Y1476552D01*
X1773450Y1476500D01*
X1773795Y1476603D01*
X1774063Y1476810D01*
X1774255Y1477172D01*
X1774293Y1477585D01*
X1774217Y1477998D01*
X1774025Y1478257D01*
X1773757Y1478463D01*
X1773488Y1478515D01*
X1773220Y1478463D01*
X1772875Y1478257D01*
X1772990Y1479600D01*
X1774025D01*
G01X1776473Y1476500D02*
X1776550Y1477172D01*
X1776665Y1477740D01*
X1776818Y1478257D01*
X1777010Y1478825D01*
X1777317Y1479600D01*
X1775783D01*
G01X1780110Y1476500D02*
Y1479600D01*
X1778692Y1477378D01*
X1780608D01*
G01X1760652Y1485778D02*
X1767779D01*
G01X1760652Y1504432D02*
Y1485778D01*
G01X1758306D02*
Y1504432D01*
G01X1763652Y1507432D02*
X1760652Y1504432D01*
G01X1758306D02*
X1755306Y1507432D01*
G01X1767779D02*
X1763652D01*
G01X1765006Y1561463D02*
Y1567663D01*
G01X1768206Y1561463D02*
X1765006D01*
G01X1762331Y1552147D02*
X1761538D01*
G01X1762331Y1554747D02*
Y1552147D01*
G01X1758451Y1578732D02*
Y1584932D01*
G01X1761651Y1578732D02*
X1758451D01*
G01X1761651Y1584932D02*
Y1578732D01*
G01X1764379Y1580805D02*
Y1584005D01*
G01X1770579Y1580805D02*
X1764379D01*
G01X1765006Y1567663D02*
X1768206D01*
G01X1757651Y1578732D02*
X1754451D01*
G01X1757651Y1584932D02*
Y1578732D01*
G01X1754451D02*
Y1584932D01*
G01X1762331Y1575769D02*
Y1573578D01*
G01X1761598Y1575769D02*
X1762331D01*
G01X1758451Y1584932D02*
X1761651D01*
G01X1764379Y1584005D02*
X1770579D01*
G01X1753579Y1587505D02*
Y1584305D01*
G01X1754451Y1584932D02*
X1757651D01*
G01X1766779Y1594550D02*
X1754779D01*
G01D02*
Y1600550D01*
G01D02*
X1766779D01*
G01Y1601950D02*
X1754779D01*
G01Y1607950D02*
X1766779D01*
G01X1754779Y1601950D02*
Y1607950D01*
G01X1764638Y1625350D02*
Y1629477D01*
X1761638Y1632477D01*
G01X1763323Y1637286D02*
X1769523D01*
G01X1763323Y1634086D02*
Y1637286D01*
G01X1769523Y1634086D02*
X1763323D01*
G01X1756363Y1652565D02*
X1759563D01*
G01X1756363Y1646365D02*
Y1652565D01*
G01X1759563Y1646365D02*
X1756363D01*
G01X1759563Y1652565D02*
Y1646365D01*
G01X1754563Y1649465D02*
Y1643265D01*
G01X1761363Y1652565D02*
X1764563D01*
G01X1761363Y1646365D02*
Y1652565D01*
G01X1764563Y1646365D02*
X1761363D01*
G01X1764563Y1652565D02*
Y1646365D01*
G01X1761316Y1656889D02*
X1761156Y1657181D01*
X1760942Y1657347D01*
X1760702Y1657389D01*
X1760489Y1657347D01*
X1760276Y1657139D01*
X1760142Y1656889D01*
X1760116Y1656639D01*
X1760169Y1656347D01*
X1760356Y1656139D01*
X1760542Y1656056D01*
X1760782D01*
G01X1760542D02*
X1760382Y1655931D01*
X1760249Y1655722D01*
X1760196Y1655472D01*
X1760249Y1655222D01*
X1760382Y1655014D01*
X1760622Y1654889D01*
X1760862Y1654931D01*
X1761102Y1655097D01*
G01X1758529Y1654889D02*
X1758742Y1654972D01*
X1758902Y1655181D01*
X1759009Y1655431D01*
X1759089Y1655764D01*
X1759116Y1656139D01*
X1759089Y1656514D01*
X1759009Y1656847D01*
X1758902Y1657097D01*
X1758742Y1657306D01*
X1758529Y1657389D01*
X1758316Y1657306D01*
X1758156Y1657097D01*
X1758049Y1656847D01*
X1757969Y1656514D01*
X1757942Y1656139D01*
X1757969Y1655764D01*
X1758049Y1655431D01*
X1758156Y1655181D01*
X1758316Y1654972D01*
X1758529Y1654889D01*
G01X1756329Y1657656D02*
Y1654656D01*
G01X1763203Y1663133D02*
X1762911Y1662973D01*
X1762745Y1662759D01*
X1762703Y1662519D01*
X1762745Y1662306D01*
X1762953Y1662093D01*
X1763203Y1661959D01*
X1763453Y1661933D01*
X1763745Y1661986D01*
X1763953Y1662173D01*
X1764036Y1662359D01*
Y1662599D01*
G01Y1662359D02*
X1764161Y1662199D01*
X1764370Y1662066D01*
X1764620Y1662013D01*
X1764870Y1662066D01*
X1765078Y1662199D01*
X1765203Y1662439D01*
X1765161Y1662679D01*
X1764995Y1662919D01*
G01X1762703Y1660346D02*
X1765203D01*
X1764703Y1660666D01*
G01X1762703D02*
Y1660026D01*
G01X1759172Y1659113D02*
X1757266D01*
G01X1759172Y1661019D02*
Y1659113D01*
G01X1762079Y1668256D02*
X1760579D01*
G01X1760563Y1684365D02*
X1757363D01*
G01X1760563Y1690565D02*
Y1684365D01*
G01X1757363D02*
Y1690565D01*
G01X1765063Y1684365D02*
X1761863D01*
G01X1765063Y1690565D02*
Y1684365D01*
G01X1761863D02*
Y1690565D01*
G01X1758455Y1682071D02*
X1760955D01*
X1759163Y1683058D01*
Y1681724D01*
G01X1760955Y1680191D02*
X1760872Y1680404D01*
X1760663Y1680564D01*
X1760413Y1680671D01*
X1760080Y1680751D01*
X1759705Y1680778D01*
X1759330Y1680751D01*
X1758997Y1680671D01*
X1758747Y1680564D01*
X1758538Y1680404D01*
X1758455Y1680191D01*
X1758538Y1679978D01*
X1758747Y1679818D01*
X1758997Y1679711D01*
X1759330Y1679631D01*
X1759705Y1679604D01*
X1760080Y1679631D01*
X1760413Y1679711D01*
X1760663Y1679818D01*
X1760872Y1679978D01*
X1760955Y1680191D01*
G01X1757266Y1678799D02*
X1759172D01*
G01X1760629Y1676056D02*
X1763629D01*
G01X1759172Y1678799D02*
Y1676893D01*
G01X1757363Y1690565D02*
X1760563D01*
G01X1761863D02*
X1765063D01*
G01X1751980Y1714908D02*
Y1708708D01*
G01X1777279Y1714960D02*
G02I-10350J0D01*
G01X1755686Y1728281D02*
Y1731381D01*
G01X1757296D02*
Y1728281D01*
G01Y1729831D02*
X1755686D01*
G01X1758939Y1728643D02*
X1759208Y1728384D01*
X1759514Y1728281D01*
X1759821Y1728384D01*
X1760089Y1728694D01*
X1760281Y1729159D01*
X1760358Y1729624D01*
Y1730193D01*
X1760281Y1730658D01*
X1760089Y1731071D01*
X1759859Y1731278D01*
X1759591Y1731381D01*
X1759284Y1731278D01*
X1759054Y1731071D01*
X1758901Y1730761D01*
X1758824Y1730348D01*
X1758901Y1729986D01*
X1759093Y1729624D01*
X1759323Y1729418D01*
X1759591Y1729366D01*
X1759898Y1729469D01*
X1760128Y1729728D01*
X1760358Y1730193D01*
G01X1762691Y1731381D02*
X1762384Y1731278D01*
X1762154Y1731019D01*
X1762001Y1730709D01*
X1761886Y1730296D01*
X1761848Y1729831D01*
X1761886Y1729366D01*
X1762001Y1728953D01*
X1762154Y1728643D01*
X1762384Y1728384D01*
X1762691Y1728281D01*
X1762998Y1728384D01*
X1763228Y1728643D01*
X1763381Y1728953D01*
X1763496Y1729366D01*
X1763534Y1729831D01*
X1763496Y1730296D01*
X1763381Y1730709D01*
X1763228Y1731019D01*
X1762998Y1731278D01*
X1762691Y1731381D01*
G01X1772525Y61337D02*
X1774951D01*
G01X1805624Y55289D02*
X1776065D01*
G01D02*
Y66785D01*
G01X1769238Y74216D02*
Y68016D01*
G01X1776065Y66785D02*
X1805624D01*
G01X1784536Y86691D02*
X1770560D01*
G01D02*
Y78503D01*
G01D02*
X1784536D01*
G01X1786778Y95327D02*
X1780578D01*
G01D02*
Y98527D01*
G01D02*
X1786778D01*
G01X1780578Y94527D02*
X1786778D01*
G01Y91327D02*
X1780578D01*
G01D02*
Y94527D01*
G01X1773378Y91291D02*
X1767178D01*
G01D02*
Y94491D01*
G01D02*
X1773378D01*
G01D02*
Y91291D01*
G01X1769491Y101920D02*
Y95720D01*
G01X1786736Y99339D02*
X1780536D01*
G01D02*
Y102539D01*
G01D02*
X1786736D01*
G01X1773491Y101920D02*
Y95720D01*
G01D02*
X1770291D01*
G01D02*
Y101920D01*
G01D02*
X1773491D01*
G01X1776878Y108490D02*
Y106064D01*
G01X1772941Y128536D02*
Y109318D01*
G01D02*
X1780815D01*
G01D02*
Y128536D01*
G01X1777078Y118177D02*
X1775578Y121177D01*
G01X1778578D02*
X1777078Y118177D01*
G01D02*
Y117177D01*
G01X1778578Y118177D02*
X1775578D01*
G01X1776878Y131604D02*
Y129364D01*
G01X1778503Y130577D02*
X1775253D01*
G01X1780815Y128536D02*
X1772941D01*
G01X1777078Y121177D02*
Y122277D01*
G01X1775578Y121177D02*
X1778578D01*
G01X1777894Y146661D02*
Y149761D01*
G01X1779504D02*
Y146661D01*
G01Y148211D02*
X1777894D01*
G01X1781071Y149244D02*
X1781301Y149554D01*
X1781569Y149709D01*
X1781876Y149761D01*
X1782259Y149658D01*
X1782527Y149399D01*
X1782604Y149089D01*
X1782566Y148779D01*
X1782412Y148521D01*
X1781646Y148004D01*
X1781301Y147643D01*
X1781071Y147126D01*
X1780994Y146661D01*
X1782604D01*
G01X1784247Y147023D02*
X1784516Y146764D01*
X1784822Y146661D01*
X1785129Y146764D01*
X1785397Y147074D01*
X1785589Y147539D01*
X1785666Y148004D01*
Y148573D01*
X1785589Y149038D01*
X1785397Y149451D01*
X1785167Y149658D01*
X1784899Y149761D01*
X1784592Y149658D01*
X1784362Y149451D01*
X1784209Y149141D01*
X1784132Y148728D01*
X1784209Y148366D01*
X1784401Y148004D01*
X1784631Y147798D01*
X1784899Y147746D01*
X1785206Y147849D01*
X1785436Y148108D01*
X1785666Y148573D01*
G01X1783175Y185311D02*
X1776975D01*
G01D02*
Y188511D01*
G01D02*
X1783175D01*
G01X1776975Y192399D02*
X1783175D01*
G01Y189199D02*
X1776975D01*
G01D02*
Y192399D01*
G01X1783175Y192799D02*
X1776975D01*
G01D02*
Y195999D01*
G01X1785604Y180863D02*
X1779404D01*
G01D02*
Y184063D01*
G01D02*
X1785604D01*
G01X1767848Y193033D02*
Y181033D01*
G01X1774848D02*
X1768848D01*
G01D02*
Y193033D01*
G01D02*
X1774848D01*
G01D02*
Y181033D01*
G01X1783231Y196299D02*
X1777031D01*
G01D02*
Y199499D01*
G01D02*
X1783231D01*
G01X1776975Y195999D02*
X1783175D01*
G01X1773848Y214065D02*
Y202065D01*
G01D02*
X1767848D01*
G01D02*
Y214065D01*
G01X1766983Y215465D02*
Y203465D01*
G01X1780848Y214065D02*
Y202065D01*
G01D02*
X1774848D01*
G01D02*
Y214065D01*
G01X1767848D02*
X1773848D01*
G01X1774848D02*
X1780848D01*
G01X1770402Y272537D02*
Y216237D01*
G01D02*
X1785396D01*
G01X1768070Y265027D02*
Y253027D01*
G01X1785396Y272537D02*
X1770402D01*
G01X1769527Y369748D02*
Y366548D01*
G01X1769320Y374052D02*
Y370852D01*
G01X1769527Y365748D02*
Y362548D01*
G01X1766832Y683675D02*
X1767024Y683365D01*
X1767254Y683158D01*
X1767522Y683055D01*
X1767829Y683158D01*
X1768059Y683365D01*
X1768289Y683675D01*
X1768366Y684088D01*
Y686155D01*
G01X1769971Y684347D02*
X1770239Y684708D01*
X1770469Y684915D01*
X1770776Y685018D01*
X1771044Y684915D01*
X1771236Y684708D01*
X1771389Y684398D01*
X1771427Y684037D01*
X1771389Y683727D01*
X1771236Y683417D01*
X1771006Y683158D01*
X1770737Y683055D01*
X1770431Y683158D01*
X1770162Y683468D01*
X1770009Y683933D01*
X1769971Y684450D01*
X1770047Y685122D01*
X1770162Y685483D01*
X1770354Y685845D01*
X1770622Y686103D01*
X1770891Y686155D01*
X1771159Y686052D01*
X1771351Y685793D01*
G01X1773722Y683055D02*
X1773799Y683727D01*
X1773914Y684295D01*
X1774067Y684812D01*
X1774259Y685380D01*
X1774566Y686155D01*
X1773032D01*
G01X1767276Y687244D02*
Y1325040D01*
G01X1792866Y687244D02*
X1767276D01*
G01X1792866Y720709D02*
X1767276D01*
G01X1792866Y1291575D02*
X1767276D01*
G01Y1325040D02*
X1792866D01*
G01X1775179Y1485778D02*
X1782306D01*
G01Y1504432D02*
X1779306Y1507432D01*
G01D02*
X1775179D01*
G01X1774184Y1522941D02*
Y1548531D01*
G01X1778179Y1522941D02*
X1774184D01*
G01X1771199D02*
X1767204D01*
G01X1771199Y1548531D02*
Y1522941D01*
G01X1776288Y1553971D02*
Y1550771D01*
G01X1770088D02*
Y1553971D01*
G01X1776288Y1550771D02*
X1770088D01*
G01X1774184Y1548531D02*
X1778179D01*
G01X1767204D02*
X1771199D01*
G01X1770088Y1553971D02*
X1776288D01*
G01X1768206Y1567663D02*
Y1561463D01*
G01X1772057Y1562107D02*
Y1568307D01*
G01X1775257Y1562107D02*
X1772057D01*
G01X1775257Y1568307D02*
Y1562107D01*
G01X1773288Y1554771D02*
X1770088D01*
G01X1773288Y1560971D02*
Y1554771D01*
G01X1770088Y1560971D02*
X1773288D01*
G01X1770088Y1554771D02*
Y1560971D01*
G01X1778388Y1561358D02*
Y1563056D01*
G01Y1552147D02*
Y1554747D01*
G01X1779181Y1552147D02*
X1778388D01*
G01X1770579Y1584005D02*
Y1580805D01*
G01X1777579Y1584005D02*
Y1580805D01*
G01X1771379D02*
Y1584005D01*
G01X1777579Y1580805D02*
X1771379D01*
G01X1772057Y1568307D02*
X1775257D01*
G01Y1569107D02*
X1772057D01*
G01Y1575307D02*
X1772900D01*
G01X1772057Y1569107D02*
Y1575307D01*
G01X1775257Y1574000D02*
Y1569107D01*
G01X1775079Y1579505D02*
Y1577600D01*
G01X1768879Y1579505D02*
X1775079D01*
G01X1768879Y1576305D02*
Y1579505D01*
G01X1772900Y1576305D02*
X1768879D01*
G01X1778388Y1575769D02*
X1779396D01*
G01X1778388Y1573915D02*
Y1575769D01*
G01X1771379Y1584005D02*
X1777579D01*
G01X1781194Y1584232D02*
Y1587432D01*
G01X1787394Y1584232D02*
X1781194D01*
G01Y1587432D02*
X1787394D01*
G01X1779118Y1590819D02*
Y1593919D01*
X1780038D01*
X1780345Y1593764D01*
X1780575Y1593402D01*
X1780652Y1592989D01*
X1780575Y1592576D01*
X1780383Y1592266D01*
X1780038Y1592111D01*
X1779118D01*
G01X1782142Y1593919D02*
Y1591697D01*
X1782295Y1591232D01*
X1782602Y1590922D01*
X1782985Y1590819D01*
X1783368Y1590922D01*
X1783675Y1591232D01*
X1783828Y1591697D01*
Y1593919D01*
G01X1785357Y1592111D02*
X1785625Y1592472D01*
X1785855Y1592679D01*
X1786162Y1592782D01*
X1786430Y1592679D01*
X1786622Y1592472D01*
X1786775Y1592162D01*
X1786813Y1591801D01*
X1786775Y1591491D01*
X1786622Y1591181D01*
X1786392Y1590922D01*
X1786123Y1590819D01*
X1785817Y1590922D01*
X1785548Y1591232D01*
X1785395Y1591697D01*
X1785357Y1592214D01*
X1785433Y1592886D01*
X1785548Y1593247D01*
X1785740Y1593609D01*
X1786008Y1593867D01*
X1786277Y1593919D01*
X1786545Y1593816D01*
X1786737Y1593557D01*
G01X1788342Y1591284D02*
X1788572Y1591026D01*
X1788840Y1590871D01*
X1789185Y1590819D01*
X1789530Y1590922D01*
X1789798Y1591129D01*
X1789990Y1591491D01*
X1790028Y1591904D01*
X1789952Y1592317D01*
X1789760Y1592576D01*
X1789492Y1592782D01*
X1789223Y1592834D01*
X1788955Y1592782D01*
X1788610Y1592576D01*
X1788725Y1593919D01*
X1789760D01*
G01X1792285D02*
X1791978Y1593816D01*
X1791748Y1593557D01*
X1791595Y1593247D01*
X1791480Y1592834D01*
X1791442Y1592369D01*
X1791480Y1591904D01*
X1791595Y1591491D01*
X1791748Y1591181D01*
X1791978Y1590922D01*
X1792285Y1590819D01*
X1792592Y1590922D01*
X1792822Y1591181D01*
X1792975Y1591491D01*
X1793090Y1591904D01*
X1793128Y1592369D01*
X1793090Y1592834D01*
X1792975Y1593247D01*
X1792822Y1593557D01*
X1792592Y1593816D01*
X1792285Y1593919D01*
G01X1795845Y1590819D02*
Y1593919D01*
X1794427Y1591697D01*
X1796343D01*
G01X1766779Y1600550D02*
Y1594550D01*
G01Y1607950D02*
Y1601950D01*
G01X1771383Y1610000D02*
Y1613100D01*
X1772303D01*
X1772610Y1612945D01*
X1772840Y1612583D01*
X1772917Y1612170D01*
X1772840Y1611757D01*
X1772648Y1611447D01*
X1772303Y1611292D01*
X1771383D01*
G01X1774483Y1613100D02*
Y1610000D01*
X1776017D01*
G01X1777622Y1611292D02*
X1777890Y1611653D01*
X1778120Y1611860D01*
X1778427Y1611963D01*
X1778695Y1611860D01*
X1778887Y1611653D01*
X1779040Y1611343D01*
X1779078Y1610982D01*
X1779040Y1610672D01*
X1778887Y1610362D01*
X1778657Y1610103D01*
X1778388Y1610000D01*
X1778082Y1610103D01*
X1777813Y1610413D01*
X1777660Y1610878D01*
X1777622Y1611395D01*
X1777698Y1612067D01*
X1777813Y1612428D01*
X1778005Y1612790D01*
X1778273Y1613048D01*
X1778542Y1613100D01*
X1778810Y1612997D01*
X1779002Y1612738D01*
G01X1780607Y1610465D02*
X1780837Y1610207D01*
X1781105Y1610052D01*
X1781450Y1610000D01*
X1781795Y1610103D01*
X1782063Y1610310D01*
X1782255Y1610672D01*
X1782293Y1611085D01*
X1782217Y1611498D01*
X1782025Y1611757D01*
X1781757Y1611963D01*
X1781488Y1612015D01*
X1781220Y1611963D01*
X1780875Y1611757D01*
X1780990Y1613100D01*
X1782025D01*
G01X1784550D02*
X1784243Y1612997D01*
X1784013Y1612738D01*
X1783860Y1612428D01*
X1783745Y1612015D01*
X1783707Y1611550D01*
X1783745Y1611085D01*
X1783860Y1610672D01*
X1784013Y1610362D01*
X1784243Y1610103D01*
X1784550Y1610000D01*
X1784857Y1610103D01*
X1785087Y1610362D01*
X1785240Y1610672D01*
X1785355Y1611085D01*
X1785393Y1611550D01*
X1785355Y1612015D01*
X1785240Y1612428D01*
X1785087Y1612738D01*
X1784857Y1612997D01*
X1784550Y1613100D01*
G01X1788110Y1610000D02*
Y1613100D01*
X1786692Y1610878D01*
X1788608D01*
G01X1771123Y1617192D02*
Y1634908D01*
G01X1774531Y1617192D02*
X1771123D01*
G01X1769523Y1637286D02*
Y1634086D01*
G01X1771123Y1634908D02*
X1774531D01*
G01X1772563Y1659065D02*
Y1655865D01*
G01X1766363D02*
Y1659065D01*
G01X1772563Y1655865D02*
X1766363D01*
G01X1766828Y1665384D02*
Y1668584D01*
G01X1773028Y1665384D02*
X1766828D01*
G01X1773028Y1668584D02*
Y1665384D01*
G01X1766828Y1668584D02*
X1773028D01*
G01X1766789Y1668914D02*
Y1672114D01*
G01X1772989Y1668914D02*
X1766789D01*
G01X1772989Y1672114D02*
Y1668914D01*
G01X1772563Y1663065D02*
Y1659865D01*
G01X1766363Y1663065D02*
X1772563D01*
G01X1766363Y1659865D02*
Y1663065D01*
G01X1772563Y1659865D02*
X1766363D01*
G01Y1659065D02*
X1772563D01*
G01X1766363Y1683865D02*
Y1687065D01*
G01X1772563Y1683865D02*
X1766363D01*
G01X1772563Y1687065D02*
Y1683865D01*
G01X1766708Y1672457D02*
Y1675657D01*
G01X1772908Y1672457D02*
X1766708D01*
G01X1772908Y1675657D02*
Y1672457D01*
G01X1766708Y1675657D02*
X1772908D01*
G01X1766363Y1680102D02*
Y1683302D01*
G01X1772563Y1680102D02*
X1766363D01*
G01X1772563Y1683302D02*
Y1680102D01*
G01X1766363Y1683302D02*
X1772563D01*
G01X1766363Y1676572D02*
Y1679772D01*
G01X1772563Y1676572D02*
X1766363D01*
G01X1772563Y1679772D02*
Y1676572D01*
G01X1766363Y1679772D02*
X1772563D01*
G01X1766789Y1672114D02*
X1772989D01*
G01X1766363Y1687065D02*
X1772563D01*
G01X1766363Y1688365D02*
Y1691565D01*
G01X1772563Y1688365D02*
X1766363D01*
G01X1772563Y1691565D02*
Y1688365D01*
G01X1766363Y1691565D02*
X1772563D01*
G01X1780528Y1731417D02*
Y1734517D01*
G01X1782138D02*
Y1731417D01*
G01Y1732967D02*
X1780528D01*
G01X1784433Y1731417D02*
Y1734517D01*
X1783973Y1733897D01*
G01Y1731417D02*
X1784893D01*
G01X1787533Y1734517D02*
X1787226Y1734414D01*
X1786996Y1734155D01*
X1786843Y1733845D01*
X1786728Y1733432D01*
X1786690Y1732967D01*
X1786728Y1732502D01*
X1786843Y1732089D01*
X1786996Y1731779D01*
X1787226Y1731520D01*
X1787533Y1731417D01*
X1787840Y1731520D01*
X1788070Y1731779D01*
X1788223Y1732089D01*
X1788338Y1732502D01*
X1788376Y1732967D01*
X1788338Y1733432D01*
X1788223Y1733845D01*
X1788070Y1734155D01*
X1787840Y1734414D01*
X1787533Y1734517D01*
G01X1789790Y1732037D02*
X1790020Y1731675D01*
X1790326Y1731469D01*
X1790671Y1731417D01*
X1790978Y1731469D01*
X1791285Y1731727D01*
X1791476Y1732037D01*
X1791515Y1732347D01*
X1791438Y1732709D01*
X1791170Y1732967D01*
X1790901Y1733070D01*
X1790556D01*
G01X1790901D02*
X1791131Y1733225D01*
X1791323Y1733484D01*
X1791400Y1733794D01*
X1791323Y1734104D01*
X1791131Y1734362D01*
X1790786Y1734517D01*
X1790441Y1734465D01*
X1790096Y1734259D01*
G01X1794181Y79D02*
Y43779D01*
G01D02*
X1783031D01*
G01X1786063Y72587D02*
X1792263D01*
G01D02*
Y69387D01*
G01D02*
X1786063D01*
G01D02*
Y72587D01*
G01X1792338Y79587D02*
Y73387D01*
G01D02*
X1789138D01*
G01D02*
Y79587D01*
G01D02*
X1792338D01*
G01X1789138Y80767D02*
Y86967D01*
G01D02*
X1792338D01*
G01D02*
Y80767D01*
G01D02*
X1789138D01*
G01X1788816Y88442D02*
Y91542D01*
X1789736D01*
X1790043Y91387D01*
X1790273Y91025D01*
X1790350Y90612D01*
X1790273Y90199D01*
X1790081Y89889D01*
X1789736Y89734D01*
X1788816D01*
G01X1791840Y91542D02*
Y89320D01*
X1791993Y88855D01*
X1792300Y88545D01*
X1792683Y88442D01*
X1793066Y88545D01*
X1793373Y88855D01*
X1793526Y89320D01*
Y91542D01*
G01X1795055Y91025D02*
X1795285Y91335D01*
X1795553Y91490D01*
X1795860Y91542D01*
X1796243Y91439D01*
X1796511Y91180D01*
X1796588Y90870D01*
X1796550Y90560D01*
X1796396Y90302D01*
X1795630Y89785D01*
X1795285Y89424D01*
X1795055Y88907D01*
X1794978Y88442D01*
X1796588D01*
G01X1798883Y91542D02*
X1798576Y91439D01*
X1798346Y91180D01*
X1798193Y90870D01*
X1798078Y90457D01*
X1798040Y89992D01*
X1798078Y89527D01*
X1798193Y89114D01*
X1798346Y88804D01*
X1798576Y88545D01*
X1798883Y88442D01*
X1799190Y88545D01*
X1799420Y88804D01*
X1799573Y89114D01*
X1799688Y89527D01*
X1799726Y89992D01*
X1799688Y90457D01*
X1799573Y90870D01*
X1799420Y91180D01*
X1799190Y91439D01*
X1798883Y91542D01*
G01X1801140Y89062D02*
X1801370Y88700D01*
X1801676Y88494D01*
X1802021Y88442D01*
X1802328Y88494D01*
X1802635Y88752D01*
X1802826Y89062D01*
X1802865Y89372D01*
X1802788Y89734D01*
X1802520Y89992D01*
X1802251Y90095D01*
X1801906D01*
G01X1802251D02*
X1802481Y90250D01*
X1802673Y90509D01*
X1802750Y90819D01*
X1802673Y91129D01*
X1802481Y91387D01*
X1802136Y91542D01*
X1801791Y91490D01*
X1801446Y91284D01*
G01X1784536Y78503D02*
Y86691D01*
G01X1786778Y98527D02*
Y95327D01*
G01Y94527D02*
Y91327D01*
G01X1786736Y102539D02*
Y99339D01*
G01X1788373Y115621D02*
X1785273D01*
Y116541D01*
X1785428Y116848D01*
X1785790Y117078D01*
X1786203Y117155D01*
X1786616Y117078D01*
X1786926Y116886D01*
X1787081Y116541D01*
Y115621D01*
G01X1788373Y118645D02*
X1785273D01*
Y119411D01*
X1785428Y119718D01*
X1785635Y119948D01*
X1785945Y120140D01*
X1786306Y120293D01*
X1786823Y120331D01*
X1787340Y120293D01*
X1787701Y120140D01*
X1788011Y119948D01*
X1788218Y119718D01*
X1788373Y119411D01*
Y118645D01*
G01Y122588D02*
X1785273D01*
X1785893Y122128D01*
G01X1788373D02*
Y123048D01*
G01X1785273Y125688D02*
X1785376Y125381D01*
X1785635Y125151D01*
X1785945Y124998D01*
X1786358Y124883D01*
X1786823Y124845D01*
X1787288Y124883D01*
X1787701Y124998D01*
X1788011Y125151D01*
X1788270Y125381D01*
X1788373Y125688D01*
X1788270Y125995D01*
X1788011Y126225D01*
X1787701Y126378D01*
X1787288Y126493D01*
X1786823Y126531D01*
X1786358Y126493D01*
X1785945Y126378D01*
X1785635Y126225D01*
X1785376Y125995D01*
X1785273Y125688D01*
G01X1788373Y128788D02*
X1785273D01*
X1785893Y128328D01*
G01X1788373D02*
Y129248D01*
G01X1809899Y126194D02*
G02I-9450J0D01*
G01X1788290Y148434D02*
X1794490D01*
G01D02*
Y145234D01*
G01D02*
X1788290D01*
G01D02*
Y148434D01*
G01X1794490Y153434D02*
Y150234D01*
G01D02*
X1788290D01*
G01D02*
Y153434D01*
G01X1794490Y155234D02*
X1788290D01*
G01D02*
Y158434D01*
G01D02*
X1794490D01*
G01D02*
Y155234D01*
G01X1788290Y153434D02*
X1794490D01*
G01Y160234D02*
X1788290D01*
G01D02*
Y163434D01*
G01D02*
X1794490D01*
G01D02*
Y160234D01*
G01Y167434D02*
Y164234D01*
G01D02*
X1788290D01*
G01D02*
Y167434D01*
G01X1785733Y161299D02*
X1782533D01*
G01X1785733Y167499D02*
Y161299D01*
G01X1782533D02*
Y167499D01*
G01Y154210D02*
Y160410D01*
X1785733D01*
Y154210D01*
X1782533D01*
G01X1795044Y185244D02*
Y179044D01*
G01D02*
X1791844D01*
G01D02*
Y185244D01*
G01X1798611Y179044D02*
X1795411D01*
G01D02*
Y185244D01*
G01X1791411D02*
Y179044D01*
G01D02*
X1788211D01*
G01D02*
Y185244D01*
G01X1788290Y167434D02*
X1794490D01*
G01X1782533Y167499D02*
X1785733D01*
G01X1796039Y171192D02*
X1795732Y171244D01*
X1795464Y171450D01*
X1795234Y171760D01*
X1795081Y172122D01*
X1795004Y172535D01*
Y172949D01*
X1795081Y173362D01*
X1795234Y173724D01*
X1795464Y174034D01*
X1795732Y174240D01*
X1796039Y174292D01*
X1796346Y174240D01*
X1796614Y174034D01*
X1796844Y173724D01*
X1796997Y173362D01*
X1797074Y172949D01*
Y172535D01*
X1796997Y172122D01*
X1796844Y171760D01*
X1796614Y171450D01*
X1796346Y171244D01*
X1796039Y171192D01*
G01X1796346Y172019D02*
X1796806Y171192D01*
G01X1799139D02*
Y174292D01*
X1798679Y173672D01*
G01Y171192D02*
X1799599D01*
G01X1801511Y173775D02*
X1801741Y174085D01*
X1802009Y174240D01*
X1802316Y174292D01*
X1802699Y174189D01*
X1802967Y173930D01*
X1803044Y173620D01*
X1803006Y173310D01*
X1802852Y173052D01*
X1802086Y172535D01*
X1801741Y172174D01*
X1801511Y171657D01*
X1801434Y171192D01*
X1803044D01*
G01X1805799D02*
Y174292D01*
X1804381Y172070D01*
X1806297D01*
G01X1791844Y185244D02*
X1795044D01*
G01X1783175Y188511D02*
Y185311D01*
G01Y192399D02*
Y189199D01*
G01X1795411Y185244D02*
X1798611D01*
G01X1783175Y195999D02*
Y192799D01*
G01X1788211Y185244D02*
X1791411D01*
G01X1785604Y184063D02*
Y180863D01*
G01X1787206Y191131D02*
Y189043D01*
G01D02*
X1789245D01*
G01X1783231Y199499D02*
Y196299D01*
G01X1781848Y205857D02*
Y212057D01*
G01X1785048D02*
Y205857D01*
G01D02*
X1781848D01*
G01Y212057D02*
X1785048D01*
G01X1787206Y213059D02*
Y211200D01*
G01X1788840Y213059D02*
X1787206D01*
G01X1813388Y289855D02*
G02I-13386J0D01*
G01D02*
X1786616D01*
G01X1790671Y369466D02*
X1796871D01*
G01Y366266D02*
X1790671D01*
G01D02*
Y369466D01*
G01X1796871Y388811D02*
X1790671D01*
G01D02*
Y392011D01*
G01X1789399Y405532D02*
Y402332D01*
G01D02*
X1783199D01*
G01D02*
Y405532D01*
G01X1790671Y392011D02*
X1796871D01*
G01X1793486Y396969D02*
Y394747D01*
X1793639Y394282D01*
X1793946Y393972D01*
X1794329Y393869D01*
X1794712Y393972D01*
X1795019Y394282D01*
X1795172Y394747D01*
Y396969D01*
G01X1796701Y395161D02*
X1796969Y395522D01*
X1797199Y395729D01*
X1797506Y395832D01*
X1797774Y395729D01*
X1797966Y395522D01*
X1798119Y395212D01*
X1798157Y394851D01*
X1798119Y394541D01*
X1797966Y394231D01*
X1797736Y393972D01*
X1797467Y393869D01*
X1797161Y393972D01*
X1796892Y394282D01*
X1796739Y394747D01*
X1796701Y395264D01*
X1796777Y395936D01*
X1796892Y396297D01*
X1797084Y396659D01*
X1797352Y396917D01*
X1797621Y396969D01*
X1797889Y396866D01*
X1798081Y396607D01*
G01X1799801Y395161D02*
X1800069Y395522D01*
X1800299Y395729D01*
X1800606Y395832D01*
X1800874Y395729D01*
X1801066Y395522D01*
X1801219Y395212D01*
X1801257Y394851D01*
X1801219Y394541D01*
X1801066Y394231D01*
X1800836Y393972D01*
X1800567Y393869D01*
X1800261Y393972D01*
X1799992Y394282D01*
X1799839Y394747D01*
X1799801Y395264D01*
X1799877Y395936D01*
X1799992Y396297D01*
X1800184Y396659D01*
X1800452Y396917D01*
X1800721Y396969D01*
X1800989Y396866D01*
X1801181Y396607D01*
G01X1783199Y412032D02*
X1789399D01*
G01D02*
Y408832D01*
G01D02*
X1783199D01*
G01D02*
Y412032D01*
G01X1789399Y420532D02*
Y417332D01*
G01D02*
X1783199D01*
G01D02*
Y420532D01*
G01Y405532D02*
X1789399D01*
G01X1791076Y416373D02*
Y414151D01*
X1791229Y413686D01*
X1791536Y413376D01*
X1791919Y413273D01*
X1792302Y413376D01*
X1792609Y413686D01*
X1792762Y414151D01*
Y416373D01*
G01X1795019Y413273D02*
X1795287Y413325D01*
X1795594Y413480D01*
X1795786Y413738D01*
X1795862Y414100D01*
X1795786Y414461D01*
X1795556Y414771D01*
X1795211Y414926D01*
X1794827D01*
X1794597Y415030D01*
X1794406Y415288D01*
X1794329Y415650D01*
X1794444Y416011D01*
X1794712Y416270D01*
X1795019Y416373D01*
X1795326Y416270D01*
X1795594Y416011D01*
X1795709Y415650D01*
X1795632Y415288D01*
X1795441Y415030D01*
X1795211Y414926D01*
X1794827D01*
X1794482Y414771D01*
X1794252Y414461D01*
X1794176Y414100D01*
X1794252Y413738D01*
X1794444Y413480D01*
X1794751Y413325D01*
X1795019Y413273D01*
G01X1783199Y427032D02*
X1789399D01*
G01D02*
Y423832D01*
G01D02*
X1783199D01*
G01D02*
Y427032D01*
G01Y420532D02*
X1789399D01*
G01X1796415Y430001D02*
Y427779D01*
X1796568Y427314D01*
X1796875Y427004D01*
X1797258Y426901D01*
X1797641Y427004D01*
X1797948Y427314D01*
X1798101Y427779D01*
Y430001D01*
G01X1799630Y429484D02*
X1799860Y429794D01*
X1800128Y429949D01*
X1800435Y430001D01*
X1800818Y429898D01*
X1801086Y429639D01*
X1801163Y429329D01*
X1801125Y429019D01*
X1800971Y428761D01*
X1800205Y428244D01*
X1799860Y427883D01*
X1799630Y427366D01*
X1799553Y426901D01*
X1801163D01*
G01X1803458D02*
Y430001D01*
X1802998Y429381D01*
G01Y426901D02*
X1803918D01*
G01X1806558D02*
Y430001D01*
X1806098Y429381D01*
G01Y426901D02*
X1807018D01*
G01X1792866Y1325040D02*
Y687244D01*
G01X1794883Y692500D02*
Y695600D01*
X1795842D01*
X1796148Y695445D01*
X1796340Y695238D01*
X1796417Y694825D01*
X1796340Y694412D01*
X1796110Y694153D01*
X1795842Y693998D01*
X1794883D01*
G01X1795842D02*
X1796417Y692500D01*
G01X1798750D02*
Y695600D01*
X1798290Y694980D01*
G01Y692500D02*
X1799210D01*
G01X1801850D02*
X1802118Y692552D01*
X1802425Y692707D01*
X1802617Y692965D01*
X1802693Y693327D01*
X1802617Y693688D01*
X1802387Y693998D01*
X1802042Y694153D01*
X1801658D01*
X1801428Y694257D01*
X1801237Y694515D01*
X1801160Y694877D01*
X1801275Y695238D01*
X1801543Y695497D01*
X1801850Y695600D01*
X1802157Y695497D01*
X1802425Y695238D01*
X1802540Y694877D01*
X1802463Y694515D01*
X1802272Y694257D01*
X1802042Y694153D01*
X1801658D01*
X1801313Y693998D01*
X1801083Y693688D01*
X1801007Y693327D01*
X1801083Y692965D01*
X1801275Y692707D01*
X1801582Y692552D01*
X1801850Y692500D01*
G01X1804107Y693120D02*
X1804337Y692758D01*
X1804643Y692552D01*
X1804988Y692500D01*
X1805295Y692552D01*
X1805602Y692810D01*
X1805793Y693120D01*
X1805832Y693430D01*
X1805755Y693792D01*
X1805487Y694050D01*
X1805218Y694153D01*
X1804873D01*
G01X1805218D02*
X1805448Y694308D01*
X1805640Y694567D01*
X1805717Y694877D01*
X1805640Y695187D01*
X1805448Y695445D01*
X1805103Y695600D01*
X1804758Y695548D01*
X1804413Y695342D01*
G01X1808050Y692500D02*
X1808318Y692552D01*
X1808625Y692707D01*
X1808817Y692965D01*
X1808893Y693327D01*
X1808817Y693688D01*
X1808587Y693998D01*
X1808242Y694153D01*
X1807858D01*
X1807628Y694257D01*
X1807437Y694515D01*
X1807360Y694877D01*
X1807475Y695238D01*
X1807743Y695497D01*
X1808050Y695600D01*
X1808357Y695497D01*
X1808625Y695238D01*
X1808740Y694877D01*
X1808663Y694515D01*
X1808472Y694257D01*
X1808242Y694153D01*
X1807858D01*
X1807513Y693998D01*
X1807283Y693688D01*
X1807207Y693327D01*
X1807283Y692965D01*
X1807475Y692707D01*
X1807782Y692552D01*
X1808050Y692500D01*
G01X1790929Y715979D02*
Y702179D01*
G01X1796471Y1389911D02*
Y1393011D01*
G01X1798081D02*
Y1389911D01*
G01Y1391461D02*
X1796471D01*
G01X1799724Y1390273D02*
X1799993Y1390014D01*
X1800299Y1389911D01*
X1800606Y1390014D01*
X1800874Y1390324D01*
X1801066Y1390789D01*
X1801143Y1391254D01*
Y1391823D01*
X1801066Y1392288D01*
X1800874Y1392701D01*
X1800644Y1392908D01*
X1800376Y1393011D01*
X1800069Y1392908D01*
X1799839Y1392701D01*
X1799686Y1392391D01*
X1799609Y1391978D01*
X1799686Y1391616D01*
X1799878Y1391254D01*
X1800108Y1391048D01*
X1800376Y1390996D01*
X1800683Y1391099D01*
X1800913Y1391358D01*
X1801143Y1391823D01*
G01X1802633Y1390376D02*
X1802863Y1390118D01*
X1803131Y1389963D01*
X1803476Y1389911D01*
X1803821Y1390014D01*
X1804089Y1390221D01*
X1804281Y1390583D01*
X1804319Y1390996D01*
X1804243Y1391409D01*
X1804051Y1391668D01*
X1803783Y1391874D01*
X1803514Y1391926D01*
X1803246Y1391874D01*
X1802901Y1391668D01*
X1803016Y1393011D01*
X1804051D01*
G01X1787883Y1477000D02*
Y1480100D01*
X1788803D01*
X1789110Y1479945D01*
X1789340Y1479583D01*
X1789417Y1479170D01*
X1789340Y1478757D01*
X1789148Y1478447D01*
X1788803Y1478292D01*
X1787883D01*
G01X1792593Y1479842D02*
X1792363Y1479997D01*
X1792095Y1480100D01*
X1791788D01*
X1791443Y1479945D01*
X1791175Y1479687D01*
X1790983Y1479377D01*
X1790830Y1478860D01*
X1790792Y1478395D01*
X1790868Y1477930D01*
X1790983Y1477620D01*
X1791213Y1477310D01*
X1791482Y1477103D01*
X1791750Y1477000D01*
X1792018D01*
X1792287Y1477103D01*
X1792517Y1477258D01*
X1792708Y1477465D01*
G01X1794122Y1478292D02*
X1794390Y1478653D01*
X1794620Y1478860D01*
X1794927Y1478963D01*
X1795195Y1478860D01*
X1795387Y1478653D01*
X1795540Y1478343D01*
X1795578Y1477982D01*
X1795540Y1477672D01*
X1795387Y1477362D01*
X1795157Y1477103D01*
X1794888Y1477000D01*
X1794582Y1477103D01*
X1794313Y1477413D01*
X1794160Y1477878D01*
X1794122Y1478395D01*
X1794198Y1479067D01*
X1794313Y1479428D01*
X1794505Y1479790D01*
X1794773Y1480048D01*
X1795042Y1480100D01*
X1795310Y1479997D01*
X1795502Y1479738D01*
G01X1797107Y1477465D02*
X1797337Y1477207D01*
X1797605Y1477052D01*
X1797950Y1477000D01*
X1798295Y1477103D01*
X1798563Y1477310D01*
X1798755Y1477672D01*
X1798793Y1478085D01*
X1798717Y1478498D01*
X1798525Y1478757D01*
X1798257Y1478963D01*
X1797988Y1479015D01*
X1797720Y1478963D01*
X1797375Y1478757D01*
X1797490Y1480100D01*
X1798525D01*
G01X1800973Y1477000D02*
X1801050Y1477672D01*
X1801165Y1478240D01*
X1801318Y1478757D01*
X1801510Y1479325D01*
X1801817Y1480100D01*
X1800283D01*
G01X1803307Y1477620D02*
X1803537Y1477258D01*
X1803843Y1477052D01*
X1804188Y1477000D01*
X1804495Y1477052D01*
X1804802Y1477310D01*
X1804993Y1477620D01*
X1805032Y1477930D01*
X1804955Y1478292D01*
X1804687Y1478550D01*
X1804418Y1478653D01*
X1804073D01*
G01X1804418D02*
X1804648Y1478808D01*
X1804840Y1479067D01*
X1804917Y1479377D01*
X1804840Y1479687D01*
X1804648Y1479945D01*
X1804303Y1480100D01*
X1803958Y1480048D01*
X1803613Y1479842D01*
G01X1784652Y1485778D02*
X1791779D01*
G01X1784652Y1504432D02*
Y1485778D01*
G01X1782306D02*
Y1504432D01*
G01X1787652Y1507432D02*
X1784652Y1504432D01*
G01X1791779Y1507432D02*
X1787652D01*
G01X1799774Y1522941D02*
X1795779D01*
G01Y1548531D02*
X1799774D01*
G01X1794194Y1578432D02*
Y1584632D01*
G01X1797394Y1578432D02*
X1794194D01*
G01X1793394D02*
X1790194D01*
G01X1793394Y1584632D02*
Y1578432D01*
G01X1790194D02*
Y1584632D01*
G01X1794194D02*
X1797394D01*
G01X1790304Y1588705D02*
X1796504D01*
G01X1790304Y1585505D02*
Y1588705D01*
G01X1796504Y1585505D02*
X1790304D01*
G01X1787394Y1587432D02*
Y1584232D01*
G01X1790194Y1584632D02*
X1793394D01*
G01X1816579Y1625250D02*
Y1632377D01*
X1797925D01*
X1794925Y1629377D01*
Y1625250D01*
G01Y1617850D02*
Y1613723D01*
X1797925Y1610723D01*
G01X1788839Y1617192D02*
X1785431D01*
G01X1788839Y1634908D02*
Y1617192D01*
G01X1785431Y1634908D02*
X1788839D01*
G01X1814100Y1667292D02*
G02I-9450J0D01*
G01X1796307Y-2520D02*
Y51142D01*
G01X1810478Y62546D02*
X1808238D01*
G01X1809451Y60921D02*
Y64171D01*
G01X1806405Y51680D02*
Y54780D01*
X1807325D01*
X1807632Y54625D01*
X1807862Y54263D01*
X1807939Y53850D01*
X1807862Y53437D01*
X1807670Y53127D01*
X1807325Y52972D01*
X1806405D01*
G01X1809429Y51680D02*
Y54780D01*
X1810195D01*
X1810502Y54625D01*
X1810732Y54418D01*
X1810924Y54108D01*
X1811077Y53747D01*
X1811115Y53230D01*
X1811077Y52713D01*
X1810924Y52352D01*
X1810732Y52042D01*
X1810502Y51835D01*
X1810195Y51680D01*
X1809429D01*
G01X1813372D02*
Y54780D01*
X1812912Y54160D01*
G01Y51680D02*
X1813832D01*
G01X1816472Y54780D02*
X1816165Y54677D01*
X1815935Y54418D01*
X1815782Y54108D01*
X1815667Y53695D01*
X1815629Y53230D01*
X1815667Y52765D01*
X1815782Y52352D01*
X1815935Y52042D01*
X1816165Y51783D01*
X1816472Y51680D01*
X1816779Y51783D01*
X1817009Y52042D01*
X1817162Y52352D01*
X1817277Y52765D01*
X1817315Y53230D01*
X1817277Y53695D01*
X1817162Y54108D01*
X1817009Y54418D01*
X1816779Y54677D01*
X1816472Y54780D01*
G01X1818844Y54263D02*
X1819074Y54573D01*
X1819342Y54728D01*
X1819649Y54780D01*
X1820032Y54677D01*
X1820300Y54418D01*
X1820377Y54108D01*
X1820339Y53798D01*
X1820185Y53540D01*
X1819419Y53023D01*
X1819074Y52662D01*
X1818844Y52145D01*
X1818767Y51680D01*
X1820377D01*
G01X1805624Y66785D02*
Y55289D01*
G01X1810039Y108658D02*
Y111758D01*
G01X1811649D02*
Y108658D01*
G01Y110208D02*
X1810039D01*
G01X1813292Y109020D02*
X1813561Y108761D01*
X1813867Y108658D01*
X1814174Y108761D01*
X1814442Y109071D01*
X1814634Y109536D01*
X1814711Y110001D01*
Y110570D01*
X1814634Y111035D01*
X1814442Y111448D01*
X1814212Y111655D01*
X1813944Y111758D01*
X1813637Y111655D01*
X1813407Y111448D01*
X1813254Y111138D01*
X1813177Y110725D01*
X1813254Y110363D01*
X1813446Y110001D01*
X1813676Y109795D01*
X1813944Y109743D01*
X1814251Y109846D01*
X1814481Y110105D01*
X1814711Y110570D01*
G01X1816316Y109950D02*
X1816584Y110311D01*
X1816814Y110518D01*
X1817121Y110621D01*
X1817389Y110518D01*
X1817581Y110311D01*
X1817734Y110001D01*
X1817772Y109640D01*
X1817734Y109330D01*
X1817581Y109020D01*
X1817351Y108761D01*
X1817082Y108658D01*
X1816776Y108761D01*
X1816507Y109071D01*
X1816354Y109536D01*
X1816316Y110053D01*
X1816392Y110725D01*
X1816507Y111086D01*
X1816699Y111448D01*
X1816967Y111706D01*
X1817236Y111758D01*
X1817504Y111655D01*
X1817696Y111396D01*
G01X1797897Y143142D02*
Y140920D01*
X1798050Y140455D01*
X1798357Y140145D01*
X1798740Y140042D01*
X1799123Y140145D01*
X1799430Y140455D01*
X1799583Y140920D01*
Y143142D01*
G01X1801840Y140042D02*
X1802108Y140094D01*
X1802415Y140249D01*
X1802607Y140507D01*
X1802683Y140869D01*
X1802607Y141230D01*
X1802377Y141540D01*
X1802032Y141695D01*
X1801648D01*
X1801418Y141799D01*
X1801227Y142057D01*
X1801150Y142419D01*
X1801265Y142780D01*
X1801533Y143039D01*
X1801840Y143142D01*
X1802147Y143039D01*
X1802415Y142780D01*
X1802530Y142419D01*
X1802453Y142057D01*
X1802262Y141799D01*
X1802032Y141695D01*
X1801648D01*
X1801303Y141540D01*
X1801073Y141230D01*
X1800997Y140869D01*
X1801073Y140507D01*
X1801265Y140249D01*
X1801572Y140094D01*
X1801840Y140042D01*
G01X1804940Y143142D02*
X1804633Y143039D01*
X1804403Y142780D01*
X1804250Y142470D01*
X1804135Y142057D01*
X1804097Y141592D01*
X1804135Y141127D01*
X1804250Y140714D01*
X1804403Y140404D01*
X1804633Y140145D01*
X1804940Y140042D01*
X1805247Y140145D01*
X1805477Y140404D01*
X1805630Y140714D01*
X1805745Y141127D01*
X1805783Y141592D01*
X1805745Y142057D01*
X1805630Y142470D01*
X1805477Y142780D01*
X1805247Y143039D01*
X1804940Y143142D01*
G01X1808040Y140042D02*
X1808308Y140094D01*
X1808615Y140249D01*
X1808807Y140507D01*
X1808883Y140869D01*
X1808807Y141230D01*
X1808577Y141540D01*
X1808232Y141695D01*
X1807848D01*
X1807618Y141799D01*
X1807427Y142057D01*
X1807350Y142419D01*
X1807465Y142780D01*
X1807733Y143039D01*
X1808040Y143142D01*
X1808347Y143039D01*
X1808615Y142780D01*
X1808730Y142419D01*
X1808653Y142057D01*
X1808462Y141799D01*
X1808232Y141695D01*
X1807848D01*
X1807503Y141540D01*
X1807273Y141230D01*
X1807197Y140869D01*
X1807273Y140507D01*
X1807465Y140249D01*
X1807772Y140094D01*
X1808040Y140042D01*
G01X1810412Y142625D02*
X1810642Y142935D01*
X1810910Y143090D01*
X1811217Y143142D01*
X1811600Y143039D01*
X1811868Y142780D01*
X1811945Y142470D01*
X1811907Y142160D01*
X1811753Y141902D01*
X1810987Y141385D01*
X1810642Y141024D01*
X1810412Y140507D01*
X1810335Y140042D01*
X1811945D01*
G01X1812052Y144944D02*
X1801028D01*
G01D02*
Y153606D01*
G01X1804405Y166165D02*
X1806305Y163965D01*
G01D02*
X1808205Y166165D01*
G01X1811552Y157503D02*
X1801058D01*
G01D02*
Y166165D01*
G01X1812052Y153606D02*
X1801028D01*
G01X1802111Y185244D02*
Y179044D01*
G01D02*
X1798911D01*
G01D02*
Y185244D01*
G01X1798611D02*
Y179044D01*
G01X1805711Y185244D02*
Y179044D01*
G01D02*
X1802511D01*
G01D02*
Y185244D01*
G01X1809311D02*
Y179044D01*
G01D02*
X1806111D01*
G01D02*
Y185244D01*
G01X1813311Y175944D02*
X1810111D01*
G01D02*
Y182144D01*
G01X1801058Y166165D02*
X1804405D01*
G01X1808205D02*
X1811552D01*
G01X1798911Y185244D02*
X1802111D01*
G01X1802511D02*
X1805711D01*
G01X1806111D02*
X1809311D01*
G01X1810111Y182144D02*
X1813311D01*
G01X1814474Y183599D02*
X1809874D01*
G01D02*
Y193799D01*
G01D02*
X1814474D01*
G01X1805245Y189043D02*
X1807284D01*
G01D02*
Y191131D01*
G01X1809527Y200398D02*
Y210598D01*
G01X1814127Y200398D02*
X1809527D01*
G01Y210598D02*
X1814127D01*
G01X1807284Y213059D02*
X1805440D01*
G01X1807284Y211200D02*
Y213059D01*
G01X1821190Y216237D02*
X1806196D01*
G01X1809051Y275436D02*
Y278536D01*
X1809971D01*
X1810278Y278381D01*
X1810508Y278019D01*
X1810585Y277606D01*
X1810508Y277193D01*
X1810316Y276883D01*
X1809971Y276728D01*
X1809051D01*
G01X1813761Y278278D02*
X1813531Y278433D01*
X1813263Y278536D01*
X1812956D01*
X1812611Y278381D01*
X1812343Y278123D01*
X1812151Y277813D01*
X1811998Y277296D01*
X1811960Y276831D01*
X1812036Y276366D01*
X1812151Y276056D01*
X1812381Y275746D01*
X1812650Y275539D01*
X1812918Y275436D01*
X1813186D01*
X1813455Y275539D01*
X1813685Y275694D01*
X1813876Y275901D01*
G01X1816018Y275436D02*
Y278536D01*
X1815558Y277916D01*
G01Y275436D02*
X1816478D01*
G01X1819118D02*
X1819386Y275488D01*
X1819693Y275643D01*
X1819885Y275901D01*
X1819961Y276263D01*
X1819885Y276624D01*
X1819655Y276934D01*
X1819310Y277089D01*
X1818926D01*
X1818696Y277193D01*
X1818505Y277451D01*
X1818428Y277813D01*
X1818543Y278174D01*
X1818811Y278433D01*
X1819118Y278536D01*
X1819425Y278433D01*
X1819693Y278174D01*
X1819808Y277813D01*
X1819731Y277451D01*
X1819540Y277193D01*
X1819310Y277089D01*
X1818926D01*
X1818581Y276934D01*
X1818351Y276624D01*
X1818275Y276263D01*
X1818351Y275901D01*
X1818543Y275643D01*
X1818850Y275488D01*
X1819118Y275436D01*
G01X1821490Y276728D02*
X1821758Y277089D01*
X1821988Y277296D01*
X1822295Y277399D01*
X1822563Y277296D01*
X1822755Y277089D01*
X1822908Y276779D01*
X1822946Y276418D01*
X1822908Y276108D01*
X1822755Y275798D01*
X1822525Y275539D01*
X1822256Y275436D01*
X1821950Y275539D01*
X1821681Y275849D01*
X1821528Y276314D01*
X1821490Y276831D01*
X1821566Y277503D01*
X1821681Y277864D01*
X1821873Y278226D01*
X1822141Y278484D01*
X1822410Y278536D01*
X1822678Y278433D01*
X1822870Y278174D01*
G01X1824590Y276728D02*
X1824858Y277089D01*
X1825088Y277296D01*
X1825395Y277399D01*
X1825663Y277296D01*
X1825855Y277089D01*
X1826008Y276779D01*
X1826046Y276418D01*
X1826008Y276108D01*
X1825855Y275798D01*
X1825625Y275539D01*
X1825356Y275436D01*
X1825050Y275539D01*
X1824781Y275849D01*
X1824628Y276314D01*
X1824590Y276831D01*
X1824666Y277503D01*
X1824781Y277864D01*
X1824973Y278226D01*
X1825241Y278484D01*
X1825510Y278536D01*
X1825778Y278433D01*
X1825970Y278174D01*
G01X1806196Y272537D02*
X1821190D01*
G01X1796871Y369466D02*
Y366266D01*
G01X1802616Y377379D02*
Y375157D01*
X1802769Y374692D01*
X1803076Y374382D01*
X1803459Y374279D01*
X1803842Y374382D01*
X1804149Y374692D01*
X1804302Y375157D01*
Y377379D01*
G01X1805831Y376862D02*
X1806061Y377172D01*
X1806329Y377327D01*
X1806636Y377379D01*
X1807019Y377276D01*
X1807287Y377017D01*
X1807364Y376707D01*
X1807326Y376397D01*
X1807172Y376139D01*
X1806406Y375622D01*
X1806061Y375261D01*
X1805831Y374744D01*
X1805754Y374279D01*
X1807364D01*
G01X1808931Y376862D02*
X1809161Y377172D01*
X1809429Y377327D01*
X1809736Y377379D01*
X1810119Y377276D01*
X1810387Y377017D01*
X1810464Y376707D01*
X1810426Y376397D01*
X1810272Y376139D01*
X1809506Y375622D01*
X1809161Y375261D01*
X1808931Y374744D01*
X1808854Y374279D01*
X1810464D01*
G01X1813219D02*
Y377379D01*
X1811801Y375157D01*
X1813717D01*
G01X1814321Y364281D02*
X1803297D01*
G01D02*
Y372943D01*
G01X1814321D02*
X1803297D01*
G01X1796871Y392011D02*
Y388811D01*
G01X1814881Y383521D02*
X1803857D01*
G01D02*
Y392183D01*
G01X1814881D02*
X1803857D01*
G01X1796479Y412387D02*
Y403725D01*
G01D02*
X1807359D01*
G01D02*
Y412387D01*
G01X1796468Y425665D02*
Y417003D01*
G01D02*
X1807348D01*
G01D02*
Y425665D01*
G01X1801919Y410056D02*
X1799588Y412387D01*
G01D02*
X1796479D01*
G01X1807359D02*
X1804250D01*
G01D02*
X1801919Y410056D01*
G01X1801908Y423334D02*
X1799577Y425665D01*
G01D02*
X1796468D01*
G01X1807348D02*
X1804239D01*
G01D02*
X1801908Y423334D01*
G01X1805084Y654084D02*
Y657184D01*
G01X1806694D02*
Y654084D01*
G01Y655634D02*
X1805084D01*
G01X1808337Y654446D02*
X1808606Y654187D01*
X1808912Y654084D01*
X1809219Y654187D01*
X1809487Y654497D01*
X1809679Y654962D01*
X1809756Y655427D01*
Y655996D01*
X1809679Y656461D01*
X1809487Y656874D01*
X1809257Y657081D01*
X1808989Y657184D01*
X1808682Y657081D01*
X1808452Y656874D01*
X1808299Y656564D01*
X1808222Y656151D01*
X1808299Y655789D01*
X1808491Y655427D01*
X1808721Y655221D01*
X1808989Y655169D01*
X1809296Y655272D01*
X1809526Y655531D01*
X1809756Y655996D01*
G01X1812089Y654084D02*
X1812357Y654136D01*
X1812664Y654291D01*
X1812856Y654549D01*
X1812932Y654911D01*
X1812856Y655272D01*
X1812626Y655582D01*
X1812281Y655737D01*
X1811897D01*
X1811667Y655841D01*
X1811476Y656099D01*
X1811399Y656461D01*
X1811514Y656822D01*
X1811782Y657081D01*
X1812089Y657184D01*
X1812396Y657081D01*
X1812664Y656822D01*
X1812779Y656461D01*
X1812702Y656099D01*
X1812511Y655841D01*
X1812281Y655737D01*
X1811897D01*
X1811552Y655582D01*
X1811322Y655272D01*
X1811246Y654911D01*
X1811322Y654549D01*
X1811514Y654291D01*
X1811821Y654136D01*
X1812089Y654084D01*
G01X1811383Y1477000D02*
Y1480100D01*
X1812303D01*
X1812610Y1479945D01*
X1812840Y1479583D01*
X1812917Y1479170D01*
X1812840Y1478757D01*
X1812648Y1478447D01*
X1812303Y1478292D01*
X1811383D01*
G01X1816093Y1479842D02*
X1815863Y1479997D01*
X1815595Y1480100D01*
X1815288D01*
X1814943Y1479945D01*
X1814675Y1479687D01*
X1814483Y1479377D01*
X1814330Y1478860D01*
X1814292Y1478395D01*
X1814368Y1477930D01*
X1814483Y1477620D01*
X1814713Y1477310D01*
X1814982Y1477103D01*
X1815250Y1477000D01*
X1815518D01*
X1815787Y1477103D01*
X1816017Y1477258D01*
X1816208Y1477465D01*
G01X1817622Y1478292D02*
X1817890Y1478653D01*
X1818120Y1478860D01*
X1818427Y1478963D01*
X1818695Y1478860D01*
X1818887Y1478653D01*
X1819040Y1478343D01*
X1819078Y1477982D01*
X1819040Y1477672D01*
X1818887Y1477362D01*
X1818657Y1477103D01*
X1818388Y1477000D01*
X1818082Y1477103D01*
X1817813Y1477413D01*
X1817660Y1477878D01*
X1817622Y1478395D01*
X1817698Y1479067D01*
X1817813Y1479428D01*
X1818005Y1479790D01*
X1818273Y1480048D01*
X1818542Y1480100D01*
X1818810Y1479997D01*
X1819002Y1479738D01*
G01X1820607Y1477465D02*
X1820837Y1477207D01*
X1821105Y1477052D01*
X1821450Y1477000D01*
X1821795Y1477103D01*
X1822063Y1477310D01*
X1822255Y1477672D01*
X1822293Y1478085D01*
X1822217Y1478498D01*
X1822025Y1478757D01*
X1821757Y1478963D01*
X1821488Y1479015D01*
X1821220Y1478963D01*
X1820875Y1478757D01*
X1820990Y1480100D01*
X1822025D01*
G01X1824473Y1477000D02*
X1824550Y1477672D01*
X1824665Y1478240D01*
X1824818Y1478757D01*
X1825010Y1479325D01*
X1825317Y1480100D01*
X1823783D01*
G01X1826922Y1479583D02*
X1827152Y1479893D01*
X1827420Y1480048D01*
X1827727Y1480100D01*
X1828110Y1479997D01*
X1828378Y1479738D01*
X1828455Y1479428D01*
X1828417Y1479118D01*
X1828263Y1478860D01*
X1827497Y1478343D01*
X1827152Y1477982D01*
X1826922Y1477465D01*
X1826845Y1477000D01*
X1828455D01*
G01X1808652Y1485778D02*
X1815779D01*
G01X1808652Y1504432D02*
Y1485778D01*
G01X1806306D02*
Y1504432D01*
G01X1799179Y1485778D02*
X1806306D01*
G01X1811652Y1507432D02*
X1808652Y1504432D01*
G01X1806306D02*
X1803306Y1507432D01*
G01D02*
X1799179D01*
G01X1811000Y1531883D02*
X1807900D01*
Y1532803D01*
X1808055Y1533110D01*
X1808417Y1533340D01*
X1808830Y1533417D01*
X1809243Y1533340D01*
X1809553Y1533148D01*
X1809708Y1532803D01*
Y1531883D01*
G01X1807900Y1534983D02*
X1811000D01*
Y1536517D01*
G01X1809708Y1538122D02*
X1809347Y1538390D01*
X1809140Y1538620D01*
X1809037Y1538927D01*
X1809140Y1539195D01*
X1809347Y1539387D01*
X1809657Y1539540D01*
X1810018Y1539578D01*
X1810328Y1539540D01*
X1810638Y1539387D01*
X1810897Y1539157D01*
X1811000Y1538888D01*
X1810897Y1538582D01*
X1810587Y1538313D01*
X1810122Y1538160D01*
X1809605Y1538122D01*
X1808933Y1538198D01*
X1808572Y1538313D01*
X1808210Y1538505D01*
X1807952Y1538773D01*
X1807900Y1539042D01*
X1808003Y1539310D01*
X1808262Y1539502D01*
G01X1810535Y1541107D02*
X1810793Y1541337D01*
X1810948Y1541605D01*
X1811000Y1541950D01*
X1810897Y1542295D01*
X1810690Y1542563D01*
X1810328Y1542755D01*
X1809915Y1542793D01*
X1809502Y1542717D01*
X1809243Y1542525D01*
X1809037Y1542257D01*
X1808985Y1541988D01*
X1809037Y1541720D01*
X1809243Y1541375D01*
X1807900Y1541490D01*
Y1542525D01*
G01Y1545050D02*
X1808003Y1544743D01*
X1808262Y1544513D01*
X1808572Y1544360D01*
X1808985Y1544245D01*
X1809450Y1544207D01*
X1809915Y1544245D01*
X1810328Y1544360D01*
X1810638Y1544513D01*
X1810897Y1544743D01*
X1811000Y1545050D01*
X1810897Y1545357D01*
X1810638Y1545587D01*
X1810328Y1545740D01*
X1809915Y1545855D01*
X1809450Y1545893D01*
X1808985Y1545855D01*
X1808572Y1545740D01*
X1808262Y1545587D01*
X1808003Y1545357D01*
X1807900Y1545050D01*
G01X1809708Y1547422D02*
X1809347Y1547690D01*
X1809140Y1547920D01*
X1809037Y1548227D01*
X1809140Y1548495D01*
X1809347Y1548687D01*
X1809657Y1548840D01*
X1810018Y1548878D01*
X1810328Y1548840D01*
X1810638Y1548687D01*
X1810897Y1548457D01*
X1811000Y1548188D01*
X1810897Y1547882D01*
X1810587Y1547613D01*
X1810122Y1547460D01*
X1809605Y1547422D01*
X1808933Y1547498D01*
X1808572Y1547613D01*
X1808210Y1547805D01*
X1807952Y1548073D01*
X1807900Y1548342D01*
X1808003Y1548610D01*
X1808262Y1548802D01*
G01X1799774Y1548531D02*
Y1522941D01*
G01X1806500Y1531883D02*
X1803400D01*
Y1532803D01*
X1803555Y1533110D01*
X1803917Y1533340D01*
X1804330Y1533417D01*
X1804743Y1533340D01*
X1805053Y1533148D01*
X1805208Y1532803D01*
Y1531883D01*
G01X1803400Y1534983D02*
X1806500D01*
Y1536517D01*
G01X1805208Y1538122D02*
X1804847Y1538390D01*
X1804640Y1538620D01*
X1804537Y1538927D01*
X1804640Y1539195D01*
X1804847Y1539387D01*
X1805157Y1539540D01*
X1805518Y1539578D01*
X1805828Y1539540D01*
X1806138Y1539387D01*
X1806397Y1539157D01*
X1806500Y1538888D01*
X1806397Y1538582D01*
X1806087Y1538313D01*
X1805622Y1538160D01*
X1805105Y1538122D01*
X1804433Y1538198D01*
X1804072Y1538313D01*
X1803710Y1538505D01*
X1803452Y1538773D01*
X1803400Y1539042D01*
X1803503Y1539310D01*
X1803762Y1539502D01*
G01X1806035Y1541107D02*
X1806293Y1541337D01*
X1806448Y1541605D01*
X1806500Y1541950D01*
X1806397Y1542295D01*
X1806190Y1542563D01*
X1805828Y1542755D01*
X1805415Y1542793D01*
X1805002Y1542717D01*
X1804743Y1542525D01*
X1804537Y1542257D01*
X1804485Y1541988D01*
X1804537Y1541720D01*
X1804743Y1541375D01*
X1803400Y1541490D01*
Y1542525D01*
G01Y1545050D02*
X1803503Y1544743D01*
X1803762Y1544513D01*
X1804072Y1544360D01*
X1804485Y1544245D01*
X1804950Y1544207D01*
X1805415Y1544245D01*
X1805828Y1544360D01*
X1806138Y1544513D01*
X1806397Y1544743D01*
X1806500Y1545050D01*
X1806397Y1545357D01*
X1806138Y1545587D01*
X1805828Y1545740D01*
X1805415Y1545855D01*
X1804950Y1545893D01*
X1804485Y1545855D01*
X1804072Y1545740D01*
X1803762Y1545587D01*
X1803503Y1545357D01*
X1803400Y1545050D01*
G01X1806035Y1547307D02*
X1806293Y1547537D01*
X1806448Y1547805D01*
X1806500Y1548150D01*
X1806397Y1548495D01*
X1806190Y1548763D01*
X1805828Y1548955D01*
X1805415Y1548993D01*
X1805002Y1548917D01*
X1804743Y1548725D01*
X1804537Y1548457D01*
X1804485Y1548188D01*
X1804537Y1547920D01*
X1804743Y1547575D01*
X1803400Y1547690D01*
Y1548725D01*
G01X1800749Y1561163D02*
Y1567363D01*
G01X1803949Y1561163D02*
X1800749D01*
G01X1803949Y1567363D02*
Y1561163D01*
G01X1798074Y1552147D02*
X1797281D01*
G01X1798074Y1554747D02*
Y1552147D01*
G01X1800749Y1567363D02*
X1803949D01*
G01X1797394Y1584632D02*
Y1578432D01*
G01X1798074Y1575769D02*
Y1573578D01*
G01X1797341Y1575769D02*
X1798074D01*
G01X1796504Y1588705D02*
Y1585505D01*
G01X1798513Y1595316D02*
Y1601316D01*
G01X1810513Y1595316D02*
X1798513D01*
G01X1810513Y1601316D02*
Y1595316D01*
G01X1797925Y1610723D02*
X1816579D01*
Y1617850D01*
G01X1798513Y1601316D02*
X1810513D01*
G01X1798513Y1608816D02*
X1810513D01*
G01X1798513Y1602816D02*
Y1608816D01*
G01X1810513Y1602816D02*
X1798513D01*
G01X1810513Y1608816D02*
Y1602816D01*
G01X1798383Y1634500D02*
Y1637600D01*
X1799303D01*
X1799610Y1637445D01*
X1799840Y1637083D01*
X1799917Y1636670D01*
X1799840Y1636257D01*
X1799648Y1635947D01*
X1799303Y1635792D01*
X1798383D01*
G01X1803093Y1637342D02*
X1802863Y1637497D01*
X1802595Y1637600D01*
X1802288D01*
X1801943Y1637445D01*
X1801675Y1637187D01*
X1801483Y1636877D01*
X1801330Y1636360D01*
X1801292Y1635895D01*
X1801368Y1635430D01*
X1801483Y1635120D01*
X1801713Y1634810D01*
X1801982Y1634603D01*
X1802250Y1634500D01*
X1802518D01*
X1802787Y1634603D01*
X1803017Y1634758D01*
X1803208Y1634965D01*
G01X1804622Y1635792D02*
X1804890Y1636153D01*
X1805120Y1636360D01*
X1805427Y1636463D01*
X1805695Y1636360D01*
X1805887Y1636153D01*
X1806040Y1635843D01*
X1806078Y1635482D01*
X1806040Y1635172D01*
X1805887Y1634862D01*
X1805657Y1634603D01*
X1805388Y1634500D01*
X1805082Y1634603D01*
X1804813Y1634913D01*
X1804660Y1635378D01*
X1804622Y1635895D01*
X1804698Y1636567D01*
X1804813Y1636928D01*
X1805005Y1637290D01*
X1805273Y1637548D01*
X1805542Y1637600D01*
X1805810Y1637497D01*
X1806002Y1637238D01*
G01X1808450Y1634500D02*
X1808718Y1634552D01*
X1809025Y1634707D01*
X1809217Y1634965D01*
X1809293Y1635327D01*
X1809217Y1635688D01*
X1808987Y1635998D01*
X1808642Y1636153D01*
X1808258D01*
X1808028Y1636257D01*
X1807837Y1636515D01*
X1807760Y1636877D01*
X1807875Y1637238D01*
X1808143Y1637497D01*
X1808450Y1637600D01*
X1808757Y1637497D01*
X1809025Y1637238D01*
X1809140Y1636877D01*
X1809063Y1636515D01*
X1808872Y1636257D01*
X1808642Y1636153D01*
X1808258D01*
X1807913Y1635998D01*
X1807683Y1635688D01*
X1807607Y1635327D01*
X1807683Y1634965D01*
X1807875Y1634707D01*
X1808182Y1634552D01*
X1808450Y1634500D01*
G01X1811550D02*
Y1637600D01*
X1811090Y1636980D01*
G01Y1634500D02*
X1812010D01*
G01X1814650Y1637600D02*
X1814343Y1637497D01*
X1814113Y1637238D01*
X1813960Y1636928D01*
X1813845Y1636515D01*
X1813807Y1636050D01*
X1813845Y1635585D01*
X1813960Y1635172D01*
X1814113Y1634862D01*
X1814343Y1634603D01*
X1814650Y1634500D01*
X1814957Y1634603D01*
X1815187Y1634862D01*
X1815340Y1635172D01*
X1815455Y1635585D01*
X1815493Y1636050D01*
X1815455Y1636515D01*
X1815340Y1636928D01*
X1815187Y1637238D01*
X1814957Y1637497D01*
X1814650Y1637600D01*
G01X1819680Y153434D02*
Y150234D01*
G01D02*
X1813480D01*
G01D02*
Y153434D01*
G01X1820480Y149434D02*
X1826680D01*
G01Y146234D02*
X1820480D01*
G01D02*
Y149434D01*
G01X1826680Y150234D02*
X1820480D01*
G01D02*
Y153434D01*
G01X1812052Y153606D02*
Y144944D01*
G01X1813480Y153434D02*
X1819680D01*
G01X1821305Y161472D02*
Y155272D01*
G01D02*
X1818105D01*
G01D02*
Y161472D01*
G01D02*
X1821305D01*
G01X1818105Y162272D02*
Y168472D01*
G01X1821305D02*
Y162272D01*
G01D02*
X1818105D01*
G01X1820480Y153434D02*
X1826680D01*
G01X1811552Y166165D02*
Y157503D01*
G01X1818105Y168472D02*
X1821305D01*
G01X1813311Y182144D02*
Y175944D01*
G01X1826285Y168581D02*
X1825978Y168633D01*
X1825710Y168839D01*
X1825480Y169149D01*
X1825327Y169511D01*
X1825250Y169924D01*
Y170338D01*
X1825327Y170751D01*
X1825480Y171113D01*
X1825710Y171423D01*
X1825978Y171629D01*
X1826285Y171681D01*
X1826592Y171629D01*
X1826860Y171423D01*
X1827090Y171113D01*
X1827243Y170751D01*
X1827320Y170338D01*
Y169924D01*
X1827243Y169511D01*
X1827090Y169149D01*
X1826860Y168839D01*
X1826592Y168633D01*
X1826285Y168581D01*
G01X1826592Y169408D02*
X1827052Y168581D01*
G01X1829385D02*
Y171681D01*
X1828925Y171061D01*
G01Y168581D02*
X1829845D01*
G01X1831757Y171164D02*
X1831987Y171474D01*
X1832255Y171629D01*
X1832562Y171681D01*
X1832945Y171578D01*
X1833213Y171319D01*
X1833290Y171009D01*
X1833252Y170699D01*
X1833098Y170441D01*
X1832332Y169924D01*
X1831987Y169563D01*
X1831757Y169046D01*
X1831680Y168581D01*
X1833290D01*
G01X1834742Y169201D02*
X1834972Y168839D01*
X1835278Y168633D01*
X1835623Y168581D01*
X1835930Y168633D01*
X1836237Y168891D01*
X1836428Y169201D01*
X1836467Y169511D01*
X1836390Y169873D01*
X1836122Y170131D01*
X1835853Y170234D01*
X1835508D01*
G01X1835853D02*
X1836083Y170389D01*
X1836275Y170648D01*
X1836352Y170958D01*
X1836275Y171268D01*
X1836083Y171526D01*
X1835738Y171681D01*
X1835393Y171629D01*
X1835048Y171423D01*
G01X1814474Y193799D02*
Y183599D01*
G01X1819974Y199799D02*
Y189599D01*
G01D02*
X1815374D01*
G01D02*
Y199799D01*
G01X1817908Y206629D02*
Y200429D01*
G01D02*
X1814708D01*
G01D02*
Y206629D01*
G01D02*
X1817908D01*
G01X1815374Y199799D02*
X1819974D01*
G01X1814127Y210598D02*
Y200398D01*
G01X1815368Y211046D02*
Y214146D01*
X1816288D01*
X1816595Y213991D01*
X1816825Y213629D01*
X1816902Y213216D01*
X1816825Y212803D01*
X1816633Y212493D01*
X1816288Y212338D01*
X1815368D01*
G01X1818392Y214146D02*
Y211924D01*
X1818545Y211459D01*
X1818852Y211149D01*
X1819235Y211046D01*
X1819618Y211149D01*
X1819925Y211459D01*
X1820078Y211924D01*
Y214146D01*
G01X1821683Y211408D02*
X1821952Y211149D01*
X1822258Y211046D01*
X1822565Y211149D01*
X1822833Y211459D01*
X1823025Y211924D01*
X1823102Y212389D01*
Y212958D01*
X1823025Y213423D01*
X1822833Y213836D01*
X1822603Y214043D01*
X1822335Y214146D01*
X1822028Y214043D01*
X1821798Y213836D01*
X1821645Y213526D01*
X1821568Y213113D01*
X1821645Y212751D01*
X1821837Y212389D01*
X1822067Y212183D01*
X1822335Y212131D01*
X1822642Y212234D01*
X1822872Y212493D01*
X1823102Y212958D01*
G01X1821190Y272537D02*
Y216237D01*
G01X1815632Y372929D02*
X1821832D01*
G01D02*
Y369729D01*
G01D02*
X1815632D01*
G01D02*
Y372929D01*
G01X1822632D02*
X1828832D01*
G01Y369729D02*
X1822632D01*
G01D02*
Y372929D01*
G01Y368959D02*
X1828832D01*
G01Y365759D02*
X1822632D01*
G01D02*
Y368959D01*
G01X1814321Y372943D02*
Y364281D01*
G01X1827756Y386451D02*
X1821556D01*
G01D02*
Y389651D01*
G01X1821569Y385552D02*
X1827769D01*
G01Y382352D02*
X1821569D01*
G01D02*
Y385552D01*
G01Y381152D02*
X1827769D01*
G01Y377952D02*
X1821569D01*
G01D02*
Y381152D01*
G01X1814881Y392183D02*
Y383521D01*
G01X1815469Y397152D02*
X1821669D01*
G01D02*
Y393952D01*
G01D02*
X1815469D01*
G01D02*
Y397152D01*
G01X1821556Y389651D02*
X1827756D01*
G01X1814699Y409532D02*
X1820899D01*
G01D02*
Y406332D01*
G01D02*
X1814699D01*
G01D02*
Y409532D01*
G01X1814199Y423032D02*
X1820399D01*
G01D02*
Y419832D01*
G01D02*
X1814199D01*
G01D02*
Y423032D01*
G01Y429032D02*
X1820399D01*
G01D02*
Y425832D01*
G01D02*
X1814199D01*
G01D02*
Y429032D01*
G01X1827399Y425832D02*
X1821199D01*
G01D02*
Y429032D01*
G01D02*
X1827399D01*
G01X1821192Y433278D02*
X1827392D01*
G01X1821192Y430078D02*
Y433278D01*
G01X1827392Y430078D02*
X1821192D01*
G01X1814192D02*
Y433278D01*
G01X1820392Y430078D02*
X1814192D01*
G01X1820392Y433278D02*
Y430078D01*
G01X1814192Y433278D02*
X1820392D01*
G01X1823179Y1485778D02*
X1830306D01*
G01X1827306Y1507432D02*
X1823179D01*
G01X1815779D02*
X1811652D01*
G01X1815011Y1583688D02*
Y1586788D01*
G01X1816621D02*
Y1583688D01*
G01Y1585238D02*
X1815011D01*
G01X1818188Y1586271D02*
X1818418Y1586581D01*
X1818686Y1586736D01*
X1818993Y1586788D01*
X1819376Y1586685D01*
X1819644Y1586426D01*
X1819721Y1586116D01*
X1819683Y1585806D01*
X1819529Y1585548D01*
X1818763Y1585031D01*
X1818418Y1584670D01*
X1818188Y1584153D01*
X1818111Y1583688D01*
X1819721D01*
G01X1815095Y1656759D02*
Y1659859D01*
G01X1816705D02*
Y1656759D01*
G01Y1658309D02*
X1815095D01*
G01X1818272Y1659342D02*
X1818502Y1659652D01*
X1818770Y1659807D01*
X1819077Y1659859D01*
X1819460Y1659756D01*
X1819728Y1659497D01*
X1819805Y1659187D01*
X1819767Y1658877D01*
X1819613Y1658619D01*
X1818847Y1658102D01*
X1818502Y1657741D01*
X1818272Y1657224D01*
X1818195Y1656759D01*
X1819805D01*
G01X1822023D02*
X1822100Y1657431D01*
X1822215Y1657999D01*
X1822368Y1658516D01*
X1822560Y1659084D01*
X1822867Y1659859D01*
X1821333D01*
G01X1826680Y149434D02*
Y146234D01*
G01Y153434D02*
Y150234D01*
G01X1836623Y157503D02*
X1833276D01*
G01D02*
X1831376Y159703D01*
G01D02*
X1829476Y157503D01*
G01D02*
X1826129D01*
G01D02*
Y166165D01*
G01X1836623D02*
Y157503D01*
G01X1826129Y166165D02*
X1836623D01*
G01X1828595Y216989D02*
Y220089D01*
G01X1830205D02*
Y216989D01*
G01Y218539D02*
X1828595D01*
G01X1831772Y218281D02*
X1832040Y218642D01*
X1832270Y218849D01*
X1832577Y218952D01*
X1832845Y218849D01*
X1833037Y218642D01*
X1833190Y218332D01*
X1833228Y217971D01*
X1833190Y217661D01*
X1833037Y217351D01*
X1832807Y217092D01*
X1832538Y216989D01*
X1832232Y217092D01*
X1831963Y217402D01*
X1831810Y217867D01*
X1831772Y218384D01*
X1831848Y219056D01*
X1831963Y219417D01*
X1832155Y219779D01*
X1832423Y220037D01*
X1832692Y220089D01*
X1832960Y219986D01*
X1833152Y219727D01*
G01X1835600Y220089D02*
X1835293Y219986D01*
X1835063Y219727D01*
X1834910Y219417D01*
X1834795Y219004D01*
X1834757Y218539D01*
X1834795Y218074D01*
X1834910Y217661D01*
X1835063Y217351D01*
X1835293Y217092D01*
X1835600Y216989D01*
X1835907Y217092D01*
X1836137Y217351D01*
X1836290Y217661D01*
X1836405Y218074D01*
X1836443Y218539D01*
X1836405Y219004D01*
X1836290Y219417D01*
X1836137Y219727D01*
X1835907Y219986D01*
X1835600Y220089D01*
G01X1838700D02*
X1838393Y219986D01*
X1838163Y219727D01*
X1838010Y219417D01*
X1837895Y219004D01*
X1837857Y218539D01*
X1837895Y218074D01*
X1838010Y217661D01*
X1838163Y217351D01*
X1838393Y217092D01*
X1838700Y216989D01*
X1839007Y217092D01*
X1839237Y217351D01*
X1839390Y217661D01*
X1839505Y218074D01*
X1839543Y218539D01*
X1839505Y219004D01*
X1839390Y219417D01*
X1839237Y219727D01*
X1839007Y219986D01*
X1838700Y220089D01*
G01X1841800Y216989D02*
Y220089D01*
X1841340Y219469D01*
G01Y216989D02*
X1842260D01*
G01X1828832Y372929D02*
Y369729D01*
G01Y368959D02*
Y365759D01*
G01X1827756Y389651D02*
Y386451D01*
G01X1827769Y385552D02*
Y382352D01*
G01Y381152D02*
Y377952D01*
G01X1827399Y429032D02*
Y425832D01*
G01X1827392Y433278D02*
Y430078D01*
G01X1830306Y1485778D02*
Y1504432D01*
G01D02*
X1827306Y1507432D01*
G01X1839702Y1591610D02*
Y1590916D01*
X1842518Y1588100D01*
X1842480D01*
X1842499Y1588081D01*
X1842518Y1588100D01*
Y1588794D01*
X1839702Y1591610D01*
X1839364D01*
X1839439Y1591685D01*
X1840922D01*
X1840809Y1591572D01*
X1840641D01*
X1842086Y1590127D01*
X1842480D01*
Y1589376D01*
X1842367Y1589489D01*
G01X1836468Y1591571D02*
X1837201D01*
X1842531Y1586241D01*
Y1585696D01*
X1842437Y1585602D01*
X1841656Y1586383D01*
Y1586822D01*
X1841093Y1587385D01*
X1840906D01*
X1836906Y1591385D01*
Y1591535D01*
X1838359D01*
X1842612Y1587282D01*
Y1586616D01*
X1841726Y1587502D01*
Y1587530D01*
X1837721Y1591535D01*
X1837237D01*
G01X1835033Y1591797D02*
X1835924D01*
X1842569Y1585152D01*
Y1584927D01*
X1842344D01*
X1835569Y1591702D01*
X1831733D01*
X1831630Y1591599D01*
X1831808D01*
X1842496Y1580911D01*
Y1581455D01*
X1832249Y1591702D01*
X1832757D01*
X1842418Y1582041D01*
Y1581943D01*
G01X1834479Y1591797D02*
Y1591776D01*
X1842472Y1583783D01*
X1842493D01*
G01X1832757Y1591702D02*
X1842418Y1582041D01*
Y1582656D01*
X1833296Y1591778D01*
Y1591834D01*
X1833822D01*
X1842475Y1583181D01*
Y1583106D01*
X1842493Y1583124D01*
Y1583783D01*
X1834479Y1591797D01*
X1835033D01*
X1842504Y1584326D01*
X1842569D01*
Y1584927D01*
X1835850Y1591646D01*
X1835774D01*
X1835849Y1591571D01*
X1836468D01*
X1842437Y1585602D01*
Y1585284D01*
X1842531Y1585378D01*
Y1586241D01*
X1837237Y1591535D01*
X1836906D01*
X1836924Y1591553D01*
X1837825D01*
X1842630Y1586748D01*
Y1586598D01*
X1842612Y1586616D01*
Y1587424D01*
X1838407Y1591629D01*
X1837994D01*
X1838069Y1591704D01*
X1838876D01*
X1842499Y1588081D01*
Y1587893D01*
X1842518Y1587912D01*
Y1588794D01*
X1839702Y1591610D01*
X1839364D01*
X1839476Y1591722D01*
X1840134D01*
X1842480Y1589376D01*
Y1590127D01*
X1840922Y1591685D01*
X1840528D01*
X1840641Y1591572D01*
X1841485D01*
X1842461Y1590596D01*
Y1590577D01*
X1842386Y1590652D01*
Y1591272D01*
X1842048Y1591610D01*
X1841880D01*
X1841936Y1591666D01*
X1842367D01*
X1842555Y1591478D01*
G01X1830945Y1591929D02*
X1842756Y1580118D01*
G01Y1591929D02*
X1830945D01*
G01X1849391Y164234D02*
X1843191D01*
G01D02*
Y167434D01*
G01X1849391D02*
Y164234D01*
G01X1843191Y163434D02*
X1849391D01*
G01D02*
Y160234D01*
G01D02*
X1843191D01*
G01D02*
Y163434D01*
G01Y167434D02*
X1849391D01*
G01X1849361Y171887D02*
Y168687D01*
G01X1843161Y171887D02*
X1849361D01*
G01X1843161Y168687D02*
Y171887D01*
G01X1849361Y168687D02*
X1843161D01*
G01X1864986Y1374442D02*
X1851873Y1409018D01*
G01D02*
X1878099D01*
G01X1842756Y1580118D02*
Y1591929D01*
G01X1851593Y1703411D02*
X1864706Y1737987D01*
G01X1877819Y1703411D02*
X1851593D01*
G01X1851528Y1728538D02*
Y1731638D01*
X1852294D01*
X1852601Y1731483D01*
X1852831Y1731276D01*
X1853023Y1730966D01*
X1853176Y1730605D01*
X1853214Y1730088D01*
X1853176Y1729571D01*
X1853023Y1729210D01*
X1852831Y1728900D01*
X1852601Y1728693D01*
X1852294Y1728538D01*
X1851528D01*
G01X1855778Y1730191D02*
X1855931Y1730346D01*
X1856046Y1730605D01*
X1856123Y1730966D01*
X1856046Y1731276D01*
X1855893Y1731483D01*
X1855624Y1731638D01*
X1854589D01*
Y1728538D01*
X1855854D01*
X1856123Y1728745D01*
X1856276Y1729055D01*
X1856353Y1729416D01*
X1856276Y1729778D01*
X1856046Y1730088D01*
X1855778Y1730191D01*
X1854589D01*
G01X1858494Y1728538D02*
X1858571Y1729210D01*
X1858686Y1729778D01*
X1858839Y1730295D01*
X1859031Y1730863D01*
X1859338Y1731638D01*
X1857804D01*
G01X1869608Y1376418D02*
Y1379518D01*
X1870374D01*
X1870681Y1379363D01*
X1870911Y1379156D01*
X1871103Y1378846D01*
X1871256Y1378485D01*
X1871294Y1377968D01*
X1871256Y1377451D01*
X1871103Y1377090D01*
X1870911Y1376780D01*
X1870681Y1376573D01*
X1870374Y1376418D01*
X1869608D01*
G01X1873858Y1378071D02*
X1874011Y1378226D01*
X1874126Y1378485D01*
X1874203Y1378846D01*
X1874126Y1379156D01*
X1873973Y1379363D01*
X1873704Y1379518D01*
X1872669D01*
Y1376418D01*
X1873934D01*
X1874203Y1376625D01*
X1874356Y1376935D01*
X1874433Y1377296D01*
X1874356Y1377658D01*
X1874126Y1377968D01*
X1873858Y1378071D01*
X1872669D01*
G01X1876651Y1376418D02*
X1876919Y1376470D01*
X1877226Y1376625D01*
X1877418Y1376883D01*
X1877494Y1377245D01*
X1877418Y1377606D01*
X1877188Y1377916D01*
X1876843Y1378071D01*
X1876459D01*
X1876229Y1378175D01*
X1876038Y1378433D01*
X1875961Y1378795D01*
X1876076Y1379156D01*
X1876344Y1379415D01*
X1876651Y1379518D01*
X1876958Y1379415D01*
X1877226Y1379156D01*
X1877341Y1378795D01*
X1877264Y1378433D01*
X1877073Y1378175D01*
X1876843Y1378071D01*
X1876459D01*
X1876114Y1377916D01*
X1875884Y1377606D01*
X1875808Y1377245D01*
X1875884Y1376883D01*
X1876076Y1376625D01*
X1876383Y1376470D01*
X1876651Y1376418D01*
G01X1875681Y1402641D02*
X1864986Y1374442D01*
G01X1864706Y1737987D02*
X1877819Y1703411D01*
G01X1886862Y78315D02*
X1873749Y112891D01*
G01D02*
X1899975D01*
G01X1900453Y405229D02*
X1874227D01*
G01D02*
X1887340Y439805D01*
G01X1887711Y447888D02*
X1874598Y482464D01*
G01D02*
X1900824D01*
G01X1900353Y777874D02*
X1874127D01*
G01D02*
X1887240Y812450D01*
G01X1888273Y821840D02*
X1875160Y856416D01*
G01D02*
X1901386D01*
G01X1900692Y1152748D02*
X1874466D01*
G01D02*
X1874919Y1153942D01*
G01X1877725Y1161341D02*
X1887579Y1187324D01*
G01X1892193Y82198D02*
Y85298D01*
X1892959D01*
X1893266Y85143D01*
X1893496Y84936D01*
X1893688Y84626D01*
X1893841Y84265D01*
X1893879Y83748D01*
X1893841Y83231D01*
X1893688Y82870D01*
X1893496Y82560D01*
X1893266Y82353D01*
X1892959Y82198D01*
X1892193D01*
G01X1896443Y83851D02*
X1896596Y84006D01*
X1896711Y84265D01*
X1896788Y84626D01*
X1896711Y84936D01*
X1896558Y85143D01*
X1896289Y85298D01*
X1895254D01*
Y82198D01*
X1896519D01*
X1896788Y82405D01*
X1896941Y82715D01*
X1897018Y83076D01*
X1896941Y83438D01*
X1896711Y83748D01*
X1896443Y83851D01*
X1895254D01*
G01X1898584Y82560D02*
X1898853Y82301D01*
X1899159Y82198D01*
X1899466Y82301D01*
X1899734Y82611D01*
X1899926Y83076D01*
X1900003Y83541D01*
Y84110D01*
X1899926Y84575D01*
X1899734Y84988D01*
X1899504Y85195D01*
X1899236Y85298D01*
X1898929Y85195D01*
X1898699Y84988D01*
X1898546Y84678D01*
X1898469Y84265D01*
X1898546Y83903D01*
X1898738Y83541D01*
X1898968Y83335D01*
X1899236Y83283D01*
X1899543Y83386D01*
X1899773Y83645D01*
X1900003Y84110D01*
G01X1899975Y112891D02*
X1886862Y78315D01*
G01X1887340Y439805D02*
X1900453Y405229D01*
G01X1894403Y433718D02*
Y436818D01*
X1895169D01*
X1895476Y436663D01*
X1895706Y436456D01*
X1895898Y436146D01*
X1896051Y435785D01*
X1896089Y435268D01*
X1896051Y434751D01*
X1895898Y434390D01*
X1895706Y434080D01*
X1895476Y433873D01*
X1895169Y433718D01*
X1894403D01*
G01X1898653Y435371D02*
X1898806Y435526D01*
X1898921Y435785D01*
X1898998Y436146D01*
X1898921Y436456D01*
X1898768Y436663D01*
X1898499Y436818D01*
X1897464D01*
Y433718D01*
X1898729D01*
X1898998Y433925D01*
X1899151Y434235D01*
X1899228Y434596D01*
X1899151Y434958D01*
X1898921Y435268D01*
X1898653Y435371D01*
X1897464D01*
G01X1901446Y433718D02*
Y436818D01*
X1900986Y436198D01*
G01Y433718D02*
X1901906D01*
G01X1904546Y436818D02*
X1904239Y436715D01*
X1904009Y436456D01*
X1903856Y436146D01*
X1903741Y435733D01*
X1903703Y435268D01*
X1903741Y434803D01*
X1903856Y434390D01*
X1904009Y434080D01*
X1904239Y433821D01*
X1904546Y433718D01*
X1904853Y433821D01*
X1905083Y434080D01*
X1905236Y434390D01*
X1905351Y434803D01*
X1905389Y435268D01*
X1905351Y435733D01*
X1905236Y436146D01*
X1905083Y436456D01*
X1904853Y436715D01*
X1904546Y436818D01*
G01X1894659Y449578D02*
Y452678D01*
X1895425D01*
X1895732Y452523D01*
X1895962Y452316D01*
X1896154Y452006D01*
X1896307Y451645D01*
X1896345Y451128D01*
X1896307Y450611D01*
X1896154Y450250D01*
X1895962Y449940D01*
X1895732Y449733D01*
X1895425Y449578D01*
X1894659D01*
G01X1898909Y451231D02*
X1899062Y451386D01*
X1899177Y451645D01*
X1899254Y452006D01*
X1899177Y452316D01*
X1899024Y452523D01*
X1898755Y452678D01*
X1897720D01*
Y449578D01*
X1898985D01*
X1899254Y449785D01*
X1899407Y450095D01*
X1899484Y450456D01*
X1899407Y450818D01*
X1899177Y451128D01*
X1898909Y451231D01*
X1897720D01*
G01X1900974Y452161D02*
X1901204Y452471D01*
X1901472Y452626D01*
X1901779Y452678D01*
X1902162Y452575D01*
X1902430Y452316D01*
X1902507Y452006D01*
X1902469Y451696D01*
X1902315Y451438D01*
X1901549Y450921D01*
X1901204Y450560D01*
X1900974Y450043D01*
X1900897Y449578D01*
X1902507D01*
G01X1900824Y482464D02*
X1887711Y447888D01*
G01X1887240Y812450D02*
X1900353Y777874D01*
G01X1893559Y808128D02*
Y811228D01*
X1894325D01*
X1894632Y811073D01*
X1894862Y810866D01*
X1895054Y810556D01*
X1895207Y810195D01*
X1895245Y809678D01*
X1895207Y809161D01*
X1895054Y808800D01*
X1894862Y808490D01*
X1894632Y808283D01*
X1894325Y808128D01*
X1893559D01*
G01X1897809Y809781D02*
X1897962Y809936D01*
X1898077Y810195D01*
X1898154Y810556D01*
X1898077Y810866D01*
X1897924Y811073D01*
X1897655Y811228D01*
X1896620D01*
Y808128D01*
X1897885D01*
X1898154Y808335D01*
X1898307Y808645D01*
X1898384Y809006D01*
X1898307Y809368D01*
X1898077Y809678D01*
X1897809Y809781D01*
X1896620D01*
G01X1899759Y808748D02*
X1899989Y808386D01*
X1900295Y808180D01*
X1900640Y808128D01*
X1900947Y808180D01*
X1901254Y808438D01*
X1901445Y808748D01*
X1901484Y809058D01*
X1901407Y809420D01*
X1901139Y809678D01*
X1900870Y809781D01*
X1900525D01*
G01X1900870D02*
X1901100Y809936D01*
X1901292Y810195D01*
X1901369Y810505D01*
X1901292Y810815D01*
X1901100Y811073D01*
X1900755Y811228D01*
X1900410Y811176D01*
X1900065Y810970D01*
G01X1894131Y824546D02*
Y827646D01*
X1894897D01*
X1895204Y827491D01*
X1895434Y827284D01*
X1895626Y826974D01*
X1895779Y826613D01*
X1895817Y826096D01*
X1895779Y825579D01*
X1895626Y825218D01*
X1895434Y824908D01*
X1895204Y824701D01*
X1894897Y824546D01*
X1894131D01*
G01X1898381Y826199D02*
X1898534Y826354D01*
X1898649Y826613D01*
X1898726Y826974D01*
X1898649Y827284D01*
X1898496Y827491D01*
X1898227Y827646D01*
X1897192D01*
Y824546D01*
X1898457D01*
X1898726Y824753D01*
X1898879Y825063D01*
X1898956Y825424D01*
X1898879Y825786D01*
X1898649Y826096D01*
X1898381Y826199D01*
X1897192D01*
G01X1901174Y824546D02*
Y827646D01*
X1900714Y827026D01*
G01Y824546D02*
X1901634D01*
G01X1901386Y856416D02*
X1888273Y821840D01*
G01X1899931Y1161696D02*
Y1164796D01*
X1900697D01*
X1901004Y1164641D01*
X1901234Y1164434D01*
X1901426Y1164124D01*
X1901579Y1163763D01*
X1901617Y1163246D01*
X1901579Y1162729D01*
X1901426Y1162368D01*
X1901234Y1162058D01*
X1901004Y1161851D01*
X1900697Y1161696D01*
X1899931D01*
G01X1904181Y1163349D02*
X1904334Y1163504D01*
X1904449Y1163763D01*
X1904526Y1164124D01*
X1904449Y1164434D01*
X1904296Y1164641D01*
X1904027Y1164796D01*
X1902992D01*
Y1161696D01*
X1904257D01*
X1904526Y1161903D01*
X1904679Y1162213D01*
X1904756Y1162574D01*
X1904679Y1162936D01*
X1904449Y1163246D01*
X1904181Y1163349D01*
X1902992D01*
G01X1907434Y1161696D02*
Y1164796D01*
X1906016Y1162574D01*
X1907932D01*
G01X1887579Y1187324D02*
X1900692Y1152748D01*
G01X1893799Y1198198D02*
X1894349D01*
G01X1893799Y1208198D02*
Y1198198D01*
G01X1896299Y1208198D02*
X1893799D01*
G01X1889816Y1213868D02*
X1891426Y1216968D01*
G01X1889816D02*
X1891426Y1213868D01*
G01X1893069Y1214230D02*
X1893338Y1213971D01*
X1893644Y1213868D01*
X1893951Y1213971D01*
X1894219Y1214281D01*
X1894411Y1214746D01*
X1894488Y1215211D01*
Y1215780D01*
X1894411Y1216245D01*
X1894219Y1216658D01*
X1893989Y1216865D01*
X1893721Y1216968D01*
X1893414Y1216865D01*
X1893184Y1216658D01*
X1893031Y1216348D01*
X1892954Y1215935D01*
X1893031Y1215573D01*
X1893223Y1215211D01*
X1893453Y1215005D01*
X1893721Y1214953D01*
X1894028Y1215056D01*
X1894258Y1215315D01*
X1894488Y1215780D01*
G01X1896821Y1216968D02*
X1896514Y1216865D01*
X1896284Y1216606D01*
X1896131Y1216296D01*
X1896016Y1215883D01*
X1895978Y1215418D01*
X1896016Y1214953D01*
X1896131Y1214540D01*
X1896284Y1214230D01*
X1896514Y1213971D01*
X1896821Y1213868D01*
X1897128Y1213971D01*
X1897358Y1214230D01*
X1897511Y1214540D01*
X1897626Y1214953D01*
X1897664Y1215418D01*
X1897626Y1215883D01*
X1897511Y1216296D01*
X1897358Y1216606D01*
X1897128Y1216865D01*
X1896821Y1216968D01*
G01X1899921Y1213868D02*
Y1216968D01*
X1899461Y1216348D01*
G01Y1213868D02*
X1900381D01*
G01X1903021Y1216968D02*
X1902714Y1216865D01*
X1902484Y1216606D01*
X1902331Y1216296D01*
X1902216Y1215883D01*
X1902178Y1215418D01*
X1902216Y1214953D01*
X1902331Y1214540D01*
X1902484Y1214230D01*
X1902714Y1213971D01*
X1903021Y1213868D01*
X1903328Y1213971D01*
X1903558Y1214230D01*
X1903711Y1214540D01*
X1903826Y1214953D01*
X1903864Y1215418D01*
X1903826Y1215883D01*
X1903711Y1216296D01*
X1903558Y1216606D01*
X1903328Y1216865D01*
X1903021Y1216968D01*
G01X1893799Y1810398D02*
Y1800398D01*
G01D02*
X1896299D01*
G01X1894349Y1810398D02*
X1893799D01*
G01X1912477Y-24036D02*
X1914087Y-20936D01*
G01X1912477D02*
X1914087Y-24036D01*
G01X1916382D02*
X1916650Y-23984D01*
X1916957Y-23829D01*
X1917149Y-23571D01*
X1917225Y-23209D01*
X1917149Y-22848D01*
X1916919Y-22538D01*
X1916574Y-22383D01*
X1916190D01*
X1915960Y-22279D01*
X1915769Y-22021D01*
X1915692Y-21659D01*
X1915807Y-21298D01*
X1916075Y-21039D01*
X1916382Y-20936D01*
X1916689Y-21039D01*
X1916957Y-21298D01*
X1917072Y-21659D01*
X1916995Y-22021D01*
X1916804Y-22279D01*
X1916574Y-22383D01*
X1916190D01*
X1915845Y-22538D01*
X1915615Y-22848D01*
X1915539Y-23209D01*
X1915615Y-23571D01*
X1915807Y-23829D01*
X1916114Y-23984D01*
X1916382Y-24036D01*
G01X1919482Y-20936D02*
X1919175Y-21039D01*
X1918945Y-21298D01*
X1918792Y-21608D01*
X1918677Y-22021D01*
X1918639Y-22486D01*
X1918677Y-22951D01*
X1918792Y-23364D01*
X1918945Y-23674D01*
X1919175Y-23933D01*
X1919482Y-24036D01*
X1919789Y-23933D01*
X1920019Y-23674D01*
X1920172Y-23364D01*
X1920287Y-22951D01*
X1920325Y-22486D01*
X1920287Y-22021D01*
X1920172Y-21608D01*
X1920019Y-21298D01*
X1919789Y-21039D01*
X1919482Y-20936D01*
G01X1922582D02*
X1922275Y-21039D01*
X1922045Y-21298D01*
X1921892Y-21608D01*
X1921777Y-22021D01*
X1921739Y-22486D01*
X1921777Y-22951D01*
X1921892Y-23364D01*
X1922045Y-23674D01*
X1922275Y-23933D01*
X1922582Y-24036D01*
X1922889Y-23933D01*
X1923119Y-23674D01*
X1923272Y-23364D01*
X1923387Y-22951D01*
X1923425Y-22486D01*
X1923387Y-22021D01*
X1923272Y-21608D01*
X1923119Y-21298D01*
X1922889Y-21039D01*
X1922582Y-20936D01*
G01X1926142Y-24036D02*
Y-20936D01*
X1924724Y-23158D01*
X1926640D01*
G01X1903249Y1198198D02*
X1904349D01*
G01X1913799D02*
Y1208198D01*
G01X1913249Y1198198D02*
X1913799D01*
G01X1906299Y1208198D02*
X1901299D01*
G01X1913799D02*
X1911299D01*
G01X1903174Y1790770D02*
X1904784Y1793870D01*
G01X1903174D02*
X1904784Y1790770D01*
G01X1906427Y1791132D02*
X1906696Y1790873D01*
X1907002Y1790770D01*
X1907309Y1790873D01*
X1907577Y1791183D01*
X1907769Y1791648D01*
X1907846Y1792113D01*
Y1792682D01*
X1907769Y1793147D01*
X1907577Y1793560D01*
X1907347Y1793767D01*
X1907079Y1793870D01*
X1906772Y1793767D01*
X1906542Y1793560D01*
X1906389Y1793250D01*
X1906312Y1792837D01*
X1906389Y1792475D01*
X1906581Y1792113D01*
X1906811Y1791907D01*
X1907079Y1791855D01*
X1907386Y1791958D01*
X1907616Y1792217D01*
X1907846Y1792682D01*
G01X1910179Y1793870D02*
X1909872Y1793767D01*
X1909642Y1793508D01*
X1909489Y1793198D01*
X1909374Y1792785D01*
X1909336Y1792320D01*
X1909374Y1791855D01*
X1909489Y1791442D01*
X1909642Y1791132D01*
X1909872Y1790873D01*
X1910179Y1790770D01*
X1910486Y1790873D01*
X1910716Y1791132D01*
X1910869Y1791442D01*
X1910984Y1791855D01*
X1911022Y1792320D01*
X1910984Y1792785D01*
X1910869Y1793198D01*
X1910716Y1793508D01*
X1910486Y1793767D01*
X1910179Y1793870D01*
G01X1913279D02*
X1912972Y1793767D01*
X1912742Y1793508D01*
X1912589Y1793198D01*
X1912474Y1792785D01*
X1912436Y1792320D01*
X1912474Y1791855D01*
X1912589Y1791442D01*
X1912742Y1791132D01*
X1912972Y1790873D01*
X1913279Y1790770D01*
X1913586Y1790873D01*
X1913816Y1791132D01*
X1913969Y1791442D01*
X1914084Y1791855D01*
X1914122Y1792320D01*
X1914084Y1792785D01*
X1913969Y1793198D01*
X1913816Y1793508D01*
X1913586Y1793767D01*
X1913279Y1793870D01*
G01X1916839Y1790770D02*
Y1793870D01*
X1915421Y1791648D01*
X1917337D01*
G01X1913799Y1800398D02*
Y1810398D01*
G01X1911299Y1800398D02*
X1913799D01*
G01X1901299D02*
X1906299D01*
G01X1913799Y1810398D02*
X1913249D01*
G01X1904349D02*
X1903249D01*
G01X1928895Y-29963D02*
X1923895D01*
G01X1925845Y-39963D02*
X1926945D01*
G01X1918895Y-29963D02*
X1916395D01*
G01D02*
Y-39963D01*
G01D02*
X1916945D01*
G01X1928013Y553174D02*
X1929623Y556274D01*
G01X1928013D02*
X1929623Y553174D01*
G01X1931918D02*
X1932186Y553226D01*
X1932493Y553381D01*
X1932685Y553639D01*
X1932761Y554001D01*
X1932685Y554362D01*
X1932455Y554672D01*
X1932110Y554827D01*
X1931726D01*
X1931496Y554931D01*
X1931305Y555189D01*
X1931228Y555551D01*
X1931343Y555912D01*
X1931611Y556171D01*
X1931918Y556274D01*
X1932225Y556171D01*
X1932493Y555912D01*
X1932608Y555551D01*
X1932531Y555189D01*
X1932340Y554931D01*
X1932110Y554827D01*
X1931726D01*
X1931381Y554672D01*
X1931151Y554362D01*
X1931075Y554001D01*
X1931151Y553639D01*
X1931343Y553381D01*
X1931650Y553226D01*
X1931918Y553174D01*
G01X1935018Y556274D02*
X1934711Y556171D01*
X1934481Y555912D01*
X1934328Y555602D01*
X1934213Y555189D01*
X1934175Y554724D01*
X1934213Y554259D01*
X1934328Y553846D01*
X1934481Y553536D01*
X1934711Y553277D01*
X1935018Y553174D01*
X1935325Y553277D01*
X1935555Y553536D01*
X1935708Y553846D01*
X1935823Y554259D01*
X1935861Y554724D01*
X1935823Y555189D01*
X1935708Y555602D01*
X1935555Y555912D01*
X1935325Y556171D01*
X1935018Y556274D01*
G01X1938118Y553174D02*
Y556274D01*
X1937658Y555654D01*
G01Y553174D02*
X1938578D01*
G01X1941218Y556274D02*
X1940911Y556171D01*
X1940681Y555912D01*
X1940528Y555602D01*
X1940413Y555189D01*
X1940375Y554724D01*
X1940413Y554259D01*
X1940528Y553846D01*
X1940681Y553536D01*
X1940911Y553277D01*
X1941218Y553174D01*
X1941525Y553277D01*
X1941755Y553536D01*
X1941908Y553846D01*
X1942023Y554259D01*
X1942061Y554724D01*
X1942023Y555189D01*
X1941908Y555602D01*
X1941755Y555912D01*
X1941525Y556171D01*
X1941218Y556274D01*
G01X1916395Y562237D02*
X1918895D01*
G01X1923895D02*
X1928895D01*
G01X1916395Y572237D02*
Y562237D01*
G01X1916945Y572237D02*
X1916395D01*
G01X1926945D02*
X1925845D01*
G01X1936395Y-29963D02*
X1933895D01*
G01X1935845Y-39963D02*
X1936395D01*
G01D02*
Y-29963D01*
G01X1933895Y562237D02*
X1936395D01*
G01D02*
Y572237D01*
G01X1949895Y582417D02*
X1944895D01*
G01X1939895D02*
X1937395D01*
G01D02*
Y572417D01*
G01D02*
X1937945D01*
G01X1936395Y572237D02*
X1935845D01*
G01X1940059Y588146D02*
X1941669Y591246D01*
G01X1940059D02*
X1941669Y588146D01*
G01X1944424D02*
Y591246D01*
X1943006Y589024D01*
X1944922D01*
G01X1944895Y1174617D02*
X1949895D01*
G01X1937395D02*
X1939895D01*
G01X1937395Y1184617D02*
Y1174617D01*
G01X1937945Y1184617D02*
X1937395D01*
G01X1935886Y1198170D02*
X1936436D01*
G01X1935886Y1208170D02*
Y1198170D01*
G01X1938386Y1208170D02*
X1935886D01*
G01X1948386D02*
X1943386D01*
G01X1932344Y1213955D02*
X1933954Y1217055D01*
G01X1932344D02*
X1933954Y1213955D01*
G01X1935597Y1214317D02*
X1935866Y1214058D01*
X1936172Y1213955D01*
X1936479Y1214058D01*
X1936747Y1214368D01*
X1936939Y1214833D01*
X1937016Y1215298D01*
Y1215867D01*
X1936939Y1216332D01*
X1936747Y1216745D01*
X1936517Y1216952D01*
X1936249Y1217055D01*
X1935942Y1216952D01*
X1935712Y1216745D01*
X1935559Y1216435D01*
X1935482Y1216022D01*
X1935559Y1215660D01*
X1935751Y1215298D01*
X1935981Y1215092D01*
X1936249Y1215040D01*
X1936556Y1215143D01*
X1936786Y1215402D01*
X1937016Y1215867D01*
G01X1939349Y1217055D02*
X1939042Y1216952D01*
X1938812Y1216693D01*
X1938659Y1216383D01*
X1938544Y1215970D01*
X1938506Y1215505D01*
X1938544Y1215040D01*
X1938659Y1214627D01*
X1938812Y1214317D01*
X1939042Y1214058D01*
X1939349Y1213955D01*
X1939656Y1214058D01*
X1939886Y1214317D01*
X1940039Y1214627D01*
X1940154Y1215040D01*
X1940192Y1215505D01*
X1940154Y1215970D01*
X1940039Y1216383D01*
X1939886Y1216693D01*
X1939656Y1216952D01*
X1939349Y1217055D01*
G01X1942449D02*
X1942142Y1216952D01*
X1941912Y1216693D01*
X1941759Y1216383D01*
X1941644Y1215970D01*
X1941606Y1215505D01*
X1941644Y1215040D01*
X1941759Y1214627D01*
X1941912Y1214317D01*
X1942142Y1214058D01*
X1942449Y1213955D01*
X1942756Y1214058D01*
X1942986Y1214317D01*
X1943139Y1214627D01*
X1943254Y1215040D01*
X1943292Y1215505D01*
X1943254Y1215970D01*
X1943139Y1216383D01*
X1942986Y1216693D01*
X1942756Y1216952D01*
X1942449Y1217055D01*
G01X1944706Y1214575D02*
X1944936Y1214213D01*
X1945242Y1214007D01*
X1945587Y1213955D01*
X1945894Y1214007D01*
X1946201Y1214265D01*
X1946392Y1214575D01*
X1946431Y1214885D01*
X1946354Y1215247D01*
X1946086Y1215505D01*
X1945817Y1215608D01*
X1945472D01*
G01X1945817D02*
X1946047Y1215763D01*
X1946239Y1216022D01*
X1946316Y1216332D01*
X1946239Y1216642D01*
X1946047Y1216900D01*
X1945702Y1217055D01*
X1945357Y1217003D01*
X1945012Y1216797D01*
G01X1935886Y1810370D02*
Y1800370D01*
G01X1943386D02*
X1948386D01*
G01X1935886D02*
X1938386D01*
G01X1936436Y1810370D02*
X1935886D01*
G01X1960862Y-29821D02*
X1958362D01*
G01D02*
Y-39821D01*
G01D02*
X1958912D01*
G01X1954835Y-24069D02*
X1956445Y-20969D01*
G01X1954835D02*
X1956445Y-24069D01*
G01X1958740D02*
X1959008Y-24017D01*
X1959315Y-23862D01*
X1959507Y-23604D01*
X1959583Y-23242D01*
X1959507Y-22881D01*
X1959277Y-22571D01*
X1958932Y-22416D01*
X1958548D01*
X1958318Y-22312D01*
X1958127Y-22054D01*
X1958050Y-21692D01*
X1958165Y-21331D01*
X1958433Y-21072D01*
X1958740Y-20969D01*
X1959047Y-21072D01*
X1959315Y-21331D01*
X1959430Y-21692D01*
X1959353Y-22054D01*
X1959162Y-22312D01*
X1958932Y-22416D01*
X1958548D01*
X1958203Y-22571D01*
X1957973Y-22881D01*
X1957897Y-23242D01*
X1957973Y-23604D01*
X1958165Y-23862D01*
X1958472Y-24017D01*
X1958740Y-24069D01*
G01X1961840Y-20969D02*
X1961533Y-21072D01*
X1961303Y-21331D01*
X1961150Y-21641D01*
X1961035Y-22054D01*
X1960997Y-22519D01*
X1961035Y-22984D01*
X1961150Y-23397D01*
X1961303Y-23707D01*
X1961533Y-23966D01*
X1961840Y-24069D01*
X1962147Y-23966D01*
X1962377Y-23707D01*
X1962530Y-23397D01*
X1962645Y-22984D01*
X1962683Y-22519D01*
X1962645Y-22054D01*
X1962530Y-21641D01*
X1962377Y-21331D01*
X1962147Y-21072D01*
X1961840Y-20969D01*
G01X1964940D02*
X1964633Y-21072D01*
X1964403Y-21331D01*
X1964250Y-21641D01*
X1964135Y-22054D01*
X1964097Y-22519D01*
X1964135Y-22984D01*
X1964250Y-23397D01*
X1964403Y-23707D01*
X1964633Y-23966D01*
X1964940Y-24069D01*
X1965247Y-23966D01*
X1965477Y-23707D01*
X1965630Y-23397D01*
X1965745Y-22984D01*
X1965783Y-22519D01*
X1965745Y-22054D01*
X1965630Y-21641D01*
X1965477Y-21331D01*
X1965247Y-21072D01*
X1964940Y-20969D01*
G01X1967388Y-23707D02*
X1967657Y-23966D01*
X1967963Y-24069D01*
X1968270Y-23966D01*
X1968538Y-23656D01*
X1968730Y-23191D01*
X1968807Y-22726D01*
Y-22157D01*
X1968730Y-21692D01*
X1968538Y-21279D01*
X1968308Y-21072D01*
X1968040Y-20969D01*
X1967733Y-21072D01*
X1967503Y-21279D01*
X1967350Y-21589D01*
X1967273Y-22002D01*
X1967350Y-22364D01*
X1967542Y-22726D01*
X1967772Y-22932D01*
X1968040Y-22984D01*
X1968347Y-22881D01*
X1968577Y-22622D01*
X1968807Y-22157D01*
G01X1958362Y562379D02*
X1960862D01*
G01X1958362Y572379D02*
Y562379D01*
G01X1957395Y582417D02*
X1954895D01*
G01X1957395Y572417D02*
Y582417D01*
G01X1946845Y572417D02*
X1947945D01*
G01X1956845D02*
X1957395D01*
G01X1958912Y572379D02*
X1958362D01*
G01X1947199Y1165406D02*
X1948809Y1168506D01*
G01X1947199D02*
X1948809Y1165406D01*
G01X1951104D02*
Y1168506D01*
X1950644Y1167886D01*
G01Y1165406D02*
X1951564D01*
G01X1954204Y1168506D02*
X1953897Y1168403D01*
X1953667Y1168144D01*
X1953514Y1167834D01*
X1953399Y1167421D01*
X1953361Y1166956D01*
X1953399Y1166491D01*
X1953514Y1166078D01*
X1953667Y1165768D01*
X1953897Y1165509D01*
X1954204Y1165406D01*
X1954511Y1165509D01*
X1954741Y1165768D01*
X1954894Y1166078D01*
X1955009Y1166491D01*
X1955047Y1166956D01*
X1955009Y1167421D01*
X1954894Y1167834D01*
X1954741Y1168144D01*
X1954511Y1168403D01*
X1954204Y1168506D01*
G01X1954895Y1174617D02*
X1957395D01*
G01D02*
Y1184617D01*
G01D02*
X1956845D01*
G01X1947945D02*
X1946845D01*
G01X1945336Y1198170D02*
X1946436D01*
G01X1955886D02*
Y1208170D01*
G01X1955336Y1198170D02*
X1955886D01*
G01Y1208170D02*
X1953386D01*
G01X1945646Y1791183D02*
X1947256Y1794283D01*
G01X1945646D02*
X1947256Y1791183D01*
G01X1948899Y1791545D02*
X1949168Y1791286D01*
X1949474Y1791183D01*
X1949781Y1791286D01*
X1950049Y1791596D01*
X1950241Y1792061D01*
X1950318Y1792526D01*
Y1793095D01*
X1950241Y1793560D01*
X1950049Y1793973D01*
X1949819Y1794180D01*
X1949551Y1794283D01*
X1949244Y1794180D01*
X1949014Y1793973D01*
X1948861Y1793663D01*
X1948784Y1793250D01*
X1948861Y1792888D01*
X1949053Y1792526D01*
X1949283Y1792320D01*
X1949551Y1792268D01*
X1949858Y1792371D01*
X1950088Y1792630D01*
X1950318Y1793095D01*
G01X1952651Y1794283D02*
X1952344Y1794180D01*
X1952114Y1793921D01*
X1951961Y1793611D01*
X1951846Y1793198D01*
X1951808Y1792733D01*
X1951846Y1792268D01*
X1951961Y1791855D01*
X1952114Y1791545D01*
X1952344Y1791286D01*
X1952651Y1791183D01*
X1952958Y1791286D01*
X1953188Y1791545D01*
X1953341Y1791855D01*
X1953456Y1792268D01*
X1953494Y1792733D01*
X1953456Y1793198D01*
X1953341Y1793611D01*
X1953188Y1793921D01*
X1952958Y1794180D01*
X1952651Y1794283D01*
G01X1955751D02*
X1955444Y1794180D01*
X1955214Y1793921D01*
X1955061Y1793611D01*
X1954946Y1793198D01*
X1954908Y1792733D01*
X1954946Y1792268D01*
X1955061Y1791855D01*
X1955214Y1791545D01*
X1955444Y1791286D01*
X1955751Y1791183D01*
X1956058Y1791286D01*
X1956288Y1791545D01*
X1956441Y1791855D01*
X1956556Y1792268D01*
X1956594Y1792733D01*
X1956556Y1793198D01*
X1956441Y1793611D01*
X1956288Y1793921D01*
X1956058Y1794180D01*
X1955751Y1794283D01*
G01X1958199Y1791545D02*
X1958468Y1791286D01*
X1958774Y1791183D01*
X1959081Y1791286D01*
X1959349Y1791596D01*
X1959541Y1792061D01*
X1959618Y1792526D01*
Y1793095D01*
X1959541Y1793560D01*
X1959349Y1793973D01*
X1959119Y1794180D01*
X1958851Y1794283D01*
X1958544Y1794180D01*
X1958314Y1793973D01*
X1958161Y1793663D01*
X1958084Y1793250D01*
X1958161Y1792888D01*
X1958353Y1792526D01*
X1958583Y1792320D01*
X1958851Y1792268D01*
X1959158Y1792371D01*
X1959388Y1792630D01*
X1959618Y1793095D01*
G01X1955886Y1800370D02*
Y1810370D01*
G01X1953386Y1800370D02*
X1955886D01*
G01Y1810370D02*
X1955336D01*
G01X1946436D02*
X1945336D01*
G01X1970862Y-29821D02*
X1965862D01*
G01X1967812Y-39821D02*
X1968912D01*
G01X1970155Y553207D02*
X1971765Y556307D01*
G01X1970155D02*
X1971765Y553207D01*
G01X1974060D02*
X1974328Y553259D01*
X1974635Y553414D01*
X1974827Y553672D01*
X1974903Y554034D01*
X1974827Y554395D01*
X1974597Y554705D01*
X1974252Y554860D01*
X1973868D01*
X1973638Y554964D01*
X1973447Y555222D01*
X1973370Y555584D01*
X1973485Y555945D01*
X1973753Y556204D01*
X1974060Y556307D01*
X1974367Y556204D01*
X1974635Y555945D01*
X1974750Y555584D01*
X1974673Y555222D01*
X1974482Y554964D01*
X1974252Y554860D01*
X1973868D01*
X1973523Y554705D01*
X1973293Y554395D01*
X1973217Y554034D01*
X1973293Y553672D01*
X1973485Y553414D01*
X1973792Y553259D01*
X1974060Y553207D01*
G01X1977160Y556307D02*
X1976853Y556204D01*
X1976623Y555945D01*
X1976470Y555635D01*
X1976355Y555222D01*
X1976317Y554757D01*
X1976355Y554292D01*
X1976470Y553879D01*
X1976623Y553569D01*
X1976853Y553310D01*
X1977160Y553207D01*
X1977467Y553310D01*
X1977697Y553569D01*
X1977850Y553879D01*
X1977965Y554292D01*
X1978003Y554757D01*
X1977965Y555222D01*
X1977850Y555635D01*
X1977697Y555945D01*
X1977467Y556204D01*
X1977160Y556307D01*
G01X1980260D02*
X1979953Y556204D01*
X1979723Y555945D01*
X1979570Y555635D01*
X1979455Y555222D01*
X1979417Y554757D01*
X1979455Y554292D01*
X1979570Y553879D01*
X1979723Y553569D01*
X1979953Y553310D01*
X1980260Y553207D01*
X1980567Y553310D01*
X1980797Y553569D01*
X1980950Y553879D01*
X1981065Y554292D01*
X1981103Y554757D01*
X1981065Y555222D01*
X1980950Y555635D01*
X1980797Y555945D01*
X1980567Y556204D01*
X1980260Y556307D01*
G01X1982517Y553827D02*
X1982747Y553465D01*
X1983053Y553259D01*
X1983398Y553207D01*
X1983705Y553259D01*
X1984012Y553517D01*
X1984203Y553827D01*
X1984242Y554137D01*
X1984165Y554499D01*
X1983897Y554757D01*
X1983628Y554860D01*
X1983283D01*
G01X1983628D02*
X1983858Y555015D01*
X1984050Y555274D01*
X1984127Y555584D01*
X1984050Y555894D01*
X1983858Y556152D01*
X1983513Y556307D01*
X1983168Y556255D01*
X1982823Y556049D01*
G01X1965862Y562379D02*
X1970862D01*
G01X1968912Y572379D02*
X1967812D01*
G01X1973664Y1214425D02*
X1975274Y1217525D01*
G01X1973664D02*
X1975274Y1214425D01*
G01X1976917Y1214787D02*
X1977186Y1214528D01*
X1977492Y1214425D01*
X1977799Y1214528D01*
X1978067Y1214838D01*
X1978259Y1215303D01*
X1978336Y1215768D01*
Y1216337D01*
X1978259Y1216802D01*
X1978067Y1217215D01*
X1977837Y1217422D01*
X1977569Y1217525D01*
X1977262Y1217422D01*
X1977032Y1217215D01*
X1976879Y1216905D01*
X1976802Y1216492D01*
X1976879Y1216130D01*
X1977071Y1215768D01*
X1977301Y1215562D01*
X1977569Y1215510D01*
X1977876Y1215613D01*
X1978106Y1215872D01*
X1978336Y1216337D01*
G01X1980669Y1217525D02*
X1980362Y1217422D01*
X1980132Y1217163D01*
X1979979Y1216853D01*
X1979864Y1216440D01*
X1979826Y1215975D01*
X1979864Y1215510D01*
X1979979Y1215097D01*
X1980132Y1214787D01*
X1980362Y1214528D01*
X1980669Y1214425D01*
X1980976Y1214528D01*
X1981206Y1214787D01*
X1981359Y1215097D01*
X1981474Y1215510D01*
X1981512Y1215975D01*
X1981474Y1216440D01*
X1981359Y1216853D01*
X1981206Y1217163D01*
X1980976Y1217422D01*
X1980669Y1217525D01*
G01X1983769D02*
X1983462Y1217422D01*
X1983232Y1217163D01*
X1983079Y1216853D01*
X1982964Y1216440D01*
X1982926Y1215975D01*
X1982964Y1215510D01*
X1983079Y1215097D01*
X1983232Y1214787D01*
X1983462Y1214528D01*
X1983769Y1214425D01*
X1984076Y1214528D01*
X1984306Y1214787D01*
X1984459Y1215097D01*
X1984574Y1215510D01*
X1984612Y1215975D01*
X1984574Y1216440D01*
X1984459Y1216853D01*
X1984306Y1217163D01*
X1984076Y1217422D01*
X1983769Y1217525D01*
G01X1986141Y1217008D02*
X1986371Y1217318D01*
X1986639Y1217473D01*
X1986946Y1217525D01*
X1987329Y1217422D01*
X1987597Y1217163D01*
X1987674Y1216853D01*
X1987636Y1216543D01*
X1987482Y1216285D01*
X1986716Y1215768D01*
X1986371Y1215407D01*
X1986141Y1214890D01*
X1986064Y1214425D01*
X1987674D01*
G01X1978362Y-29821D02*
X1975862D01*
G01X1977812Y-39821D02*
X1978362D01*
G01D02*
Y-29821D01*
G01X1975862Y562379D02*
X1978362D01*
G01D02*
Y572379D01*
G01X1981982Y582389D02*
X1979482D01*
G01D02*
Y572389D01*
G01X1991982Y582389D02*
X1986982D01*
G01X1979482Y572389D02*
X1980032D01*
G01X1988932D02*
X1990032D01*
G01X1978362Y572379D02*
X1977812D01*
G01X1982271Y587819D02*
X1983881Y590919D01*
G01X1982271D02*
X1983881Y587819D01*
G01X1985524Y588181D02*
X1985793Y587922D01*
X1986099Y587819D01*
X1986406Y587922D01*
X1986674Y588232D01*
X1986866Y588697D01*
X1986943Y589162D01*
Y589731D01*
X1986866Y590196D01*
X1986674Y590609D01*
X1986444Y590816D01*
X1986176Y590919D01*
X1985869Y590816D01*
X1985639Y590609D01*
X1985486Y590299D01*
X1985409Y589886D01*
X1985486Y589524D01*
X1985678Y589162D01*
X1985908Y588956D01*
X1986176Y588904D01*
X1986483Y589007D01*
X1986713Y589266D01*
X1986943Y589731D01*
G01X1989681Y1165539D02*
X1991291Y1168639D01*
G01X1989681D02*
X1991291Y1165539D01*
G01X1992743Y1166159D02*
X1992973Y1165797D01*
X1993279Y1165591D01*
X1993624Y1165539D01*
X1993931Y1165591D01*
X1994238Y1165849D01*
X1994429Y1166159D01*
X1994468Y1166469D01*
X1994391Y1166831D01*
X1994123Y1167089D01*
X1993854Y1167192D01*
X1993509D01*
G01X1993854D02*
X1994084Y1167347D01*
X1994276Y1167606D01*
X1994353Y1167916D01*
X1994276Y1168226D01*
X1994084Y1168484D01*
X1993739Y1168639D01*
X1993394Y1168587D01*
X1993049Y1168381D01*
G01X1986982Y1174589D02*
X1991982D01*
G01X1979482D02*
X1981982D01*
G01X1979482Y1184589D02*
Y1174589D01*
G01X1990032Y1184589D02*
X1988932D01*
G01X1980032D02*
X1979482D01*
G01X1977856Y1198350D02*
X1978406D01*
G01X1977856Y1208350D02*
Y1198350D01*
G01X1980356Y1208350D02*
X1977856D01*
G01X1987306Y1198350D02*
X1988406D01*
G01X1990356Y1208350D02*
X1985356D01*
G01X1987826Y1791213D02*
X1989436Y1794313D01*
G01X1987826D02*
X1989436Y1791213D01*
G01X1991079Y1791575D02*
X1991348Y1791316D01*
X1991654Y1791213D01*
X1991961Y1791316D01*
X1992229Y1791626D01*
X1992421Y1792091D01*
X1992498Y1792556D01*
Y1793125D01*
X1992421Y1793590D01*
X1992229Y1794003D01*
X1991999Y1794210D01*
X1991731Y1794313D01*
X1991424Y1794210D01*
X1991194Y1794003D01*
X1991041Y1793693D01*
X1990964Y1793280D01*
X1991041Y1792918D01*
X1991233Y1792556D01*
X1991463Y1792350D01*
X1991731Y1792298D01*
X1992038Y1792401D01*
X1992268Y1792660D01*
X1992498Y1793125D01*
G01X1994831Y1794313D02*
X1994524Y1794210D01*
X1994294Y1793951D01*
X1994141Y1793641D01*
X1994026Y1793228D01*
X1993988Y1792763D01*
X1994026Y1792298D01*
X1994141Y1791885D01*
X1994294Y1791575D01*
X1994524Y1791316D01*
X1994831Y1791213D01*
X1995138Y1791316D01*
X1995368Y1791575D01*
X1995521Y1791885D01*
X1995636Y1792298D01*
X1995674Y1792763D01*
X1995636Y1793228D01*
X1995521Y1793641D01*
X1995368Y1793951D01*
X1995138Y1794210D01*
X1994831Y1794313D01*
G01X1997931D02*
X1997624Y1794210D01*
X1997394Y1793951D01*
X1997241Y1793641D01*
X1997126Y1793228D01*
X1997088Y1792763D01*
X1997126Y1792298D01*
X1997241Y1791885D01*
X1997394Y1791575D01*
X1997624Y1791316D01*
X1997931Y1791213D01*
X1998238Y1791316D01*
X1998468Y1791575D01*
X1998621Y1791885D01*
X1998736Y1792298D01*
X1998774Y1792763D01*
X1998736Y1793228D01*
X1998621Y1793641D01*
X1998468Y1793951D01*
X1998238Y1794210D01*
X1997931Y1794313D01*
G01X2001031Y1791213D02*
X2001299Y1791265D01*
X2001606Y1791420D01*
X2001798Y1791678D01*
X2001874Y1792040D01*
X2001798Y1792401D01*
X2001568Y1792711D01*
X2001223Y1792866D01*
X2000839D01*
X2000609Y1792970D01*
X2000418Y1793228D01*
X2000341Y1793590D01*
X2000456Y1793951D01*
X2000724Y1794210D01*
X2001031Y1794313D01*
X2001338Y1794210D01*
X2001606Y1793951D01*
X2001721Y1793590D01*
X2001644Y1793228D01*
X2001453Y1792970D01*
X2001223Y1792866D01*
X2000839D01*
X2000494Y1792711D01*
X2000264Y1792401D01*
X2000188Y1792040D01*
X2000264Y1791678D01*
X2000456Y1791420D01*
X2000763Y1791265D01*
X2001031Y1791213D01*
G01X1977856Y1810550D02*
Y1800550D01*
G01X1985356D02*
X1990356D01*
G01X1977856D02*
X1980356D01*
G01X1988406Y1810550D02*
X1987306D01*
G01X1978406D02*
X1977856D01*
G01X2002952Y-29811D02*
X2000452D01*
G01D02*
Y-39811D01*
G01D02*
X2001002D01*
G01X1996825Y-23979D02*
X1998435Y-20879D01*
G01X1996825D02*
X1998435Y-23979D01*
G01X2000730D02*
X2000998Y-23927D01*
X2001305Y-23772D01*
X2001497Y-23514D01*
X2001573Y-23152D01*
X2001497Y-22791D01*
X2001267Y-22481D01*
X2000922Y-22326D01*
X2000538D01*
X2000308Y-22222D01*
X2000117Y-21964D01*
X2000040Y-21602D01*
X2000155Y-21241D01*
X2000423Y-20982D01*
X2000730Y-20879D01*
X2001037Y-20982D01*
X2001305Y-21241D01*
X2001420Y-21602D01*
X2001343Y-21964D01*
X2001152Y-22222D01*
X2000922Y-22326D01*
X2000538D01*
X2000193Y-22481D01*
X1999963Y-22791D01*
X1999887Y-23152D01*
X1999963Y-23514D01*
X2000155Y-23772D01*
X2000462Y-23927D01*
X2000730Y-23979D01*
G01X2003830Y-20879D02*
X2003523Y-20982D01*
X2003293Y-21241D01*
X2003140Y-21551D01*
X2003025Y-21964D01*
X2002987Y-22429D01*
X2003025Y-22894D01*
X2003140Y-23307D01*
X2003293Y-23617D01*
X2003523Y-23876D01*
X2003830Y-23979D01*
X2004137Y-23876D01*
X2004367Y-23617D01*
X2004520Y-23307D01*
X2004635Y-22894D01*
X2004673Y-22429D01*
X2004635Y-21964D01*
X2004520Y-21551D01*
X2004367Y-21241D01*
X2004137Y-20982D01*
X2003830Y-20879D01*
G01X2006930D02*
X2006623Y-20982D01*
X2006393Y-21241D01*
X2006240Y-21551D01*
X2006125Y-21964D01*
X2006087Y-22429D01*
X2006125Y-22894D01*
X2006240Y-23307D01*
X2006393Y-23617D01*
X2006623Y-23876D01*
X2006930Y-23979D01*
X2007237Y-23876D01*
X2007467Y-23617D01*
X2007620Y-23307D01*
X2007735Y-22894D01*
X2007773Y-22429D01*
X2007735Y-21964D01*
X2007620Y-21551D01*
X2007467Y-21241D01*
X2007237Y-20982D01*
X2006930Y-20879D01*
G01X2009302Y-21396D02*
X2009532Y-21086D01*
X2009800Y-20931D01*
X2010107Y-20879D01*
X2010490Y-20982D01*
X2010758Y-21241D01*
X2010835Y-21551D01*
X2010797Y-21861D01*
X2010643Y-22119D01*
X2009877Y-22636D01*
X2009532Y-22997D01*
X2009302Y-23514D01*
X2009225Y-23979D01*
X2010835D01*
G01X2000452Y562389D02*
X2002952D01*
G01X2000452Y572389D02*
Y562389D01*
G01X1999482Y572389D02*
Y582389D01*
G01D02*
X1996982D01*
G01X1998932Y572389D02*
X1999482D01*
G01X2001002D02*
X2000452D01*
G01X1996982Y1174589D02*
X1999482D01*
G01D02*
Y1184589D01*
G01D02*
X1998932D01*
G01X1997856Y1198350D02*
Y1208350D01*
G01X1997306Y1198350D02*
X1997856D01*
G01Y1208350D02*
X1995356D01*
G01X1997856Y1800550D02*
Y1810550D01*
G01X1995356Y1800550D02*
X1997856D01*
G01Y1810550D02*
X1997306D01*
G01X2020452Y-29811D02*
X2017952D01*
G01X2012952D02*
X2007952D01*
G01X2009902Y-39811D02*
X2011002D01*
G01X2012665Y553117D02*
X2014275Y556217D01*
G01X2012665D02*
X2014275Y553117D01*
G01X2016570D02*
X2016838Y553169D01*
X2017145Y553324D01*
X2017337Y553582D01*
X2017413Y553944D01*
X2017337Y554305D01*
X2017107Y554615D01*
X2016762Y554770D01*
X2016378D01*
X2016148Y554874D01*
X2015957Y555132D01*
X2015880Y555494D01*
X2015995Y555855D01*
X2016263Y556114D01*
X2016570Y556217D01*
X2016877Y556114D01*
X2017145Y555855D01*
X2017260Y555494D01*
X2017183Y555132D01*
X2016992Y554874D01*
X2016762Y554770D01*
X2016378D01*
X2016033Y554615D01*
X2015803Y554305D01*
X2015727Y553944D01*
X2015803Y553582D01*
X2015995Y553324D01*
X2016302Y553169D01*
X2016570Y553117D01*
G01X2019670Y556217D02*
X2019363Y556114D01*
X2019133Y555855D01*
X2018980Y555545D01*
X2018865Y555132D01*
X2018827Y554667D01*
X2018865Y554202D01*
X2018980Y553789D01*
X2019133Y553479D01*
X2019363Y553220D01*
X2019670Y553117D01*
X2019977Y553220D01*
X2020207Y553479D01*
X2020360Y553789D01*
X2020475Y554202D01*
X2020513Y554667D01*
X2020475Y555132D01*
X2020360Y555545D01*
X2020207Y555855D01*
X2019977Y556114D01*
X2019670Y556217D01*
G01X2022770D02*
X2022463Y556114D01*
X2022233Y555855D01*
X2022080Y555545D01*
X2021965Y555132D01*
X2021927Y554667D01*
X2021965Y554202D01*
X2022080Y553789D01*
X2022233Y553479D01*
X2022463Y553220D01*
X2022770Y553117D01*
X2023077Y553220D01*
X2023307Y553479D01*
X2023460Y553789D01*
X2023575Y554202D01*
X2023613Y554667D01*
X2023575Y555132D01*
X2023460Y555545D01*
X2023307Y555855D01*
X2023077Y556114D01*
X2022770Y556217D01*
G01X2025870Y553117D02*
X2026138Y553169D01*
X2026445Y553324D01*
X2026637Y553582D01*
X2026713Y553944D01*
X2026637Y554305D01*
X2026407Y554615D01*
X2026062Y554770D01*
X2025678D01*
X2025448Y554874D01*
X2025257Y555132D01*
X2025180Y555494D01*
X2025295Y555855D01*
X2025563Y556114D01*
X2025870Y556217D01*
X2026177Y556114D01*
X2026445Y555855D01*
X2026560Y555494D01*
X2026483Y555132D01*
X2026292Y554874D01*
X2026062Y554770D01*
X2025678D01*
X2025333Y554615D01*
X2025103Y554305D01*
X2025027Y553944D01*
X2025103Y553582D01*
X2025295Y553324D01*
X2025602Y553169D01*
X2025870Y553117D01*
G01X2007952Y562389D02*
X2012952D01*
G01X2017952D02*
X2020452D01*
G01X2011002Y572389D02*
X2009902D01*
G01X2019902Y-39811D02*
X2020452D01*
G01D02*
Y-29811D01*
G01Y562389D02*
Y572389D01*
G01X2023952Y582569D02*
X2021452D01*
G01D02*
Y572569D01*
G01X2033952Y582569D02*
X2028952D01*
G01X2021452Y572569D02*
X2022002D01*
G01X2030902D02*
X2032002D01*
G01X2020452Y572389D02*
X2019902D01*
G01X2023975Y588667D02*
X2025585Y591767D01*
G01X2023975D02*
X2025585Y588667D01*
G01X2027152Y591250D02*
X2027382Y591560D01*
X2027650Y591715D01*
X2027957Y591767D01*
X2028340Y591664D01*
X2028608Y591405D01*
X2028685Y591095D01*
X2028647Y590785D01*
X2028493Y590527D01*
X2027727Y590010D01*
X2027382Y589649D01*
X2027152Y589132D01*
X2027075Y588667D01*
X2028685D01*
G01X2031981Y1165539D02*
X2033591Y1168639D01*
G01X2031981D02*
X2033591Y1165539D01*
G01X2035886D02*
X2036154Y1165591D01*
X2036461Y1165746D01*
X2036653Y1166004D01*
X2036729Y1166366D01*
X2036653Y1166727D01*
X2036423Y1167037D01*
X2036078Y1167192D01*
X2035694D01*
X2035464Y1167296D01*
X2035273Y1167554D01*
X2035196Y1167916D01*
X2035311Y1168277D01*
X2035579Y1168536D01*
X2035886Y1168639D01*
X2036193Y1168536D01*
X2036461Y1168277D01*
X2036576Y1167916D01*
X2036499Y1167554D01*
X2036308Y1167296D01*
X2036078Y1167192D01*
X2035694D01*
X2035349Y1167037D01*
X2035119Y1166727D01*
X2035043Y1166366D01*
X2035119Y1166004D01*
X2035311Y1165746D01*
X2035618Y1165591D01*
X2035886Y1165539D01*
G01X2021452Y1174769D02*
X2023952D01*
G01X2028952D02*
X2033952D01*
G01X2021452Y1184769D02*
Y1174769D01*
G01X2032002Y1184769D02*
X2030902D01*
G01X2022002D02*
X2021452D01*
G01X2044919Y-29669D02*
X2042419D01*
G01D02*
Y-39669D01*
G01D02*
X2042969D01*
G01X2036183Y-23512D02*
X2037793Y-20412D01*
G01X2036183D02*
X2037793Y-23512D01*
G01X2040088D02*
X2040356Y-23460D01*
X2040663Y-23305D01*
X2040855Y-23047D01*
X2040931Y-22685D01*
X2040855Y-22324D01*
X2040625Y-22014D01*
X2040280Y-21859D01*
X2039896D01*
X2039666Y-21755D01*
X2039475Y-21497D01*
X2039398Y-21135D01*
X2039513Y-20774D01*
X2039781Y-20515D01*
X2040088Y-20412D01*
X2040395Y-20515D01*
X2040663Y-20774D01*
X2040778Y-21135D01*
X2040701Y-21497D01*
X2040510Y-21755D01*
X2040280Y-21859D01*
X2039896D01*
X2039551Y-22014D01*
X2039321Y-22324D01*
X2039245Y-22685D01*
X2039321Y-23047D01*
X2039513Y-23305D01*
X2039820Y-23460D01*
X2040088Y-23512D01*
G01X2043188Y-20412D02*
X2042881Y-20515D01*
X2042651Y-20774D01*
X2042498Y-21084D01*
X2042383Y-21497D01*
X2042345Y-21962D01*
X2042383Y-22427D01*
X2042498Y-22840D01*
X2042651Y-23150D01*
X2042881Y-23409D01*
X2043188Y-23512D01*
X2043495Y-23409D01*
X2043725Y-23150D01*
X2043878Y-22840D01*
X2043993Y-22427D01*
X2044031Y-21962D01*
X2043993Y-21497D01*
X2043878Y-21084D01*
X2043725Y-20774D01*
X2043495Y-20515D01*
X2043188Y-20412D01*
G01X2046288D02*
X2045981Y-20515D01*
X2045751Y-20774D01*
X2045598Y-21084D01*
X2045483Y-21497D01*
X2045445Y-21962D01*
X2045483Y-22427D01*
X2045598Y-22840D01*
X2045751Y-23150D01*
X2045981Y-23409D01*
X2046288Y-23512D01*
X2046595Y-23409D01*
X2046825Y-23150D01*
X2046978Y-22840D01*
X2047093Y-22427D01*
X2047131Y-21962D01*
X2047093Y-21497D01*
X2046978Y-21084D01*
X2046825Y-20774D01*
X2046595Y-20515D01*
X2046288Y-20412D01*
G01X2049388Y-23512D02*
Y-20412D01*
X2048928Y-21032D01*
G01Y-23512D02*
X2049848D01*
G01X2042419Y562531D02*
X2044919D01*
G01X2042419Y572531D02*
Y562531D01*
G01X2041452Y572569D02*
Y582569D01*
G01D02*
X2038952D01*
G01X2040902Y572569D02*
X2041452D01*
G01X2042969Y572531D02*
X2042419D01*
G01X2038952Y1174769D02*
X2041452D01*
G01D02*
Y1184769D01*
G01D02*
X2040902D01*
G01X2044957Y1768579D02*
Y1771679D01*
X2045877D01*
X2046184Y1771524D01*
X2046414Y1771162D01*
X2046491Y1770749D01*
X2046414Y1770336D01*
X2046222Y1770026D01*
X2045877Y1769871D01*
X2044957D01*
G01X2048134Y1768476D02*
X2049514Y1771679D01*
G01X2051042Y1768579D02*
Y1771679D01*
X2052806Y1768579D01*
Y1771679D01*
G01X2055024Y1768476D02*
X2054947Y1768527D01*
Y1768631D01*
X2055024Y1768682D01*
X2055101Y1768631D01*
Y1768527D01*
X2055024Y1768476D01*
G01Y1769871D02*
X2054947Y1769922D01*
Y1770026D01*
X2055024Y1770077D01*
X2055101Y1770026D01*
Y1769922D01*
X2055024Y1769871D01*
G01X2057281Y1768579D02*
Y1771679D01*
X2058047D01*
X2058354Y1771524D01*
X2058584Y1771317D01*
X2058776Y1771007D01*
X2058929Y1770646D01*
X2058967Y1770129D01*
X2058929Y1769612D01*
X2058776Y1769251D01*
X2058584Y1768941D01*
X2058354Y1768734D01*
X2058047Y1768579D01*
X2057281D01*
G01X2060266D02*
X2061224Y1771679D01*
X2062182Y1768579D01*
G01X2061837Y1769664D02*
X2060611D01*
G01X2063596Y1768579D02*
Y1771679D01*
X2065052D01*
G01X2064516Y1770181D02*
X2063596D01*
G01X2067424Y1771679D02*
X2067117Y1771576D01*
X2066887Y1771317D01*
X2066734Y1771007D01*
X2066619Y1770594D01*
X2066581Y1770129D01*
X2066619Y1769664D01*
X2066734Y1769251D01*
X2066887Y1768941D01*
X2067117Y1768682D01*
X2067424Y1768579D01*
X2067731Y1768682D01*
X2067961Y1768941D01*
X2068114Y1769251D01*
X2068229Y1769664D01*
X2068267Y1770129D01*
X2068229Y1770594D01*
X2068114Y1771007D01*
X2067961Y1771317D01*
X2067731Y1771576D01*
X2067424Y1771679D01*
G01X2070524D02*
Y1768579D01*
G01X2069642Y1771679D02*
X2071406D01*
G01X2072627Y1768579D02*
Y1771679D01*
X2073624Y1769096D01*
X2074621Y1771679D01*
Y1768579D01*
G01X2077031Y1770232D02*
X2077184Y1770387D01*
X2077299Y1770646D01*
X2077376Y1771007D01*
X2077299Y1771317D01*
X2077146Y1771524D01*
X2076877Y1771679D01*
X2075842D01*
Y1768579D01*
X2077107D01*
X2077376Y1768786D01*
X2077529Y1769096D01*
X2077606Y1769457D01*
X2077529Y1769819D01*
X2077299Y1770129D01*
X2077031Y1770232D01*
X2075842D01*
G01X2078981Y1769199D02*
X2079211Y1768837D01*
X2079517Y1768631D01*
X2079862Y1768579D01*
X2080169Y1768631D01*
X2080476Y1768889D01*
X2080667Y1769199D01*
X2080706Y1769509D01*
X2080629Y1769871D01*
X2080361Y1770129D01*
X2080092Y1770232D01*
X2079747D01*
G01X2080092D02*
X2080322Y1770387D01*
X2080514Y1770646D01*
X2080591Y1770956D01*
X2080514Y1771266D01*
X2080322Y1771524D01*
X2079977Y1771679D01*
X2079632Y1771627D01*
X2079287Y1771421D01*
G01X2082464Y1771679D02*
X2083384D01*
G01X2082924D02*
Y1768579D01*
G01X2082464D02*
X2083384D01*
G01X2086867Y1771421D02*
X2086637Y1771576D01*
X2086369Y1771679D01*
X2086062D01*
X2085717Y1771524D01*
X2085449Y1771266D01*
X2085257Y1770956D01*
X2085104Y1770439D01*
X2085066Y1769974D01*
X2085142Y1769509D01*
X2085257Y1769199D01*
X2085487Y1768889D01*
X2085756Y1768682D01*
X2086024Y1768579D01*
X2086292D01*
X2086561Y1768682D01*
X2086791Y1768837D01*
X2086982Y1769044D01*
G01X2089124Y1771679D02*
X2088817Y1771576D01*
X2088587Y1771317D01*
X2088434Y1771007D01*
X2088319Y1770594D01*
X2088281Y1770129D01*
X2088319Y1769664D01*
X2088434Y1769251D01*
X2088587Y1768941D01*
X2088817Y1768682D01*
X2089124Y1768579D01*
X2089431Y1768682D01*
X2089661Y1768941D01*
X2089814Y1769251D01*
X2089929Y1769664D01*
X2089967Y1770129D01*
X2089929Y1770594D01*
X2089814Y1771007D01*
X2089661Y1771317D01*
X2089431Y1771576D01*
X2089124Y1771679D01*
G01X2062419Y-29669D02*
X2059919D01*
G01X2054919D02*
X2049919D01*
G01X2061869Y-39669D02*
X2062419D01*
G01D02*
Y-29669D01*
G01X2051869Y-39669D02*
X2052969D01*
G01X2055807Y553150D02*
X2057417Y556250D01*
G01X2055807D02*
X2057417Y553150D01*
G01X2059712D02*
X2059980Y553202D01*
X2060287Y553357D01*
X2060479Y553615D01*
X2060555Y553977D01*
X2060479Y554338D01*
X2060249Y554648D01*
X2059904Y554803D01*
X2059520D01*
X2059290Y554907D01*
X2059099Y555165D01*
X2059022Y555527D01*
X2059137Y555888D01*
X2059405Y556147D01*
X2059712Y556250D01*
X2060019Y556147D01*
X2060287Y555888D01*
X2060402Y555527D01*
X2060325Y555165D01*
X2060134Y554907D01*
X2059904Y554803D01*
X2059520D01*
X2059175Y554648D01*
X2058945Y554338D01*
X2058869Y553977D01*
X2058945Y553615D01*
X2059137Y553357D01*
X2059444Y553202D01*
X2059712Y553150D01*
G01X2062812Y556250D02*
X2062505Y556147D01*
X2062275Y555888D01*
X2062122Y555578D01*
X2062007Y555165D01*
X2061969Y554700D01*
X2062007Y554235D01*
X2062122Y553822D01*
X2062275Y553512D01*
X2062505Y553253D01*
X2062812Y553150D01*
X2063119Y553253D01*
X2063349Y553512D01*
X2063502Y553822D01*
X2063617Y554235D01*
X2063655Y554700D01*
X2063617Y555165D01*
X2063502Y555578D01*
X2063349Y555888D01*
X2063119Y556147D01*
X2062812Y556250D01*
G01X2065912D02*
X2065605Y556147D01*
X2065375Y555888D01*
X2065222Y555578D01*
X2065107Y555165D01*
X2065069Y554700D01*
X2065107Y554235D01*
X2065222Y553822D01*
X2065375Y553512D01*
X2065605Y553253D01*
X2065912Y553150D01*
X2066219Y553253D01*
X2066449Y553512D01*
X2066602Y553822D01*
X2066717Y554235D01*
X2066755Y554700D01*
X2066717Y555165D01*
X2066602Y555578D01*
X2066449Y555888D01*
X2066219Y556147D01*
X2065912Y556250D01*
G01X2068935Y553150D02*
X2069012Y553822D01*
X2069127Y554390D01*
X2069280Y554907D01*
X2069472Y555475D01*
X2069779Y556250D01*
X2068245D01*
G01X2049919Y562531D02*
X2054919D01*
G01X2059919D02*
X2062419D01*
G01D02*
Y572531D01*
G01X2066039Y582541D02*
X2063539D01*
G01D02*
Y572541D01*
G01D02*
X2064089D01*
G01X2052969Y572531D02*
X2051869D01*
G01X2062419D02*
X2061869D01*
G01X2063539Y1174741D02*
X2066039D01*
G01X2063539Y1184741D02*
Y1174741D01*
G01X2064089Y1184741D02*
X2063539D01*
G01X2076039Y582541D02*
X2071039D01*
G01X2072989Y572541D02*
X2074089D01*
G01X2065117Y588590D02*
X2066727Y591690D01*
G01X2065117D02*
X2066727Y588590D01*
G01X2068945D02*
X2069022Y589262D01*
X2069137Y589830D01*
X2069290Y590347D01*
X2069482Y590915D01*
X2069789Y591690D01*
X2068255D01*
G01X2071039Y1174741D02*
X2076039D01*
G01X2074089Y1184741D02*
X2072989D01*
G01X2083539Y572541D02*
Y582541D01*
G01D02*
X2081039D01*
G01X2082989Y572541D02*
X2083539D01*
G01X2080001Y1166139D02*
X2081611Y1169239D01*
G01X2080001D02*
X2081611Y1166139D01*
G01X2083906D02*
Y1169239D01*
X2083446Y1168619D01*
G01Y1166139D02*
X2084366D01*
G01X2081039Y1174741D02*
X2083539D01*
G01D02*
Y1184741D01*
G01D02*
X2082989D01*
G01X2095383Y9186D02*
X2098483D01*
Y8266D01*
X2098328Y7959D01*
X2097966Y7729D01*
X2097553Y7652D01*
X2097140Y7729D01*
X2096830Y7921D01*
X2096675Y8266D01*
Y9186D01*
G01X2095280Y6009D02*
X2098483Y4629D01*
G01X2095383Y3101D02*
X2098483D01*
X2095383Y1337D01*
X2098483D01*
G01X2095280Y-881D02*
X2095331Y-804D01*
X2095435D01*
X2095486Y-881D01*
X2095435Y-958D01*
X2095331D01*
X2095280Y-881D01*
G01X2096675D02*
X2096726Y-804D01*
X2096830D01*
X2096881Y-881D01*
X2096830Y-958D01*
X2096726D01*
X2096675Y-881D01*
G01X2095383Y-3138D02*
X2098483D01*
Y-3904D01*
X2098328Y-4211D01*
X2098121Y-4441D01*
X2097811Y-4633D01*
X2097450Y-4786D01*
X2096933Y-4824D01*
X2096416Y-4786D01*
X2096055Y-4633D01*
X2095745Y-4441D01*
X2095538Y-4211D01*
X2095383Y-3904D01*
Y-3138D01*
G01Y-6123D02*
X2098483Y-7081D01*
X2095383Y-8039D01*
G01X2096468Y-7694D02*
Y-6468D01*
G01X2095383Y-9453D02*
X2098483D01*
Y-10909D01*
G01X2096985Y-10373D02*
Y-9453D01*
G01X2098483Y-13281D02*
X2098380Y-12974D01*
X2098121Y-12744D01*
X2097811Y-12591D01*
X2097398Y-12476D01*
X2096933Y-12438D01*
X2096468Y-12476D01*
X2096055Y-12591D01*
X2095745Y-12744D01*
X2095486Y-12974D01*
X2095383Y-13281D01*
X2095486Y-13588D01*
X2095745Y-13818D01*
X2096055Y-13971D01*
X2096468Y-14086D01*
X2096933Y-14124D01*
X2097398Y-14086D01*
X2097811Y-13971D01*
X2098121Y-13818D01*
X2098380Y-13588D01*
X2098483Y-13281D01*
G01Y-16381D02*
X2095383D01*
G01X2098483Y-15499D02*
Y-17263D01*
G01X2095383Y-18484D02*
X2098483D01*
X2095900Y-19481D01*
X2098483Y-20478D01*
X2095383D01*
G01X2097036Y-22888D02*
X2097191Y-23041D01*
X2097450Y-23156D01*
X2097811Y-23233D01*
X2098121Y-23156D01*
X2098328Y-23003D01*
X2098483Y-22734D01*
Y-21699D01*
X2095383D01*
Y-22964D01*
X2095590Y-23233D01*
X2095900Y-23386D01*
X2096261Y-23463D01*
X2096623Y-23386D01*
X2096933Y-23156D01*
X2097036Y-22888D01*
Y-21699D01*
G01X2096003Y-24838D02*
X2095641Y-25068D01*
X2095435Y-25374D01*
X2095383Y-25719D01*
X2095435Y-26026D01*
X2095693Y-26333D01*
X2096003Y-26524D01*
X2096313Y-26563D01*
X2096675Y-26486D01*
X2096933Y-26218D01*
X2097036Y-25949D01*
Y-25604D01*
G01Y-25949D02*
X2097191Y-26179D01*
X2097450Y-26371D01*
X2097760Y-26448D01*
X2098070Y-26371D01*
X2098328Y-26179D01*
X2098483Y-25834D01*
X2098431Y-25489D01*
X2098225Y-25144D01*
G01X2098483Y-28321D02*
Y-29241D01*
G01Y-28781D02*
X2095383D01*
G01Y-28321D02*
Y-29241D01*
G01X2098225Y-32724D02*
X2098380Y-32494D01*
X2098483Y-32226D01*
Y-31919D01*
X2098328Y-31574D01*
X2098070Y-31306D01*
X2097760Y-31114D01*
X2097243Y-30961D01*
X2096778Y-30923D01*
X2096313Y-30999D01*
X2096003Y-31114D01*
X2095693Y-31344D01*
X2095486Y-31613D01*
X2095383Y-31881D01*
Y-32149D01*
X2095486Y-32418D01*
X2095641Y-32648D01*
X2095848Y-32839D01*
G01X2098483Y-34981D02*
X2098380Y-34674D01*
X2098121Y-34444D01*
X2097811Y-34291D01*
X2097398Y-34176D01*
X2096933Y-34138D01*
X2096468Y-34176D01*
X2096055Y-34291D01*
X2095745Y-34444D01*
X2095486Y-34674D01*
X2095383Y-34981D01*
X2095486Y-35288D01*
X2095745Y-35518D01*
X2096055Y-35671D01*
X2096468Y-35786D01*
X2096933Y-35824D01*
X2097398Y-35786D01*
X2097811Y-35671D01*
X2098121Y-35518D01*
X2098380Y-35288D01*
X2098483Y-34981D01*
M02*
